G04 ================== begin FILE IDENTIFICATION RECORD ==================*
G04 Layout Name:  9324_DA0F0TMBIJ0_F0T_Motherboard_J_v01_20230324_0910.brd*
G04 Film Name:    bot*
G04 File Format:  Gerber RS274X*
G04 File Origin:  Cadence Allegro 17.2-S081*
G04 Origin Date:  Sat Mar 25 08:44:50 2023*
G04 *
G04 Layer:  PIN/SPECIAL_DRILL*
G04 Layer:  DRAWING FORMAT/TITLE_BLOCK_A*
G04 Layer:  DRAWING FORMAT/TITLE_BLOCK*
G04 Layer:  VIA CLASS/BOTTOM*
G04 Layer:  PIN/BOTTOM*
G04 Layer:  MANUFACTURING/PHOTOPLOT_OUTLINE*
G04 Layer:  ETCH/BOTTOM*
G04 Layer:  DRAWING FORMAT/TITLE_DATA_BOT*
G04 *
G04 Offset:    (0.00 0.00)*
G04 Mirror:    No*
G04 Mode:      Positive*
G04 Rotation:  0*
G04 FullContactRelief:  No*
G04 UndefLineWidth:     6.00*
G04 ================== end FILE IDENTIFICATION RECORD ====================*
%FSLAX25Y25*MOIN*%
%IR0*IPPOS*OFA0.00000B0.00000*MIA0B0*SFA1.00000B1.00000*%
%ADD20O,.111X.062*%
%ADD66R,.02X.005*%
%ADD67R,.005X.02*%
%AMMACRO105*
21,1,.028,.032,0.0,0.0,135.*%
%ADD105MACRO105*%
%ADD54R,.126X.06*%
%ADD11C,.02*%
%ADD83C,.03*%
%ADD39R,.111X.095*%
%ADD95R,.13X.095*%
%ADD90O,.137X.064*%
%ADD46R,.095X.111*%
%ADD34C,.04*%
%ADD33R,.007X.032*%
%ADD17R,.024X.007*%
%ADD76C,.041*%
%ADD42C,.06*%
%ADD62C,.061*%
%ADD45C,.016*%
%AMMACRO64*
4,1,8,-.005,.037,
-.005,-.005,
-.014,-.005,
-.014,-.037,
.014,-.037,
.014,-.005,
.005,-.005,
.005,.037,
-.005,.037,
0.0*
%
%ADD64MACRO64*%
%ADD55C,.017*%
%ADD37C,.062*%
%ADD29C,.044*%
%ADD12C,.026*%
%ADD87C,.036*%
%ADD15C,.018*%
%ADD71C,.046*%
%ADD35C,.028*%
%ADD28C,.064*%
%ADD70C,.065*%
%ADD49C,.03017*%
%ADD14C,.039*%
%ADD113C,.085*%
%ADD43R,.06X.06*%
%ADD40C,.0193*%
%ADD25C,.0157*%
%ADD63R,.061X.061*%
%AMMACRO77*
4,1,8,.0425,-.078,
-.0425,-.078,
-.0425,.078,
.0425,.078,
.0425,.0236,
.0145,.0236,
.0145,-.0236,
.0425,-.0236,
.0425,-.078,
0.0*
%
%ADD77MACRO77*%
%ADD38R,.062X.062*%
%ADD30C,.0177*%
%ADD112C,.0395*%
%ADD97R,.064X.064*%
%ADD51R,.03017X.03017*%
%ADD50C,.02187*%
%ADD111C,.0785*%
%AMMACRO100*
4,1,28,-.00492,.00566,
-.00659,.00733,
-.00269,.01122,
-.002174,.011659,
-.001588,.011998,
-.000951,.01223,
-.000284,.012348,
.000393,.012348,
.001061,.012231,
.001697,.012,
.002284,.011661,
.002803,.011226,
.00284,.01119,
.01119,.00284,
.011631,.002326,
.011978,.001744,
.012217,.00111,
.012343,.000444,
.012352,-.000233,
.012243,-.000902,
.012019,-.001541,
.011688,-.002132,
.011259,-.002656,
.01122,-.00269,
.00733,-.00659,
.00566,-.00492,
-.00172,-.0123,
-.0123,-.00172,
-.00492,.00566,
0.0*
%
%ADD100MACRO100*%
%ADD86C,.06574*%
%ADD48C,.03568*%
%AMMACRO32*
4,1,28,-.00748,.00052,
-.00984,.00052,
-.00984,.00603,
-.009782,.006705,
-.009607,.007359,
-.009321,.007974,
-.008933,.008529,
-.008455,.009009,
-.0079,.009398,
-.007286,.009685,
-.006632,.009861,
-.005957,.00992,
-.00591,.00992,
.00591,.00992,
.006585,.009869,
.007242,.009701,
.007859,.009421,
.008418,.009039,
.008903,.008565,
.009297,.008015,
.009591,.007404,
.009773,.006751,
.00984,.006077,
.00984,.00603,
.00984,.00052,
.00748,.00052,
.00748,-.00991,
-.00748,-.00991,
-.00748,.00052,
0.0*
%
%ADD32MACRO32*%
%AMMACRO19*
4,1,28,.00052,.00748,
.00052,.00984,
.00603,.00984,
.006705,.009782,
.007359,.009607,
.007974,.009321,
.008529,.008933,
.009009,.008455,
.009398,.0079,
.009685,.007286,
.009861,.006632,
.00992,.005957,
.00992,.00591,
.00992,-.00591,
.009869,-.006585,
.009701,-.007242,
.009421,-.007859,
.009039,-.008418,
.008565,-.008903,
.008015,-.009297,
.007404,-.009591,
.006751,-.009773,
.006077,-.00984,
.00603,-.00984,
.00052,-.00984,
.00052,-.00748,
-.00991,-.00748,
-.00991,.00748,
.00052,.00748,
0.0*
%
%ADD19MACRO19*%
%AMMACRO73*
4,1,8,.0034,.0082,
-.0034,.0082,
-.0082,.0034,
-.0082,-.00341,
-.00341,-.0082,
.0034,-.0082,
.0082,-.0034,
.0082,.0034,
.0034,.0082,
0.0*
%
%ADD73MACRO73*%
%AMMACRO72*
4,1,8,.0082,-.0034,
.0082,.0034,
.0034,.0082,
-.00341,.0082,
-.0082,.00341,
-.0082,-.0034,
-.0034,-.0082,
.0034,-.0082,
.0082,-.0034,
0.0*
%
%ADD72MACRO72*%
%AMMACRO99*
4,1,28,-.00565,.00493,
-.00732,.0066,
-.01121,.0027,
-.011649,.002185,
-.011989,.001599,
-.012222,.000962,
-.01234,.000295,
-.012342,-.000382,
-.012225,-.001049,
-.011994,-.001686,
-.011657,-.002273,
-.011222,-.002793,
-.01119,-.00283,
-.00283,-.01119,
-.002313,-.011629,
-.00173,-.011974,
-.001096,-.012212,
-.00043,-.012337,
.000247,-.012344,
.000915,-.012234,
.001554,-.012009,
.002145,-.011677,
.002668,-.011247,
.0027,-.01121,
.0066,-.00732,
.00493,-.00565,
.0123,.00173,
.00173,.0123,
-.00565,.00493,
0.0*
%
%ADD99MACRO99*%
%AMMACRO31*
4,1,28,-.00748,-.00051,
-.00984,-.00051,
-.00984,-.00602,
-.009782,-.006695,
-.009607,-.007349,
-.009321,-.007964,
-.008933,-.008519,
-.008455,-.008998,
-.0079,-.009388,
-.007287,-.009675,
-.006632,-.009851,
-.005958,-.00991,
-.00591,-.00991,
.00591,-.00991,
.006585,-.009859,
.007242,-.009691,
.007859,-.009411,
.008418,-.009029,
.008903,-.008555,
.009297,-.008005,
.00959,-.007394,
.009773,-.006742,
.00984,-.006068,
.00984,-.00602,
.00984,-.00051,
.00748,-.00051,
.00748,.00992,
-.00748,.00992,
-.00748,-.00051,
0.0*
%
%ADD31MACRO31*%
%ADD92R,.06574X.06574*%
%AMMACRO18*
4,1,28,-.00051,.00748,
-.00051,.00984,
-.00602,.00984,
-.006695,.009782,
-.007349,.009607,
-.007964,.009321,
-.008519,.008933,
-.008998,.008455,
-.009388,.0079,
-.009675,.007287,
-.009851,.006632,
-.00991,.005958,
-.00991,.00591,
-.00991,-.00591,
-.009859,-.006585,
-.009691,-.007242,
-.009411,-.007859,
-.009029,-.008418,
-.008555,-.008903,
-.008005,-.009297,
-.007394,-.00959,
-.006742,-.009773,
-.006068,-.00984,
-.00602,-.00984,
-.00051,-.00984,
-.00051,-.00748,
.00992,-.00748,
.00992,.00748,
-.00051,.00748,
0.0*
%
%ADD18MACRO18*%
%ADD78R,.02X.012*%
%ADD91O,.255X.2*%
%AMMACRO110*
21,1,.012,.015,0.0,0.0,45.*%
%ADD110MACRO110*%
%AMMACRO106*
21,1,.04,.05,0.0,0.0,45.*%
%ADD106MACRO106*%
%ADD58R,.015X.012*%
%ADD27R,.05X.04*%
%ADD65R,.012X.015*%
%ADD44R,.04X.05*%
%ADD81R,.04X.015*%
%ADD56R,.017X.02*%
%ADD41R,.02X.018*%
%AMMACRO109*
21,1,.016,.0041,0.0,0.0,135.*%
%ADD109MACRO109*%
%ADD69R,.018X.02*%
%ADD85R,.044X.014*%
%ADD102C,.122*%
%ADD57R,.032X.028*%
%ADD93R,.128X.135*%
%ADD89R,.052X.018*%
%ADD59R,.028X.032*%
%ADD21R,.046X.024*%
%ADD96R,.054X.044*%
%ADD79R,.054X.026*%
%ADD13C,.125*%
%ADD60R,.044X.054*%
%ADD53C,.135*%
%ADD52C,.315*%
%ADD36R,.026X.054*%
%ADD22R,.046X.017*%
%ADD84C,.217*%
%ADD80R,.059X.014*%
%ADD98R,.066X.017*%
%AMMACRO104*
4,1,8,.037,.005,
-.005,.005,
-.005,.014,
-.037,.014,
-.037,-.014,
-.005,-.014,
-.005,-.005,
.037,-.005,
.037,.005,
0.0*
%
%ADD104MACRO104*%
%ADD68R,.056X.056*%
%ADD88C,.158*%
%ADD10C,.394*%
%AMMACRO94*
4,1,8,-.0425,.078,
.0425,.078,
.0425,-.078,
-.0425,-.078,
-.0425,-.0236,
-.0145,-.0236,
-.0145,.0236,
-.0425,.0236,
-.0425,.078,
0.0*
%
%ADD94MACRO94*%
%AMMACRO101*
4,1,28,.00492,-.00566,
.00659,-.00733,
.00269,-.01122,
.002174,-.011659,
.001588,-.011998,
.000951,-.01223,
.000284,-.012348,
-.000393,-.012348,
-.001061,-.012231,
-.001697,-.012,
-.002284,-.011661,
-.002803,-.011226,
-.00284,-.01119,
-.01119,-.00284,
-.011631,-.002326,
-.011978,-.001744,
-.012217,-.00111,
-.012343,-.000444,
-.012352,.000233,
-.012243,.000902,
-.012019,.001541,
-.011688,.002132,
-.011259,.002656,
-.01122,.00269,
-.00733,.00659,
-.00566,.00492,
.00172,.0123,
.0123,.00172,
.00492,-.00566,
0.0*
%
%ADD101MACRO101*%
%AMMACRO23*
4,1,28,.00748,-.00052,
.00984,-.00052,
.00984,-.00603,
.009782,-.006705,
.009607,-.007359,
.009321,-.007974,
.008933,-.008529,
.008455,-.009009,
.0079,-.009398,
.007286,-.009685,
.006632,-.009861,
.005957,-.00992,
.00591,-.00992,
-.00591,-.00992,
-.006585,-.009869,
-.007242,-.009701,
-.007859,-.009421,
-.008418,-.009039,
-.008903,-.008565,
-.009297,-.008015,
-.009591,-.007404,
-.009773,-.006751,
-.00984,-.006077,
-.00984,-.00603,
-.00984,-.00052,
-.00748,-.00052,
-.00748,.00991,
.00748,.00991,
.00748,-.00052,
0.0*
%
%ADD23MACRO23*%
%AMMACRO16*
4,1,28,-.00052,-.00748,
-.00052,-.00984,
-.00603,-.00984,
-.006705,-.009782,
-.007359,-.009607,
-.007974,-.009321,
-.008529,-.008933,
-.009009,-.008455,
-.009398,-.0079,
-.009685,-.007286,
-.009861,-.006632,
-.00992,-.005957,
-.00992,-.00591,
-.00992,.00591,
-.009869,.006585,
-.009701,.007242,
-.009421,.007859,
-.009039,.008418,
-.008565,.008903,
-.008015,.009297,
-.007404,.009591,
-.006751,.009773,
-.006077,.00984,
-.00603,.00984,
-.00052,.00984,
-.00052,.00748,
.00991,.00748,
.00991,-.00748,
-.00052,-.00748,
0.0*
%
%ADD16MACRO16*%
%AMMACRO108*
4,1,28,.00329,-.00674,
.00447,-.00878,
-.0003,-.01154,
-.000915,-.011824,
-.00157,-.012,
-.002244,-.01206,
-.002919,-.012001,
-.003574,-.011826,
-.004188,-.01154,
-.004743,-.011152,
-.005223,-.010674,
-.005612,-.010119,
-.00563,-.01008,
-.01155,.00016,
-.011841,.000772,
-.012023,.001425,
-.012089,.002099,
-.012036,.002774,
-.011868,.00343,
-.011588,.004047,
-.011205,.004606,
-.010731,.00509,
-.01018,.005484,
-.01014,.00551,
-.00537,.00826,
-.00419,.00622,
.00484,.01143,
.01232,-.00152,
.00329,-.00674,
0.0*
%
%ADD108MACRO108*%
%AMMACRO75*
4,1,8,-.0034,-.0082,
.0034,-.0082,
.0082,-.0034,
.0082,.00341,
.00341,.0082,
-.0034,.0082,
-.0082,.0034,
-.0082,-.0034,
-.0034,-.0082,
0.0*
%
%ADD75MACRO75*%
%AMMACRO74*
4,1,8,-.0082,.0034,
-.0082,-.0034,
-.0034,-.0082,
.00341,-.0082,
.0082,-.00341,
.0082,.0034,
.0034,.0082,
-.0034,.0082,
-.0082,.0034,
0.0*
%
%ADD74MACRO74*%
%AMMACRO103*
4,1,28,.00565,-.00493,
.00732,-.0066,
.01121,-.0027,
.011649,-.002185,
.011989,-.001599,
.012222,-.000962,
.01234,-.000295,
.012342,.000382,
.012225,.001049,
.011994,.001686,
.011657,.002273,
.011222,.002793,
.01119,.00283,
.00283,.01119,
.002313,.011629,
.00173,.011974,
.001096,.012212,
.00043,.012337,
-.000247,.012344,
-.000915,.012234,
-.001554,.012009,
-.002145,.011677,
-.002668,.011247,
-.0027,.01121,
-.0066,.00732,
-.00493,.00565,
-.0123,-.00173,
-.00173,-.0123,
.00565,-.00493,
0.0*
%
%ADD103MACRO103*%
%AMMACRO26*
4,1,28,.00051,-.00748,
.00051,-.00984,
.00602,-.00984,
.006695,-.009782,
.007349,-.009607,
.007964,-.009321,
.008519,-.008933,
.008998,-.008455,
.009388,-.0079,
.009675,-.007287,
.009851,-.006632,
.00991,-.005958,
.00991,-.00591,
.00991,.00591,
.009859,.006585,
.009691,.007242,
.009411,.007859,
.009029,.008418,
.008555,.008903,
.008005,.009297,
.007394,.00959,
.006742,.009773,
.006068,.00984,
.00602,.00984,
.00051,.00984,
.00051,.00748,
-.00992,.00748,
-.00992,-.00748,
.00051,-.00748,
0.0*
%
%ADD26MACRO26*%
%AMMACRO24*
4,1,28,.00748,.00051,
.00984,.00051,
.00984,.00602,
.009782,.006695,
.009607,.007349,
.009321,.007964,
.008933,.008519,
.008455,.008998,
.0079,.009388,
.007287,.009675,
.006632,.009851,
.005958,.00991,
.00591,.00991,
-.00591,.00991,
-.006585,.009859,
-.007242,.009691,
-.007859,.009411,
-.008418,.009029,
-.008903,.008555,
-.009297,.008005,
-.00959,.007394,
-.009773,.006742,
-.00984,.006068,
-.00984,.00602,
-.00984,.00051,
-.00748,.00051,
-.00748,-.00992,
.00748,-.00992,
.00748,.00051,
0.0*
%
%ADD24MACRO24*%
%AMMACRO107*
4,1,28,.00418,-.00622,
.00536,-.00827,
.01013,-.00551,
.010687,-.005125,
.011167,-.004646,
.011556,-.004092,
.011844,-.003479,
.01202,-.002825,
.01208,-.00215,
.012022,-.001475,
.011848,-.00082,
.011563,-.000206,
.01154,-.00016,
.00563,.01007,
.005247,.010629,
.004774,.011114,
.004224,.011509,
.003614,.011803,
.002962,.011987,
.002288,.012054,
.001612,.012004,
.000956,.011837,
.000338,.011558,
.00029,.01153,
-.00448,.00878,
-.0033,.00673,
-.01233,.00152,
-.00485,-.01144,
.00418,-.00622,
0.0*
%
%ADD107MACRO107*%
%ADD114C,.01*%
%ADD115C,.012*%
%ADD116C,.014*%
%ADD117C,.015*%
%ADD118C,.004*%
%ADD119C,.006*%
%ADD120C,.0051*%
%ADD121C,.007*%
%ADD122C,.0052*%
%ADD123C,.0044*%
%ADD124C,.0035*%
%ADD125C,.008*%
%ADD126C,.009*%
%ADD127C,.0045*%
%ADD128C,.00349*%
%ADD129C,.0079*%
%ADD130C,.03004*%
%ADD133C,.03006*%
%ADD132C,.07004*%
%ADD141C,.02604*%
%ADD140C,.07104*%
%ADD145C,.07006*%
%ADD139C,.02704*%
%ADD135C,.07204*%
%ADD131C,.03604*%
%ADD134C,.02804*%
%ADD136C,.03606*%
%ADD146C,.06804*%
%ADD137C,.02576*%
%ADD144C,.30104*%
%ADD147C,.1622*%
%ADD138C,.1751*%
%ADD142C,.2582*%
%ADD143C,.198*%
G75*
%LPD*%
G75*
G36*
G01X2117Y71411D02*
X2480Y71603D01*
X2590Y71596D01*
X2636Y71564D01*
G03X3908Y70761I11138J16234D01*
G01X4006Y70591D01*
Y54252D01*
G03X7874Y50384I3868J0D01*
G01X43711D01*
G02X55590Y38504I-1J-11880D01*
G01Y15533D01*
X55515Y15385D01*
G03X54043Y12480I2131J-2905D01*
G03X55510Y9579I3602J0D01*
G01X55590Y9421D01*
Y4000D01*
X317654D01*
Y9415D01*
X317736Y9575D01*
G03Y15379I-2133J2902D01*
G01X317654Y15539D01*
Y38504D01*
G02X318976Y43950I11881J-1D01*
G02X319005Y43987I171J-104D01*
G01X319680Y44662D01*
G02X319710Y44687I142J-140D01*
G01X328069Y50273D01*
G02X328132Y50301I111J-166D01*
G02X329533Y50384I1402J-11797D01*
G01X488593D01*
G02X500472Y38504I-1J-11880D01*
G01Y36314D01*
G02X500391Y36167I-200J14D01*
G03X498933Y33512I2135J-2900D01*
G01X498821Y33345D01*
G03X498769Y33319I646J-1357D01*
G01X498675Y33296D01*
G02X498475Y33495I0J200D01*
G01Y38504D01*
G03X488591Y48388I-9884J0D01*
G01X329535D01*
G03X319651Y38504I0J-9884D01*
G01Y5060D01*
X319660D01*
Y3937D01*
G02X317724Y2001I-1936J0D01*
G01X55520D01*
G02X53584Y3937I0J1936D01*
G01Y5060D01*
X53593D01*
Y38504D01*
G03X43709Y48388I-9884J0D01*
G01X7874D01*
G02X2010Y54252I0J5864D01*
G01Y71234D01*
G02X2117Y71411I200J0D01*
G37*
G36*
G01X6989Y313202D02*
G03X9884Y320190I-6988J6989D01*
G01Y1588078D01*
G02X11601Y1592224I5864J0D01*
G01X24705Y1605328D01*
G03X27601Y1612316I-6987J6990D01*
G01Y1732244D01*
G02X33465Y1738108I5864J0D01*
G01X765526D01*
G02X765726Y1737908I0J-200D01*
G01Y1736890D01*
G03X769705Y1732911I3979J0D01*
G01X1087854D01*
G03X1091833Y1736890I0J3979D01*
G01Y1737908D01*
G02X1092033Y1738108I200J0D01*
G01X1824016D01*
G02X1829880Y1732244I0J-5864D01*
G01Y1612316D01*
G03X1832775Y1605328I9883J1D01*
G01X1839974Y1598129D01*
G02X1841691Y1593983I-4147J-4146D01*
G01Y326095D01*
G03X1844586Y319107I9884J1D01*
G01X1853753Y309940D01*
G02X1855470Y305794I-4147J-4146D01*
G01Y104355D01*
G02X1855363Y104178I-200J0D01*
G01X1855001Y103987D01*
X1854889Y103994D01*
X1854844Y104025D01*
G03X1853572Y104829I-11147J-16228D01*
G02X1853472Y105002I100J173D01*
G01Y122454D01*
G02X1853491Y122539I200J0D01*
G03X1854530Y127165I-9790J4628D01*
G01Y133464D01*
G03X1853491Y138090I-10829J-2D01*
G02X1853472Y138175I181J85D01*
G01Y305796D01*
G03X1852341Y308528I-3867J-1D01*
G01X1843174Y317695D01*
G02X1839694Y326095I8401J8401D01*
G01Y453145D01*
G02X1839716Y453236I200J0D01*
G03X1839881Y453921I-1337J684D01*
G03X1839716Y454606I-1502J1D01*
G02X1839694Y454697I178J91D01*
G01Y1413131D01*
G02X1839705Y1413197I200J1D01*
G03X1840910Y1420330I-20497J7131D01*
G03X1839705Y1427463I-21702J2D01*
G02X1839694Y1427529I189J65D01*
G01Y1593984D01*
G03X1838562Y1596717I-3867J-1D01*
G01X1831363Y1603916D01*
G02X1827882Y1612316I8399J8402D01*
G01Y1712691D01*
X1827884Y1712702D01*
G03X1828002Y1714961I-21585J2260D01*
G03X1827884Y1717220I-21703J-1D01*
G01X1827882Y1717231D01*
Y1732244D01*
G03X1824016Y1736110I-3866J0D01*
G01X1811167D01*
X1811145Y1736116D01*
G03X1806299Y1736664I-4846J-21155D01*
G03X1801453Y1736115I5J-21702D01*
G02X1801408Y1736110I-44J195D01*
G01X1617787D01*
X1617756Y1736121D01*
G03X1617126Y1736222I-629J-1909D01*
G03X1616496Y1736121I-1J-2010D01*
G01X1616465Y1736110D01*
X1602039D01*
X1602008Y1736121D01*
G03X1601378Y1736222I-629J-1909D01*
G03X1600748Y1736121I-1J-2010D01*
G01X1600717Y1736110D01*
X1586291D01*
X1586260Y1736121D01*
G03X1585630Y1736222I-629J-1909D01*
G03X1585000Y1736121I-1J-2010D01*
G01X1584969Y1736110D01*
X1571741D01*
X1571686Y1736126D01*
X1571662Y1736142D01*
G03X1571391Y1736222I-272J-421D01*
G01X1568373D01*
G03X1568102Y1736142I1J-501D01*
G01X1568078Y1736126D01*
X1568023Y1736110D01*
X1550858D01*
X1550827Y1736121D01*
G03X1550197Y1736222I-629J-1909D01*
G03X1549567Y1736121I-1J-2010D01*
G01X1549536Y1736110D01*
X1535110D01*
X1535079Y1736121D01*
G03X1534449Y1736222I-629J-1909D01*
G03X1533819Y1736121I-1J-2010D01*
G01X1533788Y1736110D01*
X1519362D01*
X1519331Y1736121D01*
G03X1518701Y1736222I-629J-1909D01*
G03X1518071Y1736121I-1J-2010D01*
G01X1518040Y1736110D01*
X1504812D01*
X1504757Y1736126D01*
X1504733Y1736142D01*
G03X1504462Y1736222I-272J-421D01*
G01X1501444D01*
G03X1501173Y1736142I1J-501D01*
G01X1501149Y1736126D01*
X1501094Y1736110D01*
X1466696D01*
G02X1466651Y1736115I-1J200D01*
G03X1461805Y1736664I-4851J-21153D01*
G03X1456959Y1736115I5J-21702D01*
G02X1456914Y1736110I-44J195D01*
G01X1353614D01*
X1353583Y1736121D01*
G03X1352953Y1736222I-629J-1909D01*
G03X1352323Y1736121I-1J-2010D01*
G01X1352292Y1736110D01*
X1337866D01*
X1337835Y1736121D01*
G03X1337205Y1736222I-629J-1909D01*
G03X1336575Y1736121I-1J-2010D01*
G01X1336544Y1736110D01*
X1322118D01*
X1322087Y1736121D01*
G03X1321457Y1736222I-629J-1909D01*
G03X1320827Y1736121I-1J-2010D01*
G01X1320796Y1736110D01*
X1307568D01*
X1307513Y1736126D01*
X1307489Y1736142D01*
G03X1307218Y1736222I-272J-421D01*
G01X1304200D01*
G03X1303929Y1736142I1J-501D01*
G01X1303905Y1736126D01*
X1303850Y1736110D01*
X1286685D01*
X1286654Y1736121D01*
G03X1286024Y1736222I-629J-1909D01*
G03X1285394Y1736121I-1J-2010D01*
G01X1285363Y1736110D01*
X1270937D01*
X1270906Y1736121D01*
G03X1270276Y1736222I-629J-1909D01*
G03X1269646Y1736121I-1J-2010D01*
G01X1269615Y1736110D01*
X1255189D01*
X1255158Y1736121D01*
G03X1254528Y1736222I-629J-1909D01*
G03X1253898Y1736121I-1J-2010D01*
G01X1253867Y1736110D01*
X1240639D01*
X1240584Y1736126D01*
X1240560Y1736142D01*
G03X1240289Y1736222I-272J-421D01*
G01X1237271D01*
G03X1237000Y1736142I1J-501D01*
G01X1236976Y1736126D01*
X1236921Y1736110D01*
X1160599D01*
G02X1160554Y1736115I-1J200D01*
G03X1155708Y1736664I-4851J-21153D01*
G03X1150862Y1736115I5J-21702D01*
G02X1150817Y1736110I-44J195D01*
G01X1093780D01*
G02X1087854Y1730914I-5926J781D01*
G01X769705D01*
G02X763779Y1736110I0J5977D01*
G01X712568D01*
G02X712523Y1736115I-1J200D01*
G03X707677Y1736664I-4851J-21153D01*
G03X702831Y1736115I5J-21702D01*
G02X702786Y1736110I-44J195D01*
G01X609913D01*
X609882Y1736121D01*
G03X609252Y1736222I-629J-1909D01*
G03X608622Y1736121I-1J-2010D01*
G01X608591Y1736110D01*
X594165D01*
X594134Y1736121D01*
G03X593504Y1736222I-629J-1909D01*
G03X592874Y1736121I-1J-2010D01*
G01X592843Y1736110D01*
X578417D01*
X578386Y1736121D01*
G03X577756Y1736222I-629J-1909D01*
G03X577126Y1736121I-1J-2010D01*
G01X577095Y1736110D01*
X563867D01*
X563812Y1736126D01*
X563788Y1736142D01*
G03X563517Y1736222I-272J-421D01*
G01X560499D01*
G03X560228Y1736142I1J-501D01*
G01X560204Y1736126D01*
X560149Y1736110D01*
X542984D01*
X542953Y1736121D01*
G03X542323Y1736222I-629J-1909D01*
G03X541693Y1736121I-1J-2010D01*
G01X541662Y1736110D01*
X527236D01*
X527205Y1736121D01*
G03X526575Y1736222I-629J-1909D01*
G03X525945Y1736121I-1J-2010D01*
G01X525914Y1736110D01*
X511488D01*
X511457Y1736121D01*
G03X510827Y1736222I-629J-1909D01*
G03X510197Y1736121I-1J-2010D01*
G01X510166Y1736110D01*
X496938D01*
X496883Y1736126D01*
X496859Y1736142D01*
G03X496588Y1736222I-272J-421D01*
G01X493570D01*
G03X493299Y1736142I1J-501D01*
G01X493275Y1736126D01*
X493220Y1736110D01*
X400561D01*
G02X400516Y1736115I-1J200D01*
G03X395670Y1736664I-4851J-21153D01*
G03X390824Y1736115I5J-21702D01*
G02X390779Y1736110I-44J195D01*
G01X345740D01*
X345709Y1736121D01*
G03X345079Y1736222I-629J-1909D01*
G03X344449Y1736121I-1J-2010D01*
G01X344418Y1736110D01*
X329992D01*
X329961Y1736121D01*
G03X329331Y1736222I-629J-1909D01*
G03X328701Y1736121I-1J-2010D01*
G01X328670Y1736110D01*
X314244D01*
X314213Y1736121D01*
G03X313583Y1736222I-629J-1909D01*
G03X312953Y1736121I-1J-2010D01*
G01X312922Y1736110D01*
X299694D01*
X299639Y1736126D01*
X299615Y1736142D01*
G03X299344Y1736222I-272J-421D01*
G01X296326D01*
G03X296055Y1736142I1J-501D01*
G01X296031Y1736126D01*
X295976Y1736110D01*
X278811D01*
X278780Y1736121D01*
G03X278150Y1736222I-629J-1909D01*
G03X277520Y1736121I-1J-2010D01*
G01X277489Y1736110D01*
X263063D01*
X263032Y1736121D01*
G03X262402Y1736222I-629J-1909D01*
G03X261772Y1736121I-1J-2010D01*
G01X261741Y1736110D01*
X247315D01*
X247284Y1736121D01*
G03X246654Y1736222I-629J-1909D01*
G03X246024Y1736121I-1J-2010D01*
G01X245993Y1736110D01*
X232765D01*
X232710Y1736126D01*
X232686Y1736142D01*
G03X232415Y1736222I-272J-421D01*
G01X229397D01*
G03X229126Y1736142I1J-501D01*
G01X229102Y1736126D01*
X229047Y1736110D01*
X56072D01*
G02X56027Y1736115I-1J200D01*
G03X51181Y1736664I-4851J-21153D01*
G03X46335Y1736116I0J-21703D01*
G01X46313Y1736110D01*
X33465D01*
G03X29598Y1732244I0J-3867D01*
G01Y1717240D01*
X29597Y1717230D01*
G03X29478Y1714961I21584J-2270D01*
G03X29597Y1712692I21703J1D01*
G01X29598Y1712682D01*
Y1612316D01*
G02X26117Y1603916I-11880J2D01*
G01X13013Y1590812D01*
G03X11882Y1588080I2736J-2733D01*
G01Y758466D01*
Y598758D01*
Y320190D01*
G02X8401Y311790I-11880J2D01*
G01X5139Y308528D01*
G03X4008Y305796I2736J-2733D01*
G01Y166318D01*
G02X3937Y166165I-200J0D01*
G03Y164021I902J-1072D01*
G02X4008Y163868I-129J-153D01*
G01Y162293D01*
G02X3937Y162140I-200J0D01*
G03Y159996I902J-1072D01*
G02X4008Y159843I-129J-153D01*
G01Y158141D01*
G02X3929Y157982I-200J0D01*
G03Y155594I910J-1194D01*
G02X4008Y155435I-121J-159D01*
G01Y153937D01*
G02X3937Y153784I-200J0D01*
G03Y151640I902J-1072D01*
G02X4008Y151487I-129J-153D01*
G01Y150041D01*
G02X3910Y149870I-200J1D01*
G03Y147290I770J-1290D01*
G02X4008Y147119I-102J-172D01*
G01Y145934D01*
G02X3910Y145763I-200J1D01*
G03Y143183I770J-1290D01*
G02X4008Y143012I-102J-172D01*
G01Y141966D01*
G02X3897Y141787I-200J0D01*
G03X2928Y140221I782J-1567D01*
G03X3897Y138655I1751J1D01*
G02X4008Y138476I-89J-179D01*
G01Y105002D01*
G02X3908Y104829I-200J0D01*
G03X2636Y104026I9866J-17037D01*
G01X2590Y103994D01*
X2480Y103987D01*
X2117Y104179D01*
G02X2010Y104356I93J177D01*
G01Y305794D01*
G02X3727Y309940I5864J0D01*
G01X6989Y313202D01*
G37*
G36*
G01X23280Y399132D02*
X39180D01*
X40770Y397542D01*
Y396602D01*
G03X40431Y395652I1162J-950D01*
G03X40730Y394752I1502J-1D01*
G01X40770Y394699D01*
Y394204D01*
G02X40179Y393853I-400J0D01*
G03X39320Y394071I-859J-1583D01*
G03Y390467I0J-1802D01*
G03X40179Y390685I0J1801D01*
G02X40770Y390334I191J-351D01*
G01Y389104D01*
X40607Y389073D01*
G03Y385531I333J-1771D01*
G01X40770Y385500D01*
Y384692D01*
X38290Y382212D01*
X23730D01*
X21440Y384502D01*
Y397292D01*
X23280Y399132D01*
G37*
G36*
G01X250467Y1260577D02*
G03X249801Y1260409I0J-1402D01*
G01X249757Y1260385D01*
X249355D01*
Y1260660D01*
X249404Y1260717D01*
G03X249849Y1261902I-1357J1186D01*
G03X248047Y1263704I-1802J0D01*
G03X246246Y1261955I0J-1802D01*
G02X245649Y1261619I-400J12D01*
G03X244791Y1261844I-859J-1526D01*
G01X244079D01*
G03X242841Y1261331I0J-1750D01*
G01X241894Y1260385D01*
X236164D01*
X236135Y1260395D01*
G03X236132Y1260396I-555J-1661D01*
G01X235993Y1260587D01*
X236118Y1260772D01*
G03X237001Y1262074I-518J1302D01*
G03X235599Y1263476I-1402J0D01*
G03X234285Y1262563I0J-1402D01*
G01X234270Y1262522D01*
X232902Y1261154D01*
X232819D01*
G03X231343Y1260385I1J-1802D01*
G01X221545D01*
X221465Y1260464D01*
X221460Y1260576D01*
G03X217860I-1800J-84D01*
G01X217851Y1260385D01*
X215340D01*
X215313Y1260393D01*
G03X214824Y1260462I-487J-1682D01*
G03X214335Y1260393I-2J-1751D01*
G01X214308Y1260385D01*
X208240D01*
X208211Y1260395D01*
G03X207675Y1260478I-533J-1668D01*
G01X207247D01*
G02X206948Y1261144I0J400D01*
G03X207301Y1262074I-1049J930D01*
G03X205899Y1263476I-1402J0D01*
G01X205897D01*
G03X205315Y1263349I1J-1402D01*
G01X205276Y1263330D01*
X204332D01*
G03X203040Y1263876I-1292J-1256D01*
G03X201238Y1262074I0J-1802D01*
G03X201274Y1261718I1802J2D01*
G02X200882Y1261238I-392J-80D01*
G01X199708D01*
G03X198820Y1260870I0J-1255D01*
G01X198334Y1260385D01*
X190175D01*
X190113Y1260446D01*
X190106Y1260574D01*
G03X186508I-1799J-99D01*
G01X186497Y1260385D01*
X185805D01*
X185760Y1260409D01*
G03X184923Y1260622I-837J-1538D01*
G01X184921D01*
G03X184042Y1260385I1J-1751D01*
G01X178790D01*
X178761Y1260395D01*
G03X178225Y1260478I-533J-1668D01*
G01X177547D01*
G02X177248Y1261144I0J400D01*
G03X177601Y1262074I-1049J930D01*
G03X176199Y1263476I-1402J0D01*
G03X174885Y1262563I0J-1402D01*
G01X174870Y1262522D01*
X174274Y1261926D01*
X174166Y1261950D01*
G03X173770Y1261994I-396J-1758D01*
G03X172003Y1260546I0J-1802D01*
G01X171971Y1260385D01*
X160265D01*
G03X157689I-1288J-1259D01*
G01X148126D01*
X148097Y1260395D01*
G03X147561Y1260478I-533J-1668D01*
G01X147086D01*
Y1260795D01*
X147187Y1260853D01*
G03X147901Y1262074I-687J1221D01*
G03X146999Y1263384I-1402J0D01*
G01X146959Y1263399D01*
X146887Y1263470D01*
G03X145999Y1263838I-888J-887D01*
G01X144972D01*
G03X143680Y1264384I-1292J-1256D01*
G03X141878Y1262582I0J-1802D01*
G03X142639Y1261111I1802J0D01*
G02X142408Y1260385I-232J-326D01*
G01X130565D01*
G03X127989I-1288J-1259D01*
G01X119440D01*
X119411Y1260395D01*
G03X118875Y1260478I-533J-1668D01*
G01X117726D01*
G02X117585Y1260820I0J200D01*
G01X117687Y1260923D01*
G03X117901Y1261207I-886J890D01*
G03X118201Y1262074I-1103J867D01*
G03X116799Y1263476I-1402J0D01*
G03X115409Y1262256I0J-1402D01*
G01X115400Y1262189D01*
X114047Y1260836D01*
X113967Y1260833D01*
G03X112830Y1260385I53J-1801D01*
G01X100865D01*
G03X98289I-1288J-1259D01*
G01X88726D01*
X88697Y1260395D01*
G03X88161Y1260478I-533J-1668D01*
G01X87946D01*
Y1260759D01*
X88002Y1260818D01*
G03X88316Y1261378I-902J874D01*
G03X88501Y1262074I-1217J696D01*
G03X87099Y1263476I-1402J0D01*
G03X85699Y1262141I0J-1402D01*
G01X85695Y1262064D01*
X84417Y1260786D01*
X84337Y1260783D01*
G03X83259Y1260385I53J-1801D01*
G01X71165D01*
G03X68589I-1288J-1259D01*
G01X60140D01*
X60111Y1260395D01*
G03X59575Y1260478I-533J-1668D01*
G01X58853D01*
G02X58502Y1261070I0J400D01*
G03X58624Y1261393I-1103J601D01*
G03X58801Y1262074I-1225J682D01*
G03X57399Y1263476I-1402J0D01*
G03X55998Y1262123I0J-1402D01*
G01X55995Y1262044D01*
X54647Y1260696D01*
X54567Y1260693D01*
G03X53611Y1260385I53J-1801D01*
G01X41273D01*
G03X39161I-1056J-1459D01*
G01X30410D01*
X30381Y1260395D01*
G03X29845Y1260478I-533J-1668D01*
G01X29574D01*
X29437Y1260615D01*
Y1263888D01*
X28900Y1264425D01*
X26769D01*
X26768Y1264426D01*
X23206D01*
X22697Y1264935D01*
Y1308255D01*
X24016Y1309574D01*
X63256D01*
X73404Y1319722D01*
X135360D01*
X155610Y1299472D01*
X264190D01*
X265472Y1298190D01*
Y1260670D01*
X265187Y1260385D01*
X251177D01*
X251133Y1260409D01*
G03X250467Y1260577I-666J-1234D01*
G37*
G36*
G01X41288Y404822D02*
X72038D01*
X75620Y401240D01*
Y384222D01*
X75020Y383622D01*
X65320D01*
X64420Y384522D01*
Y398322D01*
X63620Y399122D01*
X48320D01*
X46420Y397222D01*
Y382532D01*
X45830Y381942D01*
X40140D01*
X39788Y382294D01*
X41772Y384277D01*
Y385703D01*
G03Y388901I-833J1599D01*
G01Y397957D01*
X39669Y400059D01*
Y403203D01*
X41288Y404822D01*
G37*
G36*
G01X49418Y398120D02*
X61722D01*
X63418Y396424D01*
Y384107D01*
X63420Y384106D01*
Y383222D01*
X64120Y382522D01*
X70520D01*
X70820Y382222D01*
Y379222D01*
X70320Y378722D01*
X49820D01*
X47920Y380622D01*
Y396622D01*
X49418Y398120D01*
G37*
G36*
G01X49684Y440102D02*
X64240D01*
X64740Y439602D01*
Y438402D01*
X64040Y437702D01*
X52940D01*
X51140Y439502D01*
X49684D01*
Y440102D01*
G37*
G36*
G01X48683Y440602D02*
Y443802D01*
Y445916D01*
X48477Y446122D01*
X48062D01*
X47983Y446043D01*
Y443802D01*
Y440602D01*
Y438086D01*
X48096Y437973D01*
X48561D01*
X48683Y438095D01*
Y440602D01*
G37*
G36*
G01D02*
Y443802D01*
Y445916D01*
X48477Y446122D01*
X48062D01*
X47983Y446043D01*
Y443802D01*
Y440602D01*
Y438086D01*
X48096Y437973D01*
X48561D01*
X48683Y438095D01*
Y440602D01*
G37*
G36*
G01X47109D02*
Y443802D01*
Y446001D01*
X47044Y446066D01*
X46552D01*
X46409Y445923D01*
Y443802D01*
Y440602D01*
Y438231D01*
X46467Y438173D01*
X46993D01*
X47109Y438289D01*
Y440602D01*
G37*
G36*
G01D02*
Y443802D01*
Y446001D01*
X47044Y446066D01*
X46552D01*
X46409Y445923D01*
Y443802D01*
Y440602D01*
Y438231D01*
X46467Y438173D01*
X46993D01*
X47109Y438289D01*
Y440602D01*
G37*
G36*
G01X161458Y1443354D02*
G02X161517Y1443212I-141J-142D01*
G01Y1421138D01*
G02X161458Y1420996I-200J0D01*
G01X160936Y1420474D01*
X160908Y1420445D01*
X160834Y1420415D01*
X145120D01*
G03X144978Y1420356I0J-200D01*
G01X133396Y1408774D01*
G03X133337Y1408632I141J-142D01*
G01Y1334638D01*
G02X133278Y1334496I-200J0D01*
G01X128846Y1330064D01*
X128818Y1330035D01*
X128744Y1330005D01*
X62545D01*
X61120Y1331430D01*
Y1341862D01*
X72820Y1353562D01*
Y1440662D01*
Y1463592D01*
X77670Y1468442D01*
X159290D01*
X161458Y1466274D01*
Y1443354D01*
G37*
G36*
G01X73751Y37103D02*
G03I-722J0D01*
G37*
G36*
G01X73741Y40017D02*
G03I-722J0D01*
G37*
G36*
G01X73120Y382422D02*
X73220Y382522D01*
X78420D01*
X79220Y381722D01*
Y377922D01*
X78720Y377422D01*
X73520D01*
X73120Y377822D01*
Y382422D01*
G37*
G36*
G01X92122Y723637D02*
X98460D01*
X102762Y719335D01*
Y704970D01*
G02X102208Y704601I-400J0D01*
G03X101512Y704741I-696J-1662D01*
G03X99742Y703278I0J-1802D01*
G01X99731Y703217D01*
X98755Y702242D01*
G03X98419Y701718I1030J-1030D01*
G02X97908Y701481I-375J139D01*
G03X97295Y701588I-612J-1695D01*
G03Y697984I0J-1802D01*
G03X97813Y698060I0J1803D01*
G02X98328Y697677I115J-383D01*
G01Y695858D01*
X97704Y695234D01*
X95876D01*
G03X95769Y695231I-13J-1456D01*
G01X95761Y695230D01*
X94740D01*
X93950Y694440D01*
X89310D01*
X89113Y694637D01*
X85492D01*
Y697236D01*
X85497Y697259D01*
G03X85537Y697604I-1462J344D01*
G03X82533I-1502J0D01*
G03X82573Y697259I1502J-1D01*
G01X82578Y697236D01*
Y694637D01*
X77960D01*
X74532Y698064D01*
Y699785D01*
X75328Y700580D01*
X77249D01*
G03X78080Y700330I830J1252D01*
G03Y703334I0J1502D01*
G03X77249Y703084I-1J-1502D01*
G01X74810D01*
G03X73925Y702717I1J-1252D01*
G01X72396Y701188D01*
G03X72053Y700544I885J-885D01*
G01X72021Y700383D01*
X64146D01*
X62245Y702284D01*
Y717567D01*
X68315Y723637D01*
X83844D01*
Y722996D01*
X83814Y722948D01*
G03X83593Y722164I1280J-784D01*
G03X86597I1502J0D01*
G03X86376Y722948I-1501J0D01*
G01X86346Y722996D01*
Y723637D01*
X87854D01*
X87903Y723508D01*
G03X88188Y723066I1171J442D01*
G01X90136Y721118D01*
X90150Y721063D01*
G03X91610Y719912I1460J350D01*
G03X93112Y721414I0J1502D01*
G03X91961Y722874I-1501J0D01*
G01X91906Y722888D01*
X91840Y722954D01*
G02X92122Y723637I283J283D01*
G37*
G36*
G01X76074Y1509952D02*
G03I-510J0D01*
G37*
G36*
G01X93920Y1547662D02*
X104720D01*
X106120Y1546262D01*
Y1532762D01*
X101620Y1528262D01*
X76420D01*
X70620Y1534062D01*
Y1546562D01*
X72120Y1548062D01*
X74220D01*
X75020Y1547262D01*
Y1535262D01*
X75720Y1534562D01*
X96420D01*
X97320Y1535462D01*
Y1541362D01*
X96620Y1542062D01*
X94220D01*
X93520Y1542762D01*
Y1547262D01*
X93920Y1547662D01*
G37*
G36*
G01X77120Y1540662D02*
X95220D01*
X96120Y1539762D01*
Y1537162D01*
X94920Y1535962D01*
X76820D01*
X76020Y1536762D01*
Y1539562D01*
X77120Y1540662D01*
G37*
G36*
G01X95010Y37103D02*
G03I-722J0D01*
G37*
G36*
G01X87924D02*
G03I-722J0D01*
G37*
G36*
G01X80837D02*
G03I-722J0D01*
G37*
G36*
G01X95000Y40017D02*
G03I-722J0D01*
G37*
G36*
G01X87914D02*
G03I-722J0D01*
G37*
G36*
G01X80827D02*
G03I-722J0D01*
G37*
G36*
G01X92581Y1492888D02*
G03I-510J0D01*
G37*
G36*
G01X78630Y1512936D02*
G03I-510J0D01*
G37*
G36*
G01X81159Y1509944D02*
G03I-510J0D01*
G37*
G36*
G01X94054Y1510099D02*
G03I-510J0D01*
G37*
G36*
G01X88969Y1510107D02*
G03I-510J0D01*
G37*
G36*
G01X91508Y1513037D02*
G03I-510J0D01*
G37*
G36*
G01X78630Y1521336D02*
G03I-510J0D01*
G37*
G36*
G01X91508Y1521437D02*
G03I-510J0D01*
G37*
G36*
G01X109184Y37103D02*
G03I-722J0D01*
G37*
G36*
G01X102097D02*
G03I-722J0D01*
G37*
G36*
G01X109174Y40017D02*
G03I-722J0D01*
G37*
G36*
G01X102087D02*
G03I-722J0D01*
G37*
G36*
G01X101509Y653935D02*
Y658626D01*
X101709Y658826D01*
X116109D01*
X116309Y658626D01*
Y645253D01*
X118337Y643225D01*
Y642099D01*
X116100Y639862D01*
X110930D01*
X110300Y639232D01*
X108970D01*
X108230D01*
X107800Y639662D01*
Y640626D01*
X106900Y641526D01*
X101709D01*
X101114Y640931D01*
X99323D01*
X98733Y641521D01*
Y651159D01*
X101509Y653935D01*
G37*
G36*
G01X123357Y37103D02*
G03I-722J0D01*
G37*
G36*
G01X116270D02*
G03I-722J0D01*
G37*
G36*
G01X123347Y40017D02*
G03I-722J0D01*
G37*
G36*
G01X116260D02*
G03I-722J0D01*
G37*
G36*
G01X133425Y499968D02*
X119025D01*
X118825Y500168D01*
Y517568D01*
X119025Y517768D01*
X133425D01*
X133625Y517568D01*
Y500168D01*
X133425Y499968D01*
G37*
G36*
G01X125864Y689733D02*
X124359Y691238D01*
Y730821D01*
X125400Y731862D01*
X166000D01*
X167300Y730562D01*
Y706862D01*
X166250Y705812D01*
X160350D01*
X159900Y706262D01*
Y723062D01*
X158300Y724662D01*
X145600D01*
X144320Y723382D01*
Y690137D01*
X143916Y689733D01*
X125864D01*
G37*
G36*
G01X120777Y1327697D02*
G03I-510J0D01*
G37*
G36*
G01X130444Y37103D02*
G03I-722J0D01*
G37*
G36*
G01X130434Y40017D02*
G03I-722J0D01*
G37*
G36*
G01X142770Y1356720D02*
X229660D01*
X231877Y1354503D01*
Y1325605D01*
X231818Y1325546D01*
X230576Y1324304D01*
X230517Y1324245D01*
X209224D01*
X209198Y1324252D01*
G03X208247Y1324380I-952J-3474D01*
G03X207296Y1324252I1J-3602D01*
G01X207270Y1324245D01*
X184824D01*
X184798Y1324252D01*
G03X183847Y1324380I-952J-3474D01*
G03X182896Y1324252I1J-3602D01*
G01X182870Y1324245D01*
X160358D01*
X160333Y1324251D01*
G03X159474Y1324355I-859J-3498D01*
G03X158615Y1324251I0J-3602D01*
G01X158590Y1324245D01*
X144624D01*
X140807Y1328062D01*
Y1354757D01*
X142770Y1356720D01*
G37*
G36*
G01X223880Y1418395D02*
X249374D01*
G02X249516Y1418336I0J-200D01*
G01X251301Y1416551D01*
G02X251360Y1416409I-141J-142D01*
G01Y1317795D01*
G02X251301Y1317653I-200J0D01*
G01X247569Y1313921D01*
G02X247427Y1313862I-142J141D01*
G01X153983D01*
G02X153841Y1313921I0J200D01*
G01X147659Y1320103D01*
G02X147600Y1320245I141J142D01*
G01Y1322477D01*
G02X147659Y1322619I200J0D01*
G01X148041Y1323001D01*
G02X148183Y1323060I142J-141D01*
G01X153983D01*
Y1323072D01*
X156077D01*
G02X156425Y1322475I0J-400D01*
G03X155972Y1320753I3049J-1723D01*
G03X162976I3502J0D01*
G03X162523Y1322475I-3502J-1D01*
G02X162871Y1323072I348J197D01*
G01X180436D01*
G02X180785Y1322478I-1J-400D01*
G03X180345Y1320779I3062J-1699D01*
G01Y1320778D01*
G03X187349I3502J0D01*
G01Y1320779D01*
G03X186909Y1322478I-3502J0D01*
G02X187258Y1323072I350J194D01*
G01X204836D01*
G02X205185Y1322478I-1J-400D01*
G03X204745Y1320779I3062J-1699D01*
G01Y1320778D01*
G03X211749I3502J0D01*
G01Y1320779D01*
G03X211309Y1322478I-3502J0D01*
G02X211658Y1323072I350J194D01*
G01X231997D01*
G03X232139Y1323131I0J200D01*
G01X233701Y1324693D01*
G03X233760Y1324835I-141J142D01*
G01Y1355419D01*
X231430Y1357749D01*
X141380D01*
X139571D01*
X138790Y1358530D01*
Y1388140D01*
X139350Y1388700D01*
X145072D01*
X148211Y1391839D01*
G02X148353Y1391898I142J-141D01*
G01X155214D01*
G03X155356Y1391957I0J200D01*
G01X156539Y1393140D01*
G03X156598Y1393282I-141J142D01*
G01Y1400422D01*
G02X156657Y1400564I200J0D01*
G01X157003Y1400910D01*
G02X157145Y1400969I142J-141D01*
G01X163435D01*
G02X163512Y1400954I1J-200D01*
G01X163580Y1400925D01*
G02X163645Y1400882I-76J-185D01*
G01X163782Y1400745D01*
G02X163841Y1400603I-141J-142D01*
G01Y1392247D01*
G03X163900Y1392105I200J0D01*
G01X164180Y1391825D01*
G03X164322Y1391766I142J141D01*
G01X182004D01*
G03X182146Y1391825I0J200D01*
G01X182952Y1392631D01*
G03X183011Y1392773I-141J142D01*
G01Y1401077D01*
G03X182952Y1401219I-200J0D01*
G01X181640Y1402531D01*
G02X181581Y1402673I141J142D01*
G01Y1412177D01*
G02X181640Y1412319I200J0D01*
G01X184202Y1414881D01*
G02X184344Y1414940I142J-141D01*
G01X186258D01*
G02X186400Y1414881I0J-200D01*
G01X186902Y1414379D01*
G02X186961Y1414237I-141J-142D01*
G01Y1413433D01*
G02X186902Y1413291I-200J0D01*
G01X185820Y1412209D01*
G03X185761Y1412067I141J-142D01*
G01Y1392697D01*
G03X185820Y1392555I200J0D01*
G01X186293Y1392082D01*
X186552Y1391822D01*
G03X186694Y1391763I142J141D01*
G01X192151D01*
G03X192293Y1391822I0J200D01*
G01X193802Y1393331D01*
G03X193861Y1393473I-141J142D01*
G01Y1400207D01*
G02X193920Y1400349I200J0D01*
G01X194479Y1400908D01*
G02X194621Y1400967I142J-141D01*
G01X201386D01*
G02X201528Y1400908I0J-200D01*
G01X201962Y1400474D01*
G02X202021Y1400332I-141J-142D01*
G01Y1392853D01*
G03X202080Y1392711I200J0D01*
G01X202966Y1391825D01*
G03X203108Y1391766I142J141D01*
G01X222135D01*
G03X222277Y1391825I0J200D01*
G01X222938Y1392486D01*
G03X222997Y1392628I-141J142D01*
G01Y1417512D01*
G02X223056Y1417654I200J0D01*
G01X223738Y1418336D01*
G02X223880Y1418395I142J-141D01*
G37*
G36*
G01X128513Y1557433D02*
X135944D01*
X137637Y1555740D01*
X148825D01*
X150740Y1553825D01*
Y1545189D01*
X150228Y1544677D01*
X135902D01*
X127811Y1552768D01*
Y1556731D01*
X128513Y1557433D01*
G37*
G36*
G01X128500Y1563820D02*
X128970Y1564290D01*
X136050D01*
X136430Y1563910D01*
Y1560440D01*
X136140Y1560150D01*
X129200D01*
X128500Y1560850D01*
Y1563820D01*
G37*
G36*
G01X159223Y37103D02*
G03I-722J0D01*
G37*
G36*
G01X152136D02*
G03I-722J0D01*
G37*
G36*
G01X159213Y40017D02*
G03I-722J0D01*
G37*
G36*
G01X152126D02*
G03I-722J0D01*
G37*
G36*
G01X173666Y700926D02*
X207200D01*
X208200Y699926D01*
Y688670D01*
X202142D01*
X200043Y690769D01*
X189290D01*
G03X189148Y690710I0J-200D01*
G01X184359Y685921D01*
G03X184300Y685779I141J-142D01*
G01Y668445D01*
G03X184359Y668303I200J0D01*
G01X186941Y665721D01*
G03X187083Y665662I142J141D01*
G01X214620D01*
X215284Y664998D01*
Y652203D01*
X214552Y651471D01*
X204118D01*
X200793Y654796D01*
Y658745D01*
G03X200734Y658887I-200J0D01*
G01X199915Y659706D01*
G03X199773Y659765I-142J-141D01*
G01X193815D01*
G03X193673Y659706I0J-200D01*
G01X189359Y655392D01*
G03X189300Y655250I141J-142D01*
G01Y637235D01*
G03X189359Y637093I200J0D01*
G01X193673Y632779D01*
X194824Y631628D01*
X214452D01*
X215284Y630796D01*
Y618203D01*
X214552Y617471D01*
X204118D01*
X200793Y620796D01*
Y624745D01*
G03X200734Y624887I-200J0D01*
G01X199915Y625706D01*
G03X199773Y625765I-142J-141D01*
G01X193815D01*
G03X193673Y625706I0J-200D01*
G01X189359Y621392D01*
G03X189300Y621250I141J-142D01*
G01Y603235D01*
G03X189359Y603093I200J0D01*
G01X193673Y598779D01*
X194458Y597994D01*
X194984Y597468D01*
X214749D01*
X215284Y596933D01*
Y584203D01*
X214552Y583471D01*
X204118D01*
X200793Y586796D01*
Y590745D01*
G03X200734Y590887I-200J0D01*
G01X199915Y591706D01*
G03X199773Y591765I-142J-141D01*
G01X172189D01*
X172105Y591849D01*
G03X171963Y591908I-142J-141D01*
G01X157174D01*
X154300Y594782D01*
Y681792D01*
X166500Y693992D01*
X173434Y700926D01*
X173666D01*
G37*
G36*
G01X157740Y723162D02*
X158540Y722362D01*
Y704522D01*
X152760Y698742D01*
Y691962D01*
X150830Y690032D01*
X146760D01*
X145470Y691322D01*
Y722632D01*
X146000Y723162D01*
X157740D01*
G37*
G36*
G01X163764Y1411112D02*
X163281Y1410629D01*
X162115D01*
X161092Y1411652D01*
X152085D01*
X151432Y1412305D01*
Y1414635D01*
X151731Y1414934D01*
X154486D01*
X163218D01*
X164193Y1413959D01*
Y1411541D01*
X163764Y1411112D01*
G37*
G36*
G01X152746Y1550540D02*
X162448D01*
X163521Y1549467D01*
Y1539889D01*
X163191Y1539559D01*
X152828D01*
X151780Y1540607D01*
Y1549574D01*
X152746Y1550540D01*
G37*
G36*
G01X151012Y1572021D02*
G03I-510J0D01*
G37*
G36*
G01X146032D02*
G03I-510J0D01*
G37*
G36*
G01X173396Y37103D02*
G03I-722J0D01*
G37*
G36*
G01X166310D02*
G03I-722J0D01*
G37*
G36*
G01X173386Y40017D02*
G03I-722J0D01*
G37*
G36*
G01X166300D02*
G03I-722J0D01*
G37*
G36*
G01X169958Y570913D02*
Y578154D01*
X169962Y578158D01*
Y579172D01*
X170574Y579784D01*
X191908D01*
X192520Y579172D01*
Y578158D01*
X192524Y578154D01*
Y570913D01*
X191944Y570334D01*
X170538D01*
X169958Y570913D01*
G37*
G36*
G01X175600Y1440525D02*
X212690D01*
X213877Y1439339D01*
Y1432185D01*
X221807Y1424255D01*
Y1393060D01*
G02X221748Y1392918I-200J0D01*
G01X221666Y1392836D01*
G02X221524Y1392777I-142J141D01*
G01X203317D01*
G02X203175Y1392836I0J200D01*
G01X203146Y1392865D01*
G02X203087Y1393007I141J142D01*
G01Y1400762D01*
G02X203146Y1400904I200J0D01*
G01X206864Y1404622D01*
G03X206923Y1404764I-141J142D01*
G01Y1413202D01*
G03X206864Y1413344I-200J0D01*
G01X204321Y1415887D01*
G03X204179Y1415946I-142J-141D01*
G01X183577D01*
G03X183435Y1415887I0J-200D01*
G01X180412Y1412864D01*
G03X180353Y1412722I141J-142D01*
G01Y1400593D01*
G03X180412Y1400451I200J0D01*
G01X181802Y1399061D01*
G02X181861Y1398919I-141J-142D01*
G01Y1393923D01*
G02X181802Y1393781I-200J0D01*
G01X180857Y1392836D01*
G02X180715Y1392777I-142J141D01*
G01X165707D01*
G02X165565Y1392836I0J200D01*
G01X164850Y1393551D01*
G02X164791Y1393693I141J142D01*
G01Y1401692D01*
G02X164850Y1401834I200J0D01*
G01X167858Y1404842D01*
G03X167917Y1404984I-141J142D01*
G01Y1432842D01*
X175600Y1440525D01*
G37*
G36*
G01X180483Y37103D02*
G03I-722J0D01*
G37*
G36*
G01X180473Y40017D02*
G03I-722J0D01*
G37*
G36*
G01X199687Y1411175D02*
X199235Y1411627D01*
X194730D01*
X193737Y1412620D01*
X190065D01*
X189575Y1413110D01*
Y1414610D01*
X189874Y1414909D01*
X192629D01*
X201361D01*
X202336Y1413934D01*
Y1411516D01*
X201995Y1411175D01*
X199687D01*
G37*
G36*
G01X187271Y1578182D02*
G03I-574J0D01*
G37*
G36*
G01Y1590094D02*
G03I-574J0D01*
G37*
G36*
G01X192571Y1602380D02*
G03I-574J0D01*
G37*
G36*
G01Y1614292D02*
G03I-574J0D01*
G37*
G36*
G01X203357Y37103D02*
G03I-722J0D01*
G37*
G36*
G01X196270D02*
G03I-722J0D01*
G37*
G36*
G01X203347Y40017D02*
G03I-722J0D01*
G37*
G36*
G01X196260D02*
G03I-722J0D01*
G37*
G36*
G01X210700Y708362D02*
X241500D01*
X242550Y707312D01*
Y693672D01*
X243200Y693022D01*
Y668862D01*
X245400Y666662D01*
X245800D01*
X246800Y665662D01*
Y564262D01*
X247400Y563662D01*
Y562062D01*
X247200Y561862D01*
X219100D01*
X217100Y563862D01*
Y574462D01*
X216600Y574962D01*
X208200D01*
X207500Y575662D01*
Y581462D01*
X208100Y582062D01*
X215300D01*
X216700Y583462D01*
Y608462D01*
X216100Y609062D01*
X208000D01*
X207300Y609762D01*
Y616062D01*
X207400Y616162D01*
X215800D01*
X216700Y617062D01*
Y641462D01*
X215000Y643162D01*
X208100D01*
X207400Y643862D01*
Y649462D01*
X208000Y650062D01*
X215800D01*
X216600Y650862D01*
Y674562D01*
X210700Y680462D01*
X202900D01*
X202300Y681062D01*
Y686862D01*
X202800Y687362D01*
X208900D01*
X209900Y688362D01*
Y707362D01*
X210700Y708162D01*
Y708362D01*
G37*
G36*
G01X194504Y590833D02*
X199198D01*
X199373Y590658D01*
Y584183D01*
G02X199172Y583983I-200J0D01*
G01X199164D01*
G03Y580979I0J-1502D01*
G01X199172D01*
G02X199373Y580779I1J-200D01*
G01Y580500D01*
X199004Y580131D01*
X194164D01*
X193534Y580761D01*
Y589863D01*
X194504Y590833D01*
G37*
G36*
G01Y624833D02*
X199198D01*
X199373Y624658D01*
Y618483D01*
G02X199172Y618283I-200J0D01*
G01X199164D01*
G03X197362Y616481I0J-1802D01*
G03X199081Y614681I1802J0D01*
G01X199158Y614677D01*
X199354Y614481D01*
X199004Y614131D01*
X194164D01*
X193534Y614761D01*
Y623863D01*
X194504Y624833D01*
G37*
G36*
G01Y658833D02*
X199198D01*
X199373Y658658D01*
Y652183D01*
G02X199172Y651983I-200J0D01*
G01X199164D01*
G03Y648979I0J-1502D01*
G01X199172D01*
G02X199373Y648779I1J-200D01*
G01Y648500D01*
X199004Y648131D01*
X194164D01*
X193534Y648761D01*
Y657863D01*
X194504Y658833D01*
G37*
G36*
G01X195071Y1578182D02*
G03I-574J0D01*
G37*
G36*
G01X207131D02*
G03I-574J0D01*
G37*
G36*
G01X199331D02*
G03I-574J0D01*
G37*
G36*
G01X195071Y1590094D02*
G03I-574J0D01*
G37*
G36*
G01X207131D02*
G03I-574J0D01*
G37*
G36*
G01X199331D02*
G03I-574J0D01*
G37*
G36*
G01X200371Y1614292D02*
G03I-574J0D01*
G37*
G36*
G01Y1602380D02*
G03I-574J0D01*
G37*
G36*
G01X204631Y1614292D02*
G03I-574J0D01*
G37*
G36*
G01Y1602380D02*
G03I-574J0D01*
G37*
G36*
G01X224617Y37103D02*
G03I-722J0D01*
G37*
G36*
G01X217530D02*
G03I-722J0D01*
G37*
G36*
G01X210444D02*
G03I-722J0D01*
G37*
G36*
G01X224607Y40017D02*
G03I-722J0D01*
G37*
G36*
G01X217520D02*
G03I-722J0D01*
G37*
G36*
G01X210434D02*
G03I-722J0D01*
G37*
G36*
G01X221764Y1016226D02*
X265436D01*
X267000Y1014662D01*
Y989662D01*
X266300Y988962D01*
X260972D01*
X260938Y988975D01*
G03X259944I-497J-1312D01*
G01X259910Y988962D01*
X252272D01*
X252238Y988975D01*
G03X251915Y989055I-496J-1311D01*
G02X251682Y989735I50J397D01*
G01X252629Y990683D01*
G03X252998Y991571I-887J889D01*
G01Y993734D01*
X253016Y993773D01*
G03X253143Y994357I-1275J583D01*
G03X250339I-1402J0D01*
G03X250466Y993773I1402J-1D01*
G01X250484Y993734D01*
Y992091D01*
X248602Y990209D01*
X248522Y990206D01*
G03X246907Y989086I53J-1801D01*
G01X246856Y988962D01*
X237907D01*
X237407Y989462D01*
Y992059D01*
X236200Y993266D01*
X226896D01*
X225951Y994211D01*
Y1000975D01*
X221000Y1005926D01*
Y1015462D01*
X221764Y1016226D01*
G37*
G36*
G01X234462Y1032058D02*
X245604D01*
X247165Y1030497D01*
X266165D01*
X267200Y1029462D01*
Y1017362D01*
X266521Y1016683D01*
X266395D01*
X265851Y1017228D01*
X221349D01*
X221033Y1016912D01*
X220577Y1017368D01*
Y1029491D01*
X221583Y1030497D01*
X232900D01*
X234462Y1032058D01*
G37*
G36*
G01X219191Y1578182D02*
G03I-574J0D01*
G37*
G36*
G01X211391D02*
G03I-574J0D01*
G37*
G36*
G01X223451D02*
G03I-574J0D01*
G37*
G36*
G01X219191Y1590094D02*
G03I-574J0D01*
G37*
G36*
G01X211391D02*
G03I-574J0D01*
G37*
G36*
G01X223451D02*
G03I-574J0D01*
G37*
G36*
G01X212431Y1614292D02*
G03I-574J0D01*
G37*
G36*
G01Y1602380D02*
G03I-574J0D01*
G37*
G36*
G01X224491Y1614292D02*
G03I-574J0D01*
G37*
G36*
G01X216691D02*
G03I-574J0D01*
G37*
G36*
G01X224491Y1602380D02*
G03I-574J0D01*
G37*
G36*
G01X216691D02*
G03I-574J0D01*
G37*
G36*
G01X231703Y37103D02*
G03I-722J0D01*
G37*
G36*
G01X236220Y42862D02*
X254870D01*
X255560Y42172D01*
Y36472D01*
X254950Y35862D01*
X239764D01*
Y37162D01*
G03X238063Y38864I-1702J0D01*
G03X236405Y37543I0J-1701D01*
G02X235732Y37350I-390J90D01*
G01X234220Y38862D01*
Y40862D01*
X236220Y42862D01*
G37*
G36*
G01X231693Y40017D02*
G03I-722J0D01*
G37*
G36*
G01X228177Y992195D02*
X235817D01*
X236406Y991606D01*
Y989047D01*
X236437Y989016D01*
Y988862D01*
X237137Y988162D01*
X237291D01*
X237492Y987960D01*
X246823D01*
X246869Y987825D01*
G03X250281I1706J580D01*
G01X250327Y987960D01*
X263202D01*
X263500Y987662D01*
Y980662D01*
X263250Y980412D01*
X245848D01*
X245586Y980673D01*
G03X244698Y981042I-889J-887D01*
G01X233208D01*
X231677Y982573D01*
X228149D01*
X227062Y983660D01*
Y991080D01*
X228177Y992195D01*
G37*
G36*
G01X231251Y1578182D02*
G03I-574J0D01*
G37*
G36*
G01X235511D02*
G03I-574J0D01*
G37*
G36*
G01X231251Y1590094D02*
G03I-574J0D01*
G37*
G36*
G01X235511D02*
G03I-574J0D01*
G37*
G36*
G01X228751Y1614292D02*
G03I-574J0D01*
G37*
G36*
G01X236551D02*
G03I-574J0D01*
G37*
G36*
G01X228751Y1602380D02*
G03I-574J0D01*
G37*
G36*
G01X236551D02*
G03I-574J0D01*
G37*
G36*
G01X240811D02*
G03I-574J0D01*
G37*
G36*
G01Y1614292D02*
G03I-574J0D01*
G37*
G36*
G01X255366Y34862D02*
X259720D01*
X262720Y31862D01*
Y28139D01*
X261443Y26862D01*
X248171D01*
X248152Y27041D01*
G03X246360Y28654I-1792J-189D01*
G03X245060Y28100I0J-1802D01*
G02X244488Y28094I-289J277D01*
G01X240720Y31862D01*
Y34362D01*
X241218Y34860D01*
X255365D01*
X255366Y34862D01*
G37*
G36*
G01X260920Y102462D02*
X283490D01*
X292050Y93902D01*
Y86523D01*
X292038Y86490D01*
G03X291950Y85983I1414J-507D01*
G03X292038Y85476I1502J0D01*
G01X292050Y85443D01*
Y83732D01*
X292310Y83472D01*
X292215Y83335D01*
G03X291950Y82483I1237J-852D01*
G03X293452Y80981I1502J0D01*
G03X294304Y81246I0J1502D01*
G01X294441Y81341D01*
X295190Y80592D01*
Y79920D01*
G02X294508Y79637I-400J0D01*
G03X293447Y80075I-1060J-1064D01*
G03Y77071I0J-1502D01*
G03X294508Y77509I1J1502D01*
G02X295190Y77226I282J-283D01*
G01Y72952D01*
X298830Y69312D01*
X307410D01*
X311310Y73212D01*
X315630D01*
X316820Y72022D01*
Y61672D01*
X315480Y60332D01*
X289285D01*
X289244Y60477D01*
G03X286356I-1444J-416D01*
G01X286315Y60332D01*
X284290D01*
X269220Y45262D01*
X248920D01*
X246120Y48062D01*
Y51562D01*
X248120Y53562D01*
X260120D01*
X261110Y54552D01*
Y82252D01*
X261270Y82412D01*
X258720Y84962D01*
Y100262D01*
X260920Y102462D01*
G37*
G36*
G01X246520Y82962D02*
X257620D01*
X259760Y80822D01*
Y54962D01*
X254520D01*
X252551Y56931D01*
Y67631D01*
X251233Y68949D01*
X251282Y69071D01*
G03X251387Y69623I-1397J552D01*
G03X249885Y71125I-1502J0D01*
G03X249333Y71020I0J-1502D01*
G01X249211Y70971D01*
X249020Y71162D01*
X246620D01*
X245720Y72062D01*
Y82162D01*
X246520Y82962D01*
G37*
G36*
G01X271990Y637300D02*
X279870D01*
X284310Y632860D01*
Y631190D01*
X284588Y630912D01*
X285075D01*
X285080Y630749D01*
G03X288084I1502J8D01*
G01X288089Y630912D01*
X289940D01*
X299020Y621832D01*
Y590003D01*
G02X298518Y589616I-400J0D01*
G03X298000Y589692I-518J-1727D01*
G03Y586088I0J-1802D01*
G03X298518Y586164I0J1803D01*
G02X299020Y585777I102J-387D01*
G01Y571717D01*
X298868Y571565D01*
X295881D01*
G03X293805Y572399I-2076J-2167D01*
G03X290803Y569397I0J-3002D01*
G03X291161Y567975I3003J0D01*
G03X290503Y565997I2644J-1978D01*
G03X293805Y562695I3302J0D01*
G03X297107Y565982I0J3302D01*
G01Y565999D01*
G03X296943Y567026I-3302J-1D01*
G02X297329Y567531I386J105D01*
G01X298868D01*
X299020Y567379D01*
Y561082D01*
X297300Y559362D01*
X249300D01*
X248518Y560144D01*
Y632086D01*
X249152Y632720D01*
X267410D01*
X271990Y637300D01*
G37*
G36*
G01X268630Y684060D02*
X284402D01*
X299000Y669462D01*
Y664986D01*
X299020Y664899D01*
Y642392D01*
X295610Y638982D01*
X295474Y639070D01*
G03X294658Y639311I-816J-1261D01*
G03X293156Y637809I0J-1502D01*
G03X293397Y636993I1502J0D01*
G01X293485Y636857D01*
X289840Y633212D01*
X286188D01*
X280790Y638610D01*
X271560D01*
X266940Y633990D01*
X249097D01*
X248518Y634569D01*
Y666086D01*
X249152Y666720D01*
X255900D01*
X266068Y676888D01*
G02X266750Y676605I282J-283D01*
G01Y673160D01*
G03X267152Y672758I402J0D01*
G01X273352D01*
G03X273754Y673160I0J402D01*
G01Y679360D01*
G03X273352Y679762I-402J0D01*
G01X267035D01*
Y682465D01*
X268630Y684060D01*
G37*
G36*
G01X266750Y697314D02*
G03X267152Y696912I402J0D01*
G01X273340D01*
Y693052D01*
X264900Y684612D01*
Y678112D01*
X256330Y669542D01*
X245480D01*
X244600Y670422D01*
Y695492D01*
X243552Y696540D01*
Y707524D01*
X244290Y708262D01*
X256657D01*
X258888Y706031D01*
X272671D01*
X273340Y705362D01*
Y703916D01*
X267152D01*
G03X266750Y703514I0J-402D01*
G01Y697314D01*
G37*
G36*
G01X243311Y1578182D02*
G03I-574J0D01*
G37*
G36*
G01X247571D02*
G03I-574J0D01*
G37*
G36*
G01X255371D02*
G03I-574J0D01*
G37*
G36*
G01X243311Y1590094D02*
G03I-574J0D01*
G37*
G36*
G01X247571D02*
G03I-574J0D01*
G37*
G36*
G01X255371D02*
G03I-574J0D01*
G37*
G36*
G01X248611Y1602380D02*
G03I-574J0D01*
G37*
G36*
G01Y1614292D02*
G03I-574J0D01*
G37*
G36*
G01X252871Y1602380D02*
G03I-574J0D01*
G37*
G36*
G01Y1614292D02*
G03I-574J0D01*
G37*
G36*
G01X267431Y1578182D02*
G03I-574J0D01*
G37*
G36*
G01X259631D02*
G03I-574J0D01*
G37*
G36*
G01X271691D02*
G03I-574J0D01*
G37*
G36*
G01X267431Y1590094D02*
G03I-574J0D01*
G37*
G36*
G01X259631D02*
G03I-574J0D01*
G37*
G36*
G01X271691D02*
G03I-574J0D01*
G37*
G36*
G01X260671Y1602380D02*
G03I-574J0D01*
G37*
G36*
G01Y1614292D02*
G03I-574J0D01*
G37*
G36*
G01X272731Y1602380D02*
G03I-574J0D01*
G37*
G36*
G01Y1614292D02*
G03I-574J0D01*
G37*
G36*
G01X264931D02*
G03I-574J0D01*
G37*
G36*
G01Y1602380D02*
G03I-574J0D01*
G37*
G36*
G01X281221Y140746D02*
G03I-534J0D01*
G37*
G36*
G01X288377Y727962D02*
G03I-557J0D01*
G37*
G36*
G01X279077Y738072D02*
G03I-557J0D01*
G37*
G36*
G01X274827Y746602D02*
G03I-557J0D01*
G37*
G36*
G01X289604Y760245D02*
G03I-557J0D01*
G37*
G36*
G01X279491Y1578182D02*
G03I-574J0D01*
G37*
G36*
G01X283751D02*
G03I-574J0D01*
G37*
G36*
G01X279491Y1590094D02*
G03I-574J0D01*
G37*
G36*
G01X283751D02*
G03I-574J0D01*
G37*
G36*
G01X284791Y1602380D02*
G03I-574J0D01*
G37*
G36*
G01Y1614292D02*
G03I-574J0D01*
G37*
G36*
G01X276991D02*
G03I-574J0D01*
G37*
G36*
G01Y1602380D02*
G03I-574J0D01*
G37*
G36*
G01X289051Y1614292D02*
G03I-574J0D01*
G37*
G36*
G01Y1602380D02*
G03I-574J0D01*
G37*
G36*
G01X303425Y141811D02*
G03I-534J0D01*
G37*
G36*
G01X304679Y178710D02*
X327591D01*
X329220Y177082D01*
Y166412D01*
X326970Y164162D01*
X304210D01*
X303840Y164532D01*
Y177872D01*
X304679Y178710D01*
G37*
G36*
G01X304140Y180192D02*
Y188712D01*
X291220Y201632D01*
Y226652D01*
X294110Y229542D01*
X311420D01*
X312100Y228862D01*
Y223632D01*
X316220Y219512D01*
X320200D01*
X321710Y218002D01*
Y213952D01*
X320510Y212752D01*
X316910D01*
X313990Y209832D01*
Y202312D01*
X317890Y198412D01*
X326010D01*
X329760Y194662D01*
Y181822D01*
X327650Y179712D01*
X304620D01*
X304140Y180192D01*
G37*
G36*
G01X290634Y739735D02*
G03I-557J0D01*
G37*
G36*
G01X291237Y745312D02*
G03I-557J0D01*
G37*
G36*
G01X565542Y1334559D02*
G02X565544Y1334527I-198J-28D01*
G01Y1315164D01*
G02X565498Y1315037I-200J1D01*
G01X565492Y1315030D01*
X565146Y1314684D01*
X565118Y1314655D01*
X565044Y1314625D01*
X528016D01*
G03X527874Y1314566I0J-200D01*
G01X526647Y1313339D01*
G03X526588Y1313197I141J-142D01*
G01Y1294130D01*
G02X526388Y1293930I-200J0D01*
G01X494323D01*
G03X494182Y1293871I1J-200D01*
G01X493028Y1292717D01*
G03X492970Y1292577I142J-141D01*
G01Y1281086D01*
G02X492933Y1280971I-200J1D01*
G01X492923Y1280956D01*
X492446Y1280479D01*
G02X492304Y1280420I-142J141D01*
G01X372697D01*
G02X372555Y1280479I0J200D01*
G01X371565Y1281469D01*
G02X371543Y1281495I141J142D01*
G01Y1281496D01*
G02X371506Y1281611I163J116D01*
G01Y1290011D01*
G03X371448Y1290151I-200J-1D01*
G01X367848Y1293751D01*
G03X367707Y1293810I-142J-141D01*
G01X333879D01*
G02X333679Y1294010I0J200D01*
G01Y1305865D01*
G03X333620Y1306007I-200J0D01*
G01X333138Y1306489D01*
G02X333108Y1306527I141J142D01*
G01X333084Y1306566D01*
G03X333055Y1306604I-172J-101D01*
G01X332836Y1306823D01*
G03X332694Y1306882I-142J-141D01*
G01X312033D01*
G02X311891Y1306941I0J200D01*
G01X311559Y1307273D01*
G02X311500Y1307415I141J142D01*
G01Y1310827D01*
G03X311441Y1310969I-200J0D01*
G01X310159Y1312251D01*
G03X309877I-141J-142D01*
G01Y1312250D01*
X306066Y1316061D01*
G03X305924Y1316120I-142J-141D01*
G01X303873D01*
G02X303731Y1316179I0J200D01*
G01X301997Y1317913D01*
G03X301855Y1317972I-142J-141D01*
G01X299738D01*
G02X299596Y1318031I0J200D01*
G01X298824Y1318803D01*
X298795Y1318831D01*
X298765Y1318905D01*
Y1349168D01*
G02X298822Y1349308I200J0D01*
G01X299508Y1349994D01*
G02X299510Y1349996I142J-140D01*
G02X299650Y1350053I140J-143D01*
G01X307464D01*
G03X307606Y1350112I0J200D01*
G01X308588Y1351094D01*
G03X308647Y1351236I-141J142D01*
G01Y1356832D01*
G02X308704Y1356972I200J0D01*
G01X310788Y1359056D01*
G02X310790Y1359058I142J-140D01*
G02X310930Y1359115I140J-143D01*
G01X317459D01*
X317566Y1359070D01*
G02X317629Y1359027I-79J-184D01*
G01X317765Y1358891D01*
G02X317767Y1358889I-140J-142D01*
G02X317824Y1358749I-143J-140D01*
G01Y1350393D01*
G03X317883Y1350251I200J0D01*
G01X318163Y1349971D01*
G03X318305Y1349912I142J141D01*
G01X332138D01*
X332149Y1349902D01*
X332156Y1349909D01*
X332765D01*
G02X332905Y1349852I0J-200D01*
G01X333240Y1349517D01*
G02X333242Y1349515I-140J-142D01*
G02X333299Y1349375I-143J-140D01*
G01Y1329736D01*
G03X333358Y1329594I200J0D01*
G01X335540Y1327412D01*
G03X335682Y1327353I142J141D01*
G01X339664D01*
G03X339806Y1327412I0J200D01*
G01X340588Y1328194D01*
G03X340647Y1328336I-141J142D01*
G01Y1333934D01*
G02X340704Y1334074I200J0D01*
G01X342644Y1336014D01*
G03X342686Y1336076I-142J141D01*
G01X342701Y1336111D01*
X342846Y1336256D01*
G02X342909Y1336299I142J-141D01*
G01X342915Y1336301D01*
G02X342993Y1336317I78J-184D01*
G01X349587D01*
X349694Y1336272D01*
G02X349757Y1336229I-79J-184D01*
G01X349893Y1336093D01*
G02X349895Y1336091I-140J-142D01*
G02X349952Y1335951I-143J-140D01*
G01Y1327595D01*
G03X350011Y1327453I200J0D01*
G01X350291Y1327173D01*
G03X350433Y1327114I142J141D01*
G01X364266D01*
X364277Y1327104D01*
X364284Y1327111D01*
X364893D01*
G02X365033Y1327054I0J-200D01*
G01X365368Y1326719D01*
G02X365370Y1326717I-140J-142D01*
G02X365427Y1326577I-143J-140D01*
G01Y1316536D01*
G03X365486Y1316394I200J0D01*
G01X367528Y1314352D01*
G03X367670Y1314293I142J141D01*
G01X373654D01*
G03X373796Y1314352I0J200D01*
G01X374738Y1315294D01*
G03X374797Y1315436I-141J142D01*
G01Y1322609D01*
X374842Y1322716D01*
G02X374885Y1322779I184J-79D01*
G01X374909Y1322803D01*
G02X374972Y1322846I142J-141D01*
G01X375079Y1322891D01*
X381715D01*
X381822Y1322846D01*
G02X381885Y1322803I-79J-184D01*
G01X382021Y1322667D01*
G02X382023Y1322665I-140J-142D01*
G02X382080Y1322525I-143J-140D01*
G01Y1314169D01*
G03X382139Y1314027I200J0D01*
G01X382419Y1313747D01*
G03X382561Y1313688I142J141D01*
G01X405755D01*
G03X405897Y1313747I0J200D01*
G01X406866Y1314716D01*
G03X406925Y1314858I-141J142D01*
G01Y1315729D01*
G02X406946Y1315818I200J0D01*
G03X407158Y1316713I-1790J897D01*
G03X406946Y1317608I-2002J-2D01*
G01X406925Y1317650D01*
Y1322609D01*
X406970Y1322716D01*
G02X407013Y1322779I184J-79D01*
G01X407037Y1322803D01*
G02X407100Y1322846I142J-141D01*
G01X407207Y1322891D01*
X413843D01*
X413950Y1322846D01*
G02X414013Y1322803I-79J-184D01*
G01X414149Y1322667D01*
G02X414151Y1322665I-140J-142D01*
G02X414208Y1322525I-143J-140D01*
G01Y1314169D01*
G03X414267Y1314027I200J0D01*
G01X414547Y1313747D01*
G03X414689Y1313688I142J141D01*
G01X428522D01*
X428533Y1313678D01*
X428540Y1313685D01*
X437880D01*
G03X438022Y1313744I0J200D01*
G01X438994Y1314716D01*
G03X439053Y1314858I-141J142D01*
G01Y1322609D01*
X439090Y1322697D01*
G02X439133Y1322761I184J-77D01*
G01X439183Y1322811D01*
G02X439247Y1322854I141J-141D01*
G01X439335Y1322891D01*
X445971D01*
X446078Y1322846D01*
G02X446141Y1322803I-79J-184D01*
G01X446277Y1322667D01*
G02X446279Y1322665I-140J-142D01*
G02X446336Y1322525I-143J-140D01*
G01Y1314169D01*
G03X446395Y1314027I200J0D01*
G01X446675Y1313747D01*
G03X446817Y1313688I142J141D01*
G01X460650D01*
X460661Y1313678D01*
X460668Y1313685D01*
X461728D01*
G02X461868Y1313628I0J-200D01*
G01X462854Y1312642D01*
G03X462996Y1312583I142J141D01*
G01X468906D01*
G03X469048Y1312642I0J200D01*
G01X471122Y1314716D01*
G03X471181Y1314858I-141J142D01*
G01Y1322525D01*
G02X471240Y1322667I200J0D01*
G01X471405Y1322832D01*
G02X471547Y1322891I142J-141D01*
G01X478099D01*
X478206Y1322846D01*
G02X478269Y1322803I-79J-184D01*
G01X478405Y1322667D01*
G02X478407Y1322665I-140J-142D01*
G02X478464Y1322525I-143J-140D01*
G01Y1314169D01*
G03X478523Y1314027I200J0D01*
G01X478803Y1313747D01*
G03X478945Y1313688I142J141D01*
G01X492778D01*
X492789Y1313678D01*
X492796Y1313685D01*
X493856D01*
G03X493998Y1313744I0J200D01*
G01X495042Y1314788D01*
G03X495101Y1314930I-141J142D01*
G01Y1327124D01*
G02X495158Y1327264I200J0D01*
G01X495388Y1327494D01*
G02X495390Y1327496I142J-140D01*
G02X495530Y1327553I140J-143D01*
G01X496960D01*
X496977Y1327550D01*
G03X497314Y1327522I334J1973D01*
G01X501013D01*
G03X501350Y1327550I3J2001D01*
G01X501367Y1327553D01*
X502578D01*
G03X502720Y1327612I0J200D01*
G01X503250Y1328142D01*
G03X503309Y1328284I-141J142D01*
G01Y1335753D01*
G02X503368Y1335895I200J0D01*
G01X503467Y1335994D01*
X503519Y1336021D01*
X503550Y1336027D01*
G03X504175Y1336271I-331J1771D01*
G01X504198Y1336285D01*
X504277Y1336309D01*
G02X504334Y1336317I56J-192D01*
G01X510227D01*
X510334Y1336272D01*
G02X510397Y1336229I-79J-184D01*
G01X510533Y1336093D01*
G02X510535Y1336091I-140J-142D01*
G02X510592Y1335951I-143J-140D01*
G01Y1327595D01*
G03X510651Y1327453I200J0D01*
G01X510931Y1327173D01*
G03X511073Y1327114I142J141D01*
G01X526382D01*
G03X526524Y1327173I0J200D01*
G01X527172Y1327821D01*
G03X527231Y1327963I-141J142D01*
G01Y1348472D01*
G02X527288Y1348612I200J0D01*
G01X527424Y1348748D01*
G02X527426Y1348750I142J-140D01*
G02X527566Y1348807I140J-143D01*
G01X530763D01*
G02X530903Y1348750I0J-200D01*
G01X530918Y1348735D01*
X530931Y1348748D01*
G02X531073Y1348807I142J-141D01*
G01X533162D01*
G03X533304Y1348866I0J200D01*
G01X535378Y1350940D01*
G03X535437Y1351082I-141J142D01*
G01Y1358833D01*
X535482Y1358940D01*
G02X535525Y1359003I184J-79D01*
G01X535549Y1359027D01*
G02X535612Y1359070I142J-141D01*
G01X535719Y1359115D01*
X542355D01*
X542462Y1359070D01*
G02X542525Y1359027I-79J-184D01*
G01X542661Y1358891D01*
G02X542663Y1358889I-140J-142D01*
G02X542720Y1358749I-143J-140D01*
G01Y1350393D01*
G03X542779Y1350251I200J0D01*
G01X543059Y1349971D01*
G03X543201Y1349912I142J141D01*
G01X560487D01*
G03X560629Y1349971I0J200D01*
G01X562141Y1351483D01*
G03X562200Y1351625I-141J142D01*
G01Y1378019D01*
G03X562141Y1378161I-200J0D01*
G01X560799Y1379503D01*
G03X560657Y1379562I-142J-141D01*
G01X501603D01*
G02X501461Y1379621I0J200D01*
G01X501440Y1379642D01*
X501367Y1379672D01*
X496873D01*
G02X496731Y1379731I0J200D01*
G01X493859Y1382603D01*
G02X493800Y1382745I141J142D01*
G01Y1423579D01*
G03X493741Y1423721I-200J0D01*
G01X489193Y1428269D01*
G03X489051Y1428328I-142J-141D01*
G01X475567D01*
G02X475425Y1428387I0J200D01*
G01X473766Y1430046D01*
G02X473707Y1430188I141J142D01*
G01Y1441552D01*
G02X473766Y1441694I200J0D01*
G01X475684Y1443612D01*
X524522D01*
G02X524727Y1442869I0J-400D01*
G03X523076Y1439952I1751J-2917D01*
G03X529880I3402J0D01*
G03X528229Y1442869I-3402J0D01*
G02X528434Y1443612I205J343D01*
G01X537337D01*
X575105Y1405844D01*
Y1346930D01*
G02X575046Y1346788I-200J0D01*
G01X565544Y1337286D01*
G03X565485Y1337144I141J-142D01*
G01Y1334669D01*
G02X565542Y1334559I-141J-143D01*
G37*
G36*
G01X291551Y1578182D02*
G03I-574J0D01*
G37*
G36*
G01X295811D02*
G03I-574J0D01*
G37*
G36*
G01X303611D02*
G03I-574J0D01*
G37*
G36*
G01X291551Y1590094D02*
G03I-574J0D01*
G37*
G36*
G01X295811D02*
G03I-574J0D01*
G37*
G36*
G01X303611D02*
G03I-574J0D01*
G37*
G36*
G01X296851Y1614292D02*
G03I-574J0D01*
G37*
G36*
G01Y1602380D02*
G03I-574J0D01*
G37*
G36*
G01X301111D02*
G03I-574J0D01*
G37*
G36*
G01Y1614292D02*
G03I-574J0D01*
G37*
G36*
G01X316954Y776125D02*
G03I-557J0D01*
G37*
G36*
G01X547659Y1097952D02*
G03X547272Y1097215I991J-991D01*
G01X547261D01*
G03X545859Y1095813I0J-1402D01*
G01X545846Y1095800D01*
G03X545268Y1095543I266J-1376D01*
G02X544960Y1095724I-108J168D01*
G03X544963Y1095813I-1399J92D01*
G03X543561Y1094411I-1402J0D01*
G01X543563D01*
G03X544064Y1094504I-1J1402D01*
G02X544605Y1094171I143J-373D01*
G03X544621Y1094057I1395J138D01*
G03X544691Y1093811I1377J259D01*
G03X544414Y1093594I719J-1203D01*
G01X539008D01*
G03X537014I-997J-987D01*
G01X535139D01*
G03X533481I-829J-987D01*
G01X531440D01*
G03X529782I-829J-987D01*
G01X527740D01*
G03X526082I-829J-987D01*
G01X524040D01*
G03X522382I-829J-987D01*
G01X520508D01*
G03X518514I-997J-987D01*
G01X516809D01*
G03X514815I-997J-987D01*
G01X513109D01*
G03X511115I-997J-987D01*
G01X509240D01*
G03X507582I-829J-987D01*
G01X505540D01*
G03X503882I-829J-987D01*
G01X501840D01*
G03X500182I-829J-987D01*
G01X498140D01*
G03X496482I-829J-987D01*
G01X494609D01*
G03X492615I-997J-987D01*
G01X490908D01*
G03X488914I-997J-987D01*
G01X487208D01*
G03X485214I-997J-987D01*
G01X483508D01*
G03X481516I-996J-988D01*
G01X479808D01*
G03X477816I-996J-988D01*
G01X476108D01*
G03X474116I-996J-988D01*
G01X472408D01*
G03X470416I-996J-988D01*
G01X468709D01*
G03X466715I-997J-987D01*
G01X465565D01*
G02X465004Y1093598I-278J287D01*
G03X464012Y1094009I-992J-992D01*
G03X462610Y1092607I0J-1402D01*
G03X463178Y1091480I1402J0D01*
G01Y1091095D01*
G02X462641Y1090720I-400J1D01*
G03X462161Y1090805I-481J-1317D01*
G03Y1088001I0J-1402D01*
G03X462641Y1088086I-1J1402D01*
G02X463178Y1087711I137J-376D01*
G01Y1087328D01*
G03Y1085072I834J-1128D01*
G01Y1084230D01*
X462850D01*
X462810Y1084239D01*
X462786Y1084251D01*
G03X462162Y1084397I-623J-1256D01*
G03X461538Y1084251I-1J-1402D01*
G01X461514Y1084239D01*
X461474Y1084230D01*
X459149D01*
X459109Y1084239D01*
X459085Y1084251D01*
G03X458461Y1084397I-623J-1256D01*
G03X457837Y1084251I-1J-1402D01*
G01X457813Y1084239D01*
X457773Y1084230D01*
X455450D01*
X455408Y1084240D01*
X455385Y1084251D01*
G03X454762Y1084397I-623J-1256D01*
G01X454760D01*
G03X453415Y1083391I0J-1402D01*
G01X453397Y1083330D01*
X453207Y1083181D01*
X453199D01*
X453131Y1083186D01*
G03X452623Y1083181I-221J-3395D01*
G02X452423Y1083333I-6J200D01*
G03X451062Y1084397I-1361J-338D01*
G01X451060D01*
G03X449715Y1083391I0J-1402D01*
G01X449697Y1083330D01*
X449507Y1083181D01*
X449499D01*
X449431Y1083186D01*
G03X448922Y1083181I-221J-3395D01*
G02X448722Y1083333I-6J200D01*
G03X447361Y1084397I-1361J-338D01*
G03X445959Y1082995I0J-1402D01*
G03X446363Y1082010I1403J0D01*
G01X446390Y1081983D01*
X446450Y1081841D01*
X446414Y1081728D01*
X446398Y1081704D01*
G03X445810Y1079851I2813J-1912D01*
G01Y1079731D01*
G03X446398Y1077878I3401J59D01*
G01X446414Y1077854D01*
X446450Y1077741D01*
X446390Y1077599D01*
X446363Y1077572D01*
G03X445998Y1076914I999J-984D01*
G03Y1076260I1362J-327D01*
G03X446363Y1075602I1364J326D01*
G01X446390Y1075575D01*
X446450Y1075433D01*
X446414Y1075320D01*
X446398Y1075296D01*
G03X445810Y1073443I2813J-1912D01*
G01Y1073271D01*
G03X446397Y1071469I3401J111D01*
G01X446414Y1071445D01*
X446449Y1071332D01*
X446389Y1071189D01*
X446388Y1071188D01*
G03X445959Y1070178I974J-1010D01*
G03X446363Y1069193I1403J0D01*
G01X446390Y1069166D01*
X446450Y1069024D01*
X446414Y1068911D01*
X446398Y1068887D01*
G03X445810Y1067034I2813J-1912D01*
G01Y1066974D01*
G02X445677Y1066726I-299J1D01*
G01X445664Y1066718D01*
G03X445660Y1066716I524J-1053D01*
G03X443960Y1063830I1701J-2946D01*
G01Y1063658D01*
G03X444090Y1062834I3401J114D01*
G03X445646Y1060831I3271J936D01*
G01X445649Y1060830D01*
G03X445660Y1060823I1832J2867D01*
G01X445661D01*
X445687Y1060808D01*
G02X445810Y1060565I-177J-242D01*
G03X446196Y1058992I3403J1D01*
G03X446399Y1058652I3018J1571D01*
G01X446415Y1058628D01*
X446450Y1058516D01*
X446390Y1058373D01*
X446389Y1058372D01*
G03X445959Y1057361I974J-1011D01*
G03X447361Y1055959I1402J0D01*
G03X447561Y1055973I2J1402D01*
G03X448706Y1056963I-200J1388D01*
G01X448724Y1057025D01*
X448916Y1057175D01*
X448924D01*
X448992Y1057170D01*
G03X449501Y1057175I221J3395D01*
G02X449701Y1057023I6J-200D01*
G03X451062Y1055959I1361J338D01*
G03X451456Y1056016I-2J1402D01*
G02X451681Y1055917I49J-194D01*
G03X451947Y1055449I3082J1442D01*
G01X451964Y1055425D01*
X452000Y1055311D01*
X451940Y1055169D01*
X451913Y1055142D01*
G03X451730Y1054912I999J-983D01*
G03X451555Y1054513I1181J-756D01*
G01X451549Y1054494D01*
X451357Y1054344D01*
X451281Y1054349D01*
X450842D01*
X450766Y1054344D01*
X450574Y1054494D01*
X450556Y1054555D01*
G03X449211Y1055559I-1345J-399D01*
G03X447809Y1054157I0J-1402D01*
G03X448213Y1053172I1403J0D01*
G01X448240Y1053145D01*
X448300Y1053003D01*
X448264Y1052890D01*
X448255Y1052876D01*
G03X447985Y1052406I2807J-1925D01*
G01X447981Y1052398D01*
G02X447976Y1052389I-177J93D01*
G01X447963Y1052370D01*
G02X447749Y1052299I-159J121D01*
G03X447361Y1052354I-389J-1347D01*
G03Y1049550I0J-1402D01*
G01X447362D01*
G03X447756Y1049607I-2J1402D01*
G02X447981Y1049508I49J-194D01*
G03X448247Y1049040I3082J1442D01*
G01X448264Y1049016D01*
X448299Y1048903D01*
X448239Y1048760D01*
X448238Y1048759D01*
G03X447809Y1047749I974J-1010D01*
G03X449211Y1046347I1402J0D01*
G03X449605Y1046404I-2J1402D01*
G02X449833Y1046299I49J-194D01*
G03X449853Y1046258I3067J1471D01*
G03X450114Y1045812I3058J1490D01*
G02X450089Y1045554I-164J-114D01*
G03X449659Y1044544I971J-1010D01*
G03X451061Y1043142I1402J0D01*
G01X451062D01*
G03X451456Y1043199I-2J1402D01*
G02X451683Y1043097I49J-194D01*
G03X451752Y1042958I3081J1443D01*
G03X451964Y1042608I3011J1584D01*
G01X452000Y1042494D01*
X451940Y1042352D01*
X451913Y1042325D01*
G03X451509Y1041340I999J-985D01*
G03X452911Y1039938I1402J0D01*
G01X452913D01*
G03X453617Y1040128I-1J1402D01*
G01X453618Y1040129D01*
X453665Y1040156D01*
X453772Y1040157D01*
X454120Y1039958D01*
G02X454198Y1039877I-100J-174D01*
G01X454203Y1039866D01*
G02X454220Y1039786I-183J-81D01*
G01Y1039500D01*
X454186Y1039444D01*
X454153Y1039400D01*
X454141Y1039394D01*
X454112Y1039379D01*
G03Y1036893I650J-1243D01*
G01X454141Y1036878D01*
X454153Y1036872D01*
X454186Y1036828D01*
X454220Y1036772D01*
Y1025058D01*
G02X454162Y1024917I-200J0D01*
G01X452642Y1023397D01*
G03X452583Y1023255I141J-142D01*
G01Y1016532D01*
X452608Y1016506D01*
Y1016500D01*
X453827Y1015281D01*
X453909Y1015248D01*
X461412D01*
X461485Y1015218D01*
X461502Y1015201D01*
Y1014449D01*
G02X461444Y1014308I-200J0D01*
G01X461244Y1014108D01*
G02X461103Y1014050I-141J142D01*
G01X455473D01*
G03X455331Y1013991I0J-200D01*
G01X455183Y1013843D01*
X455143D01*
X454279Y1012979D01*
G03X454220Y1012837I141J-142D01*
G01Y1011803D01*
G02X454162Y1011662I-200J0D01*
G01X452844Y1010344D01*
G03X452788Y1010235I141J-141D01*
G01X452777Y1010188D01*
X452623Y1010034D01*
G03X452564Y1009892I141J-142D01*
G01Y1006268D01*
G03X452623Y1006126I200J0D01*
G01X452785Y1005964D01*
Y1005950D01*
X453484Y1005251D01*
X453581Y1005210D01*
X454709D01*
G03X454839Y1005258I0J200D01*
G01X455095Y1005478D01*
G03X455106Y1005488I-129J153D01*
G01X455204Y1005586D01*
G02X455345Y1005644I141J-142D01*
G01X474475D01*
X474516Y1005603D01*
Y999887D01*
G02X474465Y999754I-200J0D01*
G01X474420Y999708D01*
X474142Y999430D01*
G02X474018Y999373I-141J142D01*
G01X474008Y999372D01*
X468661D01*
G02X468531Y999430I11J200D01*
G01X468414Y999547D01*
G02X468356Y999688I142J141D01*
G01Y1000532D01*
G03X468297Y1000674I-200J0D01*
G01X468178Y1000793D01*
Y1000833D01*
X468053Y1000958D01*
X467740Y1001270D01*
X467430Y1001580D01*
X467425D01*
X467305Y1001700D01*
X467271D01*
X467123Y1001849D01*
G03X466981Y1001908I-142J-141D01*
G01X462859D01*
G03X462717Y1001849I0J-200D01*
G01X462628Y1001759D01*
G02X462486Y1001700I-142J141D01*
G01X462388D01*
G03X462246Y1001641I0J-200D01*
G01X461684Y1001079D01*
G03X461625Y1000937I141J-142D01*
G01Y1000756D01*
X461614Y1000745D01*
Y999988D01*
G02X461556Y999847I-200J0D01*
G01X461126Y999417D01*
G02X460985Y999359I-141J142D01*
G01X455644D01*
X455636Y999352D01*
X455373D01*
G03X455231Y999293I0J-200D01*
G01X452683Y996744D01*
G03X452624Y996602I141J-142D01*
G01Y992148D01*
X452665Y992046D01*
Y991903D01*
G03X452724Y991761I200J0D01*
G01X453082Y991403D01*
G03X453224Y991344I142J141D01*
G01X453300D01*
G02X453440Y991287I0J-200D01*
G01X453530Y991197D01*
G03X453672Y991138I142J141D01*
G01X455631D01*
X455651Y991158D01*
X474406D01*
G02X474606Y990958I0J-200D01*
G01Y985945D01*
G02X474548Y985804I-200J0D01*
G01X474547Y985803D01*
X473779Y985036D01*
X473735Y984994D01*
G02X473602Y984942I-134J148D01*
G01X468842D01*
X468837Y984943D01*
G02X468711Y985000I14J200D01*
G01X468124Y985587D01*
G02X468066Y985728I142J141D01*
G01Y986428D01*
G03X468007Y986570I-200J0D01*
G01X467304Y987273D01*
G03X467162Y987332I-142J-141D01*
G01X462793D01*
G03X462654Y987276I0J-200D01*
G01X462626Y987249D01*
X462555Y987220D01*
X462198D01*
G03X462056Y987161I0J-200D01*
G01X461724Y986829D01*
G03X461665Y986687I141J-142D01*
G01Y986370D01*
G02X461607Y986229I-200J0D01*
G01X461584Y986206D01*
Y985458D01*
G02X461526Y985317I-200J0D01*
G01X461126Y984917D01*
G02X460985Y984859I-141J142D01*
G01X454769D01*
G03X454627Y984800I0J-200D01*
G01X452594Y982767D01*
G03X452535Y982635I141J-142D01*
G01X452529Y982570D01*
X452473Y982514D01*
G03X452414Y982372I141J-142D01*
G01Y977998D01*
G03X452473Y977856I200J0D01*
G01X452477Y977852D01*
G02X452502Y977822I-141J-143D01*
G01X452506Y977814D01*
G02X452535Y977711I-171J-104D01*
G01Y977703D01*
G03X452594Y977561I200J0D01*
G01X453126Y977029D01*
G03X453268Y976970I142J141D01*
G01X453315D01*
X453390Y976938D01*
X455886D01*
Y976940D01*
X467850D01*
G02X467992Y976881I0J-200D01*
G01X468007Y976866D01*
X468037Y976793D01*
Y973491D01*
G02X467979Y973350I-200J0D01*
G01X467568Y972939D01*
X467403D01*
X467374Y972968D01*
X463289D01*
G03X463147Y972909I0J-200D01*
G01X463108Y972869D01*
G02X462966Y972810I-142J141D01*
G01X462945D01*
X462164Y972029D01*
G03X462105Y971901I141J-142D01*
G01X462103Y971877D01*
X462064Y971782D01*
Y970788D01*
G02X462006Y970647I-200J0D01*
G01X461770Y970411D01*
G02X461629Y970353I-141J142D01*
G01X455021D01*
G03X454879Y970294I0J-200D01*
G01X452714Y968129D01*
G03X452655Y967987I141J-142D01*
G01Y967949D01*
G02X452597Y967808I-200J0D01*
G01X452595Y967806D01*
G03X452536Y967664I141J-142D01*
G01Y963044D01*
G03X452595Y962902I200J0D01*
G01X452598Y962899D01*
G02X452655Y962759I-143J-140D01*
G01Y962671D01*
G03X452714Y962529I200J0D01*
G01X453246Y961997D01*
G03X453388Y961938I142J141D01*
G01X453477D01*
G02X453615Y961882I-1J-200D01*
G01X453640Y961856D01*
X455028D01*
G03X455170Y961914I1J200D01*
G01X455543Y962287D01*
G02X455663Y962341I137J-145D01*
G01X455673Y962342D01*
X474290D01*
G02X474490Y962142I0J-200D01*
G01Y959136D01*
G03X474549Y958994I200J0D01*
G01X474633Y958911D01*
G02X474692Y958769I-141J-142D01*
G01Y956006D01*
G02X474634Y955865I-200J0D01*
G01X474397Y955628D01*
G02X474256Y955570I-141J142D01*
G01X468768D01*
G02X468627Y955628I0J200D01*
G01X468215Y956040D01*
G02X468157Y956181I142J141D01*
G01Y957095D01*
G03X468098Y957237I-200J0D01*
G01X467185Y958150D01*
X467181D01*
X467070Y958261D01*
G03X466928Y958320I-142J-141D01*
G01X462742D01*
G03X462600Y958261I0J-200D01*
G01X462547Y958208D01*
G02X462406Y958150I-141J142D01*
G01X462388D01*
G03X462246Y958091I0J-200D01*
G01X461704Y957549D01*
G03X461645Y957407I141J-142D01*
G01Y957389D01*
G02X461587Y957248I-200J0D01*
G01X461583Y957244D01*
G03X461524Y957102I141J-142D01*
G01Y956348D01*
G02X461466Y956207I-200J0D01*
G01X461203Y955944D01*
G02X461062Y955886I-141J142D01*
G01X453728D01*
G03X453586Y955827I0J-200D01*
G01X452503Y954744D01*
G03X452444Y954602I141J-142D01*
G01Y948308D01*
G03X452503Y948166I200J0D01*
G01X452557Y948112D01*
G02X452582Y948082I-141J-143D01*
G01X452586Y948074D01*
G02X452615Y947971I-171J-104D01*
G01Y947962D01*
X453176Y947401D01*
G03X453327Y947342I142J141D01*
G01X453334Y947335D01*
G03X453483Y947268I149J133D01*
G01X455096D01*
G03X455239Y947328I0J200D01*
G01X455253Y947342D01*
X455257D01*
X455425Y947510D01*
G02X455555Y947568I141J-142D01*
G01X467720D01*
X468020Y947268D01*
Y944670D01*
X467620Y944270D01*
X461468D01*
G03X461326Y944211I0J-200D01*
G01X460754Y943639D01*
G03X460695Y943497I141J-142D01*
G01Y943394D01*
G02X460637Y943253I-200J0D01*
G01X460601Y943217D01*
G03X460542Y943075I141J-142D01*
G01Y937766D01*
X460511Y937693D01*
X460486Y937668D01*
X452127D01*
G02X451986Y937726I0J200D01*
G01X449859Y939853D01*
G03X449717Y939912I-142J-141D01*
G01X448548D01*
G02X448383Y939999I0J200D01*
G01X448198Y940295D01*
G02X448189Y940312I172J102D01*
G01Y940485D01*
X448207Y940524D01*
G03X448331Y941100I-1278J576D01*
G01Y941101D01*
G03X445527I-1402J0D01*
G03X445669Y940487I1402J1D01*
G01Y940486D01*
G02X445662Y940299I-180J-87D01*
G01X445474Y939999D01*
G02X445310Y939912I-165J113D01*
G01X428178D01*
G02X428037Y939970I0J200D01*
G01X428036Y939971D01*
X427079Y940927D01*
X427078Y940928D01*
G02X427020Y941069I142J141D01*
G01Y944557D01*
G02X427077Y944697I200J0D01*
G01X428806Y946426D01*
G03X428865Y946568I-141J142D01*
G01Y950327D01*
G03X428806Y950469I-200J0D01*
G01X428214Y951061D01*
G03X428072Y951120I-142J-141D01*
G01X427806D01*
X427733Y951150D01*
X427711Y951172D01*
X421999D01*
X421872Y951120D01*
X421203D01*
G03X421061Y951061I0J-200D01*
G01X420300Y950300D01*
G02X420159Y950242I-141J142D01*
G01X412621D01*
G02X412450Y950339I1J200D01*
G01X412276Y950661D01*
G02X412255Y950752I179J89D01*
G01X412286Y950859D01*
X412299Y950880D01*
G03X412368Y951135I-432J254D01*
G01Y955135D01*
G03X411867Y955636I-501J0D01*
G01X409737D01*
G02X409595Y955695I0J200D01*
G01X409459Y955831D01*
G03X409339Y955889I-142J-141D01*
G01X409310Y955892D01*
X409240Y955922D01*
X406846D01*
X406841Y955923D01*
G02X406715Y955980I14J200D01*
G01X406373Y956322D01*
G02X406315Y956463I142J141D01*
G01Y962027D01*
G02X406365Y962160I200J1D01*
G01X406370Y962165D01*
G02X406373Y962168I143J-140D01*
G01X406641Y962436D01*
G02X406767Y962493I140J-143D01*
G01X406772Y962494D01*
X425134D01*
X425139Y962493D01*
G02X425262Y962439I-14J-200D01*
G01X425822Y961878D01*
G03X425964Y961820I141J142D01*
G01X427608D01*
G03X427750Y961879I0J200D01*
G01X427777Y961906D01*
G02X427917Y961963I140J-143D01*
G01X427952D01*
X428025Y961993D01*
X428683Y962652D01*
X428655Y962680D01*
Y962701D01*
G02X428713Y962842I200J0D01*
G01X428734Y962863D01*
X428764Y962936D01*
Y967190D01*
G03X428706Y967332I-200J1D01*
G01X427926Y968112D01*
X427925D01*
X425521Y970515D01*
G03X425379Y970574I-142J-141D01*
G01X419664D01*
G02X419523Y970632I0J200D01*
G01X419407Y970748D01*
G02X419349Y970889I142J141D01*
G01Y971885D01*
G03X419290Y972027I-200J0D01*
G01X418576Y972741D01*
G03X418434Y972800I-142J-141D01*
G01X413618D01*
X413545Y972831D01*
X413536Y972840D01*
Y976750D01*
G02X413594Y976890I200J-1D01*
G01X413605Y976901D01*
X413678Y976932D01*
X425268D01*
G02X425408Y976875I0J-200D01*
G01X425950Y976333D01*
G03X426092Y976274I142J141D01*
G01X426216D01*
X426289Y976244D01*
X426297Y976236D01*
X427564D01*
X427637Y976266D01*
X427656Y976274D01*
X427802D01*
G03X427944Y976333I0J200D01*
G01X428516Y976905D01*
G03X428575Y977047I-141J142D01*
G01Y977121D01*
G02X428632Y977261I200J0D01*
G01X428636Y977265D01*
Y981212D01*
G03X428577Y981354I-200J0D01*
G01X427016Y982915D01*
G02X426958Y983056I142J141D01*
G01Y984217D01*
G03X426899Y984359I-200J0D01*
G01X426323Y984935D01*
G03X426181Y984994I-142J-141D01*
G01X419698D01*
G02X419557Y985052I0J200D01*
G01X419514Y985095D01*
G02X419456Y985236I142J141D01*
G01Y986255D01*
X419442Y986269D01*
Y986480D01*
G03X419383Y986622I-200J0D01*
G01X418914Y987091D01*
G03X418772Y987150I-142J-141D01*
G01X418644D01*
G02X418503Y987208I0J200D01*
G01X418446Y987265D01*
G03X418304Y987324I-142J-141D01*
G01X414286D01*
G03X414144Y987265I0J-200D01*
G01X413313Y986434D01*
G03X413254Y986292I141J-142D01*
G01Y985318D01*
G02X413196Y985177I-200J0D01*
G01X413071Y985052D01*
G02X412930Y984994I-141J142D01*
G01X407036D01*
G02X406895Y985052I0J200D01*
G01X406840Y985107D01*
G02X406782Y985248I142J141D01*
G01Y991178D01*
G02X406841Y991320I200J0D01*
G01X406865Y991344D01*
X425371D01*
G02X425511Y991287I0J-200D01*
G01X426009Y990789D01*
G03X426151Y990730I142J141D01*
G01X426288D01*
G02X426428Y990673I0J-200D01*
G01X426442Y990659D01*
G03X426584Y990600I142J141D01*
G01X427548D01*
G03X427690Y990659I0J200D01*
G01X427704Y990673D01*
G02X427844Y990730I140J-143D01*
G01X427912D01*
G03X428054Y990789I0J200D01*
G01X428656Y991391D01*
G03X428715Y991533I-141J142D01*
G01Y995358D01*
G03X428656Y995500I-200J0D01*
G01X427104Y997052D01*
G02X427046Y997193I142J141D01*
G01Y998152D01*
G03X426987Y998294I-200J0D01*
G01X425896Y999385D01*
X425894Y999386D01*
X425821Y999416D01*
X419858D01*
G02X419717Y999474I0J200D01*
G01X419541Y999650D01*
G02X419483Y999791I142J141D01*
G01Y1000999D01*
G03X419424Y1001141I-200J0D01*
G01X418914Y1001651D01*
G03X418772Y1001710I-142J-141D01*
G01X418434D01*
X418361Y1001741D01*
X418340Y1001762D01*
X414373D01*
X414252Y1001711D01*
X414231Y1001707D01*
G03X414126Y1001651I37J-197D01*
G01X413374Y1000899D01*
G03X413315Y1000757I141J-142D01*
G01Y999623D01*
G02X413257Y999482I-200J0D01*
G01X413135Y999360D01*
G02X413005Y999302I-141J142D01*
G01X409496D01*
G02X409355Y999360I0J200D01*
G01X409313Y999402D01*
G02X409255Y999543I142J141D01*
G01Y1000507D01*
G02X409312Y1000647I200J0D01*
G01X409358Y1000693D01*
G02X409498Y1000750I140J-143D01*
G01X411835D01*
X411864Y1000778D01*
X412386D01*
G03X412586Y1000978I0J200D01*
G01Y1001501D01*
X412595Y1001510D01*
Y1005154D01*
G02X412652Y1005294I200J0D01*
G01X412865Y1005507D01*
G02X413005Y1005564I140J-143D01*
G01X425484D01*
G02X425609Y1005520I0J-200D01*
G01X425617Y1005514D01*
G02X425624Y1005507I-138J-145D01*
G01X425937Y1005193D01*
G03X426079Y1005134I142J141D01*
G01X426186D01*
G02X426323Y1005076I-4J-200D01*
G01X426383Y1005015D01*
G03X426525Y1004957I141J142D01*
G01X427822D01*
G03X427964Y1005016I0J200D01*
G01X428776Y1005828D01*
G03X428835Y1005970I-141J142D01*
G01Y1010122D01*
G03X428776Y1010264I-200J0D01*
G01X428666Y1010374D01*
Y1010406D01*
X427178Y1011894D01*
G02X427120Y1012035I142J141D01*
G01Y1012737D01*
G03X427061Y1012879I-200J0D01*
G01X426178Y1013762D01*
X426169D01*
X426079Y1013853D01*
G03X425937Y1013912I-142J-141D01*
G01X420326D01*
G02X420126Y1014112I0J200D01*
G01Y1014918D01*
G02X420326Y1015118I200J0D01*
G01X426018D01*
G03X426160Y1015177I0J200D01*
G01X426878Y1015895D01*
G03X426936Y1016037I-142J141D01*
G01Y1016202D01*
G02X426993Y1016342I200J0D01*
G01X428657Y1018006D01*
G03X428716Y1018148I-141J142D01*
G01Y1022562D01*
G03X428669Y1022691I-200J0D01*
G01X428635Y1022736D01*
Y1022997D01*
G03X428576Y1023139I-200J0D01*
G01X426878Y1024837D01*
G02X426820Y1024978I142J141D01*
G01Y1029637D01*
G03X426761Y1029779I-200J0D01*
G01X425929Y1030611D01*
G03X425787Y1030670I-142J-141D01*
G01X425468D01*
X425395Y1030700D01*
X425379Y1030716D01*
X417957D01*
G02X417816Y1030774I0J200D01*
G01X417278Y1031312D01*
G02X417220Y1031453I142J141D01*
G01Y1036637D01*
G02X417277Y1036777I200J0D01*
G01X418291Y1037791D01*
G02X418348Y1037831I142J-141D01*
G01X422152Y1039367D01*
G03X422244Y1039443I-75J185D01*
G01X422616Y1040011D01*
X422749Y1040054D01*
X422815Y1040029D01*
G03X423312Y1039938I497J1312D01*
G03X424704Y1041169I0J1403D01*
G01X424710Y1041218D01*
G03X424715Y1041340I-1398J118D01*
G03X424315Y1042321I-1403J0D01*
G01X424304Y1042333D01*
G02X424290Y1042570I154J128D01*
G01X424570Y1042997D01*
X424668Y1043146D01*
X424783Y1043193D01*
X424846Y1043178D01*
G03X425166Y1043142I316J1366D01*
G01X425167D01*
G03X426564Y1044544I-5J1402D01*
G03X426283Y1045386I-1402J0D01*
G01X426263Y1045413D01*
X426243Y1045473D01*
Y1045597D01*
G02X426323Y1045757I200J0D01*
G01X427070Y1046320D01*
G02X427163Y1046355I115J-164D01*
G01X427164D01*
G03X428403Y1047582I-153J1394D01*
G03X428262Y1048383I-1393J168D01*
G01X428240Y1048426D01*
Y1048617D01*
G02X428274Y1048662I175J-97D01*
G01X429185Y1049573D01*
X429228Y1049598D01*
X429253Y1049605D01*
G03X430209Y1050561I-391J1347D01*
G01X430216Y1050586D01*
X430241Y1050629D01*
X430508Y1050896D01*
G02X430698Y1050949I142J-141D01*
G01X431046Y1050842D01*
X431183Y1050691D01*
X431194Y1050640D01*
G03X432561Y1049550I1367J312D01*
G03X433963Y1050952I0J1402D01*
G03X432824Y1052329I-1402J0D01*
G01X432769Y1052340D01*
X432687Y1052413D01*
X432565Y1052814D01*
G02X432617Y1053005I194J50D01*
G01X432627Y1053015D01*
X432666Y1053109D01*
X432981Y1053228D01*
X433137Y1053287D01*
G02X433357Y1053233I71J-187D01*
G01X433358Y1053232D01*
G03X434411Y1052755I1053J924D01*
G03Y1055559I0J1402D01*
G03X433358Y1055082I0J-1401D01*
G01X433357Y1055081D01*
G02X433137Y1055027I-149J133D01*
G01X432786Y1055159D01*
G02X432657Y1055346I71J187D01*
G01Y1055787D01*
G02X432814Y1055982I200J0D01*
G03X433963Y1057361I-253J1379D01*
G03X432615Y1058762I-1402J0D01*
G01X432576Y1058764D01*
X432509Y1058793D01*
X431846Y1059456D01*
G02X431828Y1059718I142J141D01*
G03X432113Y1060565I-1116J847D01*
G03X429309I-1402J0D01*
G03X429369Y1060160I1402J1D01*
G01X429383Y1060114D01*
X429366Y1060021D01*
X429353Y1060004D01*
X429146Y1059726D01*
G02X428986Y1059645I-161J119D01*
G01X428736D01*
G02X428576Y1059726I1J200D01*
G01X428369Y1060004D01*
X428356Y1060021D01*
X428339Y1060114D01*
X428353Y1060160D01*
G03X428413Y1060565I-1342J406D01*
G03X427011Y1061967I-1402J0D01*
G03X426624Y1061912I2J-1402D01*
G02X426388Y1062020I-55J192D01*
G03X426279Y1062231I-3076J-1456D01*
G03X426269Y1062248I-2937J-1716D01*
G02X426243Y1062346I174J99D01*
G01Y1062808D01*
G02X426274Y1062914I200J-1D01*
G03Y1064626I-1111J856D01*
G02X426243Y1064732I169J107D01*
G01Y1065210D01*
G02X426314Y1065362I200J-1D01*
G01X426562Y1065563D01*
G02X426688Y1065606I124J-157D01*
G01X426719Y1065603D01*
X426720D01*
X426730Y1065600D01*
G03X427011Y1065572I279J1374D01*
G03Y1068376I0J1402D01*
G03X426725Y1068347I-2J-1402D01*
G01X426679Y1068337D01*
X426594Y1068358D01*
X426317Y1068583D01*
G02X426243Y1068738I126J155D01*
G01Y1069216D01*
G02X426274Y1069322I200J-1D01*
G03Y1071034I-1111J856D01*
G02X426243Y1071140I169J107D01*
G01Y1071619D01*
G02X426314Y1071771I200J-1D01*
G01X426562Y1071972D01*
G02X426688Y1072015I124J-157D01*
G01X426719Y1072012D01*
X426720D01*
X426730Y1072009D01*
G03X427011Y1071981I279J1374D01*
G03Y1074785I0J1402D01*
G03X426725Y1074756I-2J-1402D01*
G01X426679Y1074746D01*
X426594Y1074767D01*
X426317Y1074992D01*
G02X426243Y1075147I126J155D01*
G01Y1075625D01*
G02X426274Y1075731I200J-1D01*
G03X426565Y1076586I-1111J855D01*
G01Y1076587D01*
G03X426246Y1077477I-1403J-1D01*
G01X426242Y1077481D01*
X426236Y1077488D01*
G03X426063Y1077661I-1074J-901D01*
G01X426056Y1077667D01*
X424660Y1079063D01*
G02X424656Y1079067I139J143D01*
G01X424655Y1079068D01*
G02X424616Y1079277I147J136D01*
G03X424713Y1079788I-1305J512D01*
G01Y1079791D01*
G03X423311Y1081193I-1402J0D01*
G01X423308D01*
G03X422797Y1081096I1J-1402D01*
G02X422582Y1081141I-73J186D01*
G01X422366Y1081357D01*
G02X422308Y1081505I142J141D01*
G01X422319Y1081838D01*
X422354Y1081912D01*
X422386Y1081940D01*
G03X422864Y1082995I-925J1055D01*
G03X421462Y1084397I-1402J0D01*
G03X420407Y1083919I0J-1403D01*
G01X420379Y1083887D01*
X420305Y1083852D01*
X419972Y1083841D01*
G02X419824Y1083899I-7J200D01*
G01X419498Y1084225D01*
G02X419448Y1084307I141J142D01*
G01X419445Y1084318D01*
G02X419449Y1084428I195J48D01*
G01X419573Y1084774D01*
X419739Y1084905D01*
X419793Y1084912D01*
G03X420654Y1085422I-181J1288D01*
G01X422272D01*
G03X423311Y1084902I1039J778D01*
G03Y1087498I0J1298D01*
G03X422272Y1086978I0J-1298D01*
G01X420654D01*
G03X419611Y1087501I-1043J-779D01*
G03X418323Y1086382I0J-1301D01*
G01X418316Y1086328D01*
X418185Y1086162D01*
X417839Y1086038D01*
G02X417729Y1086034I-62J191D01*
G01X417718Y1086037D01*
G02X417636Y1086087I60J191D01*
G01X417340Y1086383D01*
G02X417285Y1086485I141J142D01*
G03X416914Y1087181I-1373J-285D01*
G03X416188Y1087575I-1002J-981D01*
G02X416096Y1087627I49J194D01*
G01X415169Y1088554D01*
X415152Y1088689D01*
X415186Y1088748D01*
G03X415363Y1089402I-1124J655D01*
G01Y1089404D01*
G03X414106Y1090704I-1301J0D01*
G01X414066Y1090705D01*
X413997Y1090736D01*
X413923Y1090812D01*
X413776Y1090965D01*
G02X413720Y1091104I144J139D01*
G01Y1094012D01*
G02X413772Y1094146I200J0D01*
G01X413873Y1094251D01*
X413970Y1094351D01*
G02X414103Y1094412I144J-139D01*
G01X414107D01*
G03Y1097214I-46J1401D01*
G01X414103D01*
G02X413970Y1097275I11J200D01*
G01X413873Y1097375D01*
X413772Y1097480D01*
G02X413720Y1097614I148J134D01*
G01Y1100420D01*
G02X413770Y1100552I200J0D01*
G01X413980Y1100769D01*
G02X414103Y1100820I134J-149D01*
G01X414107D01*
G03X414246Y1103611I-44J1401D01*
G01X414149Y1103624D01*
X413720Y1104366D01*
Y1106829D01*
G02X413772Y1106963I200J0D01*
G01X413873Y1107068D01*
X413970Y1107168D01*
G02X414103Y1107229I144J-139D01*
G01X414107D01*
G03Y1110031I-45J1401D01*
G01X414103D01*
G02X413970Y1110092I11J200D01*
G01X413873Y1110192D01*
X413772Y1110297D01*
G02X413720Y1110431I148J134D01*
G01Y1113239D01*
G02X413772Y1113373I200J-1D01*
G01X413810Y1113412D01*
G02X414127Y1113373I144J-139D01*
G01X414717Y1112350D01*
X414687Y1112263D01*
G03X414614Y1111834I1224J-429D01*
G03X417208I1297J0D01*
G03X416154Y1113109I-1298J0D01*
G01X416064Y1113126D01*
X415320Y1114413D01*
X415358Y1114504D01*
G03X414107Y1116440I-1296J535D01*
G01X414103D01*
G02X413980Y1116491I11J200D01*
G01X413770Y1116708D01*
G02X413720Y1116840I150J132D01*
G01Y1119646D01*
G02X413772Y1119780I200J0D01*
G01X413873Y1119885D01*
X413970Y1119985D01*
G02X414103Y1120046I144J-139D01*
G01X414107D01*
G03Y1122848I-46J1401D01*
G01X414103D01*
G02X413970Y1122909I11J200D01*
G01X413873Y1123009D01*
X413772Y1123114D01*
G02X413720Y1123248I148J134D01*
G01Y1124955D01*
G02X413777Y1125095I200J0D01*
G01X413875Y1125195D01*
X413977Y1125299D01*
G02X414108Y1125355I139J-144D01*
G01X414112D01*
G03X416564Y1127856I-49J2501D01*
G01Y1129823D01*
X416651Y1129988D01*
G03X417214Y1131056I-739J1072D01*
G01X417320Y1131257D01*
X417155Y1131447D01*
G03X416471Y1132236I-1243J-387D01*
G01X416366Y1132357D01*
G03X415498Y1133913I-4153J-1297D01*
G02X415451Y1134071I151J131D01*
G03X415464Y1134264I-1389J191D01*
G03X414582Y1135566I-1402J0D01*
G02X414579Y1135567I62J191D01*
G02X414478Y1135675I85J181D01*
G03X414401Y1135884I-4120J-1399D01*
G03X414347Y1136013I-4040J-1616D01*
G02X414361Y1136188I186J73D01*
G03X414714Y1137469I-2149J1281D01*
G01Y1139738D01*
G02X414790Y1139895I200J0D01*
G03X415363Y1140973I-728J1078D01*
G03X414800Y1142045I-1302J0D01*
G01X414786Y1142054D01*
G02X414714Y1142208I128J154D01*
G01Y1142592D01*
G03X413981Y1144361I-2501J0D01*
G01X408662Y1149680D01*
G03X406895Y1150412I-1768J-1769D01*
G01X399386D01*
G02X399245Y1150470I0J200D01*
G01X397972Y1151744D01*
G03X396205Y1152476I-1768J-1769D01*
G01X318456D01*
G02X318314Y1152535I0J200D01*
G01X311366Y1159483D01*
G02X311308Y1159624I142J141D01*
G01Y1303670D01*
X312120Y1304482D01*
X326470D01*
X327869Y1305880D01*
X331421D01*
X332078Y1305224D01*
Y1293788D01*
G03X332137Y1293646I200J0D01*
G01X332916Y1292867D01*
G03X333058Y1292808I142J141D01*
G01X367292D01*
G02X367433Y1292750I0J-200D01*
G01X370447Y1289736D01*
G02X370476Y1289698I-143J-139D01*
G02X370504Y1289609I-171J-103D01*
G01Y1281610D01*
G03X370505Y1281580I1201J25D01*
G01Y1281196D01*
G03X370564Y1281054I200J0D01*
G01X370841Y1280777D01*
G03X370857Y1280760I883J815D01*
G01X371846Y1279771D01*
G03X371863Y1279755I832J867D01*
G01X372141Y1279477D01*
G03X372283Y1279418I142J141D01*
G01X492718D01*
G03X492860Y1279477I0J200D01*
G01X493138Y1279755D01*
G03X493155Y1279771I-815J883D01*
G01X493701Y1280318D01*
X493912Y1280529D01*
G03X493971Y1280671I-141J142D01*
G01Y1281055D01*
G03X493972Y1281085I-1200J55D01*
G01Y1292181D01*
G02X494019Y1292291I199J-20D01*
G01X494600Y1292873D01*
G02X494738Y1292928I138J-145D01*
G01X527023D01*
G03X527165Y1292987I0J200D01*
G01X528407Y1294229D01*
G03X528466Y1294371I-141J142D01*
G01Y1304399D01*
X528487Y1304420D01*
Y1312333D01*
G02X528544Y1312473I200J0D01*
G01X529592Y1313521D01*
G02X529732Y1313578I140J-143D01*
G01X563341D01*
G02X563481Y1313521I0J-200D01*
G01X564920Y1312082D01*
G02X564977Y1311942I-143J-140D01*
G01Y1115270D01*
X547659Y1097952D01*
G37*
G36*
G01X343898Y1391728D02*
X378864D01*
X378967Y1391708D01*
X398211Y1372464D01*
G03X398353Y1372405I142J141D01*
G01X442543D01*
X454400Y1384262D01*
X485000D01*
X491200Y1378062D01*
X559810D01*
X560690Y1377182D01*
Y1352082D01*
X559520Y1350912D01*
X558130D01*
X558100Y1350942D01*
X555680D01*
X555660Y1350923D01*
X544053D01*
X543950Y1350943D01*
X543823Y1351070D01*
Y1363758D01*
X543843Y1363861D01*
X545335Y1365353D01*
X550027D01*
G03X550169Y1365412I0J200D01*
G01X551188Y1366431D01*
G03X551247Y1366573I-141J142D01*
G01Y1371175D01*
G03X551188Y1371317I-200J0D01*
G01X549294Y1373212D01*
G03X549152Y1373271I-142J-141D01*
G01X527408D01*
G03X527266Y1373212I0J-200D01*
G01X525968Y1371915D01*
G03X525909Y1371773I141J-142D01*
G01Y1333105D01*
X525907Y1333104D01*
Y1332637D01*
X525909Y1332635D01*
Y1328504D01*
X525853Y1328360D01*
X525618Y1328125D01*
X511925D01*
X511822Y1328145D01*
X511695Y1328272D01*
Y1340960D01*
X511715Y1341063D01*
X512523Y1341871D01*
X516327D01*
G03X516469Y1341930I0J200D01*
G01X519063Y1344524D01*
G03X519122Y1344666I-141J142D01*
G01Y1350229D01*
G03X519063Y1350371I-200J0D01*
G01X517940Y1351494D01*
G03X517798Y1351553I-142J-141D01*
G01X498430D01*
G03X498288Y1351494I0J-200D01*
G01X493840Y1347046D01*
G03X493781Y1346904I141J-142D01*
G01Y1344598D01*
X493695Y1344516D01*
G03X493255Y1343454I1062J-1062D01*
G01Y1340893D01*
G03X493695Y1339831I1502J0D01*
G01X493781Y1339748D01*
Y1319679D01*
X493779Y1319678D01*
Y1319211D01*
X493781Y1319209D01*
Y1315078D01*
X493725Y1314934D01*
X493490Y1314699D01*
X479797D01*
X479694Y1314719D01*
X479567Y1314846D01*
Y1327534D01*
X479587Y1327637D01*
X480729Y1328779D01*
X484628D01*
G03X484770Y1328838I0J200D01*
G01X485546Y1329614D01*
X486159D01*
G03X486301Y1329673I0J200D01*
G01X487169Y1330541D01*
G03X487228Y1330683I-141J142D01*
G01Y1331296D01*
X487247Y1331315D01*
Y1336918D01*
G03X487188Y1337060I-200J0D01*
G01X487121Y1337127D01*
X486053Y1338194D01*
G03X485911Y1338253I-142J-141D01*
G01X465122D01*
G03X464980Y1338194I0J-200D01*
G01X462902Y1336116D01*
G03X462843Y1335974I141J-142D01*
G01Y1330832D01*
X462823Y1330729D01*
X461712Y1329618D01*
G03X461653Y1329476I141J-142D01*
G01Y1319679D01*
X461651Y1319678D01*
Y1319211D01*
X461653Y1319209D01*
Y1315078D01*
X461597Y1314934D01*
X461362Y1314699D01*
X447669D01*
X447566Y1314719D01*
X447439Y1314846D01*
Y1326236D01*
X447459Y1326339D01*
X450310Y1329190D01*
X454827D01*
G03X454969Y1329249I0J200D01*
G01X455788Y1330068D01*
G03X455847Y1330210I-141J142D01*
G01Y1336950D01*
G03X455788Y1337092I-200J0D01*
G01X454946Y1337934D01*
G03X454804Y1337993I-142J-141D01*
G01X431130D01*
G03X430988Y1337934I0J-200D01*
G01X429584Y1336530D01*
G03X429525Y1336388I141J-142D01*
G01Y1319679D01*
X429523Y1319678D01*
Y1319211D01*
X429525Y1319209D01*
Y1315078D01*
X429469Y1314934D01*
X429234Y1314699D01*
X415541D01*
X415438Y1314719D01*
X415311Y1314846D01*
Y1326091D01*
X415331Y1326194D01*
X418190Y1329053D01*
X422910D01*
G03X423052Y1329112I0J200D01*
G01X424034Y1330094D01*
G03X424093Y1330236I-141J142D01*
G01Y1336973D01*
G03X424034Y1337115I-200J0D01*
G01X423592Y1337557D01*
X423547D01*
X423110Y1337994D01*
G03X422968Y1338053I-142J-141D01*
G01X399830D01*
G03X399688Y1337994I0J-200D01*
G01X397456Y1335762D01*
G03X397397Y1335620I141J-142D01*
G01Y1319679D01*
X397395Y1319678D01*
Y1319211D01*
X397397Y1319209D01*
Y1315078D01*
X397341Y1314934D01*
X397106Y1314699D01*
X383413D01*
X383310Y1314719D01*
X383183Y1314846D01*
Y1326642D01*
X383203Y1326745D01*
X385647Y1329189D01*
X391000D01*
G03X391142Y1329248I0J200D01*
G01X391694Y1329800D01*
G03X391753Y1329942I-141J142D01*
G01Y1335370D01*
G03X391694Y1335512I-200J0D01*
G01X390959Y1336247D01*
G03X390817Y1336306I-142J-141D01*
G01X373770D01*
X373667Y1336326D01*
X372166Y1337827D01*
G03X372024Y1337886I-142J-141D01*
G01X369725D01*
G03X369583Y1337827I0J-200D01*
G01X365328Y1333572D01*
G03X365269Y1333430I141J-142D01*
G01Y1333105D01*
X365267Y1333104D01*
Y1332637D01*
X365269Y1332635D01*
Y1328458D01*
X365249Y1328355D01*
X365019Y1328125D01*
X351285D01*
X351182Y1328145D01*
X351055Y1328272D01*
Y1339840D01*
X351075Y1339943D01*
X353747Y1342615D01*
X358447D01*
G03X358523Y1342630I0J200D01*
G01X358929Y1342802D01*
X358940Y1342805D01*
G03X359024Y1342855I-57J192D01*
G01X359431Y1343262D01*
G03X359481Y1343346I-142J141D01*
G01X359484Y1343357D01*
X359656Y1343763D01*
G03X359671Y1343839I-185J76D01*
G01Y1349346D01*
G03X359612Y1349488I-200J0D01*
G01X358006Y1351094D01*
G03X357864Y1351153I-142J-141D01*
G01X340854D01*
X340751Y1351173D01*
X339651Y1352273D01*
G03X339509Y1352332I-142J-141D01*
G01X337925D01*
G03X337783Y1352273I0J-200D01*
G01X336663Y1351153D01*
X319610D01*
X319507Y1351173D01*
X318927Y1351753D01*
Y1362310D01*
X318947Y1362413D01*
X321947Y1365413D01*
X326320D01*
G03X326386Y1365425I-2J200D01*
G01X326418Y1365436D01*
X327147D01*
G03X327289Y1365495I0J200D01*
G01X327588Y1365794D01*
G03X327647Y1365936I-141J142D01*
G01Y1371049D01*
X327798Y1371099D01*
X327805Y1371101D01*
G03X343895Y1391531I-5305J20729D01*
G01X343898Y1391728D01*
G37*
G36*
G01X317070Y1372855D02*
X325340D01*
G02X325482Y1372796I0J-200D01*
G01X326260Y1372018D01*
G02X326319Y1371876I-141J-142D01*
G01Y1367085D01*
G02X326260Y1366943I-200J0D01*
G01X326078Y1366761D01*
G02X325936Y1366702I-142J141D01*
G01X320693D01*
G02X320551Y1366761I0J200D01*
G01X318823Y1368489D01*
G03X318681Y1368548I-142J-141D01*
G01X317407D01*
G02X317265Y1368607I0J200D01*
G01X316536Y1369336D01*
G02X316477Y1369478I141J142D01*
G01Y1371821D01*
X316495Y1371860D01*
G03X316623Y1372412I-1274J586D01*
G01X316624Y1372451D01*
X316653Y1372521D01*
X316928Y1372796D01*
G02X317070Y1372855I142J-141D01*
G37*
G36*
G01X315671Y1578182D02*
G03I-574J0D01*
G37*
G36*
G01X307871D02*
G03I-574J0D01*
G37*
G36*
G01X319931D02*
G03I-574J0D01*
G37*
G36*
G01X315671Y1590094D02*
G03I-574J0D01*
G37*
G36*
G01X307871D02*
G03I-574J0D01*
G37*
G36*
G01X319931D02*
G03I-574J0D01*
G37*
G36*
G01X308911Y1602380D02*
G03I-574J0D01*
G37*
G36*
G01Y1614292D02*
G03I-574J0D01*
G37*
G36*
G01X320971D02*
G03I-574J0D01*
G37*
G36*
G01X313171D02*
G03I-574J0D01*
G37*
G36*
G01X320971Y1602380D02*
G03I-574J0D01*
G37*
G36*
G01X313171D02*
G03I-574J0D01*
G37*
G36*
G01X345079Y988550D02*
X384729D01*
X388872Y984407D01*
G02X388824Y983800I-282J-283D01*
G03X388290Y982756I754J-1044D01*
G03X389440Y981476I1287J0D01*
G01X389619Y981457D01*
Y977646D01*
X389441Y977627D01*
G03Y975067I138J-1280D01*
G01X389619Y975048D01*
Y971238D01*
X389440Y971219D01*
G03Y968659I137J-1280D01*
G01X389619Y968640D01*
Y964829D01*
X389440Y964810D01*
G03Y962250I137J-1280D01*
G01X389619Y962231D01*
Y958421D01*
X389440Y958402D01*
G03Y955842I137J-1280D01*
G01X389619Y955823D01*
Y952012D01*
X389440Y951993D01*
G03Y949433I137J-1280D01*
G01X389619Y949414D01*
Y945603D01*
X389440Y945584D01*
G03Y943024I137J-1280D01*
G01X389619Y943005D01*
Y941570D01*
X389553Y941504D01*
G02X388905Y941624I-283J283D01*
G03X387729Y942388I-1176J-523D01*
G03X386442Y941100I0J-1287D01*
G03X386576Y940528I1288J0D01*
G02X386217Y939950I-358J-178D01*
G01X381841D01*
G02X381482Y940528I-1J400D01*
G03X381616Y941100I-1154J572D01*
G03X379042I-1287J0D01*
G03X379176Y940528I1288J0D01*
G02X378817Y939950I-358J-178D01*
G01X378141D01*
G02X377782Y940528I-1J400D01*
G03X377916Y941100I-1154J572D01*
G03X375342I-1287J0D01*
G03X375476Y940528I1288J0D01*
G02X375117Y939950I-358J-178D01*
G01X370741D01*
G02X370382Y940528I-1J400D01*
G03X370516Y941100I-1154J572D01*
G03X367942I-1287J0D01*
G03X368076Y940528I1288J0D01*
G02X367717Y939950I-358J-178D01*
G01X363341D01*
G02X362982Y940528I-1J400D01*
G03X363116Y941100I-1154J572D01*
G03X360542I-1287J0D01*
G03X360676Y940528I1288J0D01*
G02X360317Y939950I-358J-178D01*
G01X355941D01*
G02X355582Y940528I-1J400D01*
G03X355716Y941100I-1154J572D01*
G03X353142I-1287J0D01*
G03X353276Y940528I1288J0D01*
G02X352917Y939950I-358J-178D01*
G01X352241D01*
G02X351882Y940528I-1J400D01*
G03X352016Y941100I-1154J572D01*
G03X349442I-1287J0D01*
G03X349576Y940528I1288J0D01*
G02X349217Y939950I-358J-178D01*
G01X344679D01*
X335869Y948760D01*
X328289D01*
X325719Y951330D01*
Y969190D01*
X328436Y971908D01*
X328572D01*
G03X329602Y972334I1J1456D01*
G01X338563Y981295D01*
G03X338990Y982325I-1029J1030D01*
G01Y982460D01*
X345079Y988550D01*
G37*
G36*
G01X391313Y1137340D02*
X392411D01*
X392446Y1137184D01*
G03X393470Y1136194I1266J285D01*
G01X393560Y1136177D01*
X394229Y1135019D01*
Y1132858D01*
G02X393803Y1132459I-400J0D01*
G03X393711Y1132462I-92J-1399D01*
G03Y1129658I0J-1402D01*
G03X393803Y1129661I0J1402D01*
G02X394229Y1129262I26J-399D01*
G01Y1128294D01*
X394220Y1128266D01*
G03X394159Y1127856I1341J-409D01*
G03X394220Y1127446I1402J-1D01*
G01X394229Y1127418D01*
Y1126344D01*
G02X393801Y1125945I-400J0D01*
G03X393711Y1125948I-88J-1294D01*
G03X392414Y1124651I0J-1297D01*
G03X393469Y1123376I1298J0D01*
G01X393559Y1123359D01*
X394229Y1122199D01*
Y1120020D01*
X394479Y1119770D01*
X394252Y1119542D01*
X394136Y1119579D01*
G03X393711Y1119645I-425J-1335D01*
G03Y1116841I0J-1402D01*
G03X395112Y1118188I0J1402D01*
G02X395794Y1118455I400J-16D01*
G01X396007Y1118242D01*
X396011Y1118166D01*
G03X397334Y1116843I1400J77D01*
G01X397410Y1116839D01*
X398311Y1115938D01*
X398211Y1115800D01*
G03X397964Y1115039I1051J-762D01*
G03X399262Y1113742I1297J0D01*
G03X400023Y1113988I1J1297D01*
G01X400161Y1114088D01*
X400621Y1113628D01*
G02X400520Y1112989I-283J-283D01*
G03X399814Y1111834I592J-1155D01*
G03X400869Y1110559I1298J0D01*
G01X400959Y1110542D01*
X401767Y1109143D01*
X401737Y1109057D01*
G03X401664Y1108630I1225J-429D01*
G03X404260I1298J0D01*
G03X403202Y1109905I-1297J0D01*
G01X403112Y1109922D01*
X402305Y1111319D01*
X402336Y1111406D01*
G03X402357Y1111473I-1227J421D01*
G01X402371Y1111522D01*
X402549Y1111700D01*
X405293Y1108956D01*
X405277Y1108854D01*
G03X405259Y1108630I1385J-224D01*
G03X406108Y1107342I1401J0D01*
G01X406229Y1107290D01*
Y1106914D01*
G02X405603Y1106583I-400J-1D01*
G03X404812Y1106828I-792J-1157D01*
G03Y1104024I0J-1402D01*
G03X405603Y1104269I-1J1402D01*
G02X406229Y1103938I226J-330D01*
G01Y1103561D01*
X406108Y1103509D01*
G03Y1100933I552J-1288D01*
G01X406229Y1100881D01*
Y1099794D01*
X405854D01*
X405794Y1099864D01*
G03X404811Y1100314I-982J-847D01*
G03Y1097720I0J-1297D01*
G03X405794Y1098170I1J1297D01*
G01X405854Y1098240D01*
X406229D01*
Y1097153D01*
X406108Y1097101D01*
G03Y1094525I554J-1288D01*
G01X406229Y1094473D01*
Y1090634D01*
X406114Y1090580D01*
G03X405364Y1089404I547J-1176D01*
G03X405398Y1089110I1298J1D01*
G02X405009Y1088620I-390J-90D01*
G01X404311D01*
X404155Y1088889D01*
X404186Y1088976D01*
G03X404258Y1089404I-1225J426D01*
G03X401664I-1297J0D01*
G03X401697Y1089110I1297J-3D01*
G02X401308Y1088620I-390J-90D01*
G01X401023D01*
G02X400632Y1089105I0J400D01*
G03X400664Y1089404I-1370J298D01*
G03X397860I-1402J0D01*
G03X397892Y1089105I1402J-1D01*
G02X397501Y1088620I-391J-85D01*
G01X397205D01*
G02X396816Y1089111I0J400D01*
G03X396850Y1089404I-1245J293D01*
G03X394274I-1288J0D01*
G03X394308Y1089111I1279J0D01*
G02X393919Y1088620I-389J-91D01*
G01X393623D01*
G02X393232Y1089105I0J400D01*
G03X393264Y1089404I-1370J298D01*
G03X390460I-1402J0D01*
G03X390492Y1089105I1402J-1D01*
G02X390101Y1088620I-391J-85D01*
G01X389805D01*
G02X389416Y1089111I0J400D01*
G03X389450Y1089404I-1245J293D01*
G03X386874I-1288J0D01*
G03X386908Y1089111I1279J0D01*
G02X386519Y1088620I-389J-91D01*
G01X386222D01*
G02X385831Y1089105I0J400D01*
G03X385863Y1089404I-1370J298D01*
G03X383059I-1402J0D01*
G03X383091Y1089105I1402J-1D01*
G02X382700Y1088620I-391J-85D01*
G01X382405D01*
G02X382016Y1089111I0J400D01*
G03X382050Y1089404I-1245J293D01*
G03X379474I-1288J0D01*
G03X379508Y1089111I1279J0D01*
G02X379119Y1088620I-389J-91D01*
G01X378705D01*
G02X378316Y1089111I0J400D01*
G03X378350Y1089404I-1245J293D01*
G03X375774I-1288J0D01*
G03X375808Y1089111I1279J0D01*
G02X375419Y1088620I-389J-91D01*
G01X375123D01*
G02X374732Y1089105I0J400D01*
G03X374764Y1089404I-1370J298D01*
G03X371960I-1402J0D01*
G03X371992Y1089105I1402J-1D01*
G02X371601Y1088620I-391J-85D01*
G01X371305D01*
G02X370916Y1089111I0J400D01*
G03X370950Y1089404I-1245J293D01*
G03X368374I-1288J0D01*
G03X368408Y1089111I1279J0D01*
G02X368019Y1088620I-389J-91D01*
G01X367723D01*
G02X367332Y1089105I0J400D01*
G03X367364Y1089404I-1370J298D01*
G03X364560I-1402J0D01*
G03X364592Y1089105I1402J-1D01*
G02X364201Y1088620I-391J-85D01*
G01X363905D01*
G02X363516Y1089111I0J400D01*
G03X363550Y1089404I-1245J293D01*
G03X360974I-1288J0D01*
G03X361008Y1089111I1279J0D01*
G02X360619Y1088620I-389J-91D01*
G01X360322D01*
G02X359931Y1089105I0J400D01*
G03X359963Y1089404I-1370J298D01*
G03X357159I-1402J0D01*
G03X357191Y1089105I1402J-1D01*
G02X356800Y1088620I-391J-85D01*
G01X356504D01*
G02X356115Y1089111I0J400D01*
G03X356148Y1089404I-1254J290D01*
G03X353574I-1287J0D01*
G03X353607Y1089111I1287J-3D01*
G02X353218Y1088620I-389J-91D01*
G01X352804D01*
G02X352415Y1089111I0J400D01*
G03X352448Y1089404I-1254J290D01*
G03X349874I-1287J0D01*
G03X349907Y1089111I1287J-3D01*
G02X349518Y1088620I-389J-91D01*
G01X349222D01*
G02X348831Y1089105I0J400D01*
G03X348863Y1089404I-1370J298D01*
G03X346059I-1402J0D01*
G03X346091Y1089105I1402J-1D01*
G02X345700Y1088620I-391J-85D01*
G01X337669D01*
X333599Y1092690D01*
Y1096090D01*
G02X334298Y1096356I400J0D01*
G03X335344Y1095887I1046J932D01*
G03Y1098691I0J1402D01*
G03X334298Y1098222I0J-1401D01*
G02X333599Y1098488I-299J266D01*
G01Y1137340D01*
X344206D01*
X344239Y1137181D01*
G03X346983I1372J288D01*
G01X347016Y1137340D01*
X348011D01*
X348046Y1137184D01*
G03X349070Y1136194I1266J285D01*
G01X349160Y1136177D01*
X349967Y1134779D01*
X349936Y1134693D01*
G03X349864Y1134264I1225J-426D01*
G03X352458I1297J0D01*
G03X351403Y1135539I-1298J0D01*
G01X351313Y1135556D01*
X350506Y1136954D01*
X350537Y1137040D01*
G03X350578Y1137184I-1226J427D01*
G01X350613Y1137340D01*
X351606D01*
X351639Y1137181D01*
G03X354383I1372J288D01*
G01X354416Y1137340D01*
X355411D01*
X355446Y1137184D01*
G03X356470Y1136194I1266J285D01*
G01X356560Y1136177D01*
X357367Y1134779D01*
X357336Y1134693D01*
G03X357264Y1134264I1225J-426D01*
G03X359858I1297J0D01*
G03X358803Y1135539I-1298J0D01*
G01X358713Y1135556D01*
X357906Y1136954D01*
X357937Y1137040D01*
G03X357978Y1137184I-1226J427D01*
G01X358013Y1137340D01*
X359111D01*
X359146Y1137184D01*
G03X361678I1266J286D01*
G01X361713Y1137340D01*
X362811D01*
X362846Y1137184D01*
G03X363870Y1136194I1266J285D01*
G01X363960Y1136177D01*
X364768Y1134779D01*
X364737Y1134692D01*
G03X364664Y1134264I1225J-429D01*
G03X367260I1298J0D01*
G03X366204Y1135539I-1298J0D01*
G01X366114Y1135556D01*
X365306Y1136954D01*
X365337Y1137041D01*
G03X365378Y1137184I-1225J429D01*
G01X365413Y1137340D01*
X366511D01*
X366546Y1137184D01*
G03X369078I1266J286D01*
G01X369113Y1137340D01*
X370211D01*
X370246Y1137184D01*
G03X371270Y1136194I1266J285D01*
G01X371360Y1136177D01*
X372168Y1134779D01*
X372137Y1134692D01*
G03X372064Y1134264I1225J-429D01*
G03X374660I1298J0D01*
G03X373604Y1135539I-1298J0D01*
G01X373514Y1135556D01*
X372706Y1136954D01*
X372737Y1137041D01*
G03X372778Y1137184I-1225J429D01*
G01X372813Y1137340D01*
X373911D01*
X373946Y1137184D01*
G03X376478I1266J286D01*
G01X376513Y1137340D01*
X377611D01*
X377646Y1137184D01*
G03X378670Y1136194I1266J285D01*
G01X378760Y1136177D01*
X379568Y1134779D01*
X379537Y1134692D01*
G03X379464Y1134264I1225J-429D01*
G03X382060I1298J0D01*
G03X381004Y1135539I-1298J0D01*
G01X380914Y1135556D01*
X380106Y1136954D01*
X380137Y1137041D01*
G03X380178Y1137184I-1225J429D01*
G01X380213Y1137340D01*
X381311D01*
X381346Y1137184D01*
G03X383878I1266J286D01*
G01X383913Y1137340D01*
X385011D01*
X385046Y1137184D01*
G03X386070Y1136194I1266J285D01*
G01X386160Y1136177D01*
X386968Y1134779D01*
X386937Y1134692D01*
G03X386864Y1134264I1225J-429D01*
G03X389460I1298J0D01*
G03X388404Y1135539I-1298J0D01*
G01X388314Y1135556D01*
X387506Y1136954D01*
X387537Y1137041D01*
G03X387578Y1137184I-1225J429D01*
G01X387613Y1137340D01*
X388711D01*
X388746Y1137184D01*
G03X391278I1266J286D01*
G01X391313Y1137340D01*
G37*
G36*
G01X327731Y1578182D02*
G03I-574J0D01*
G37*
G36*
G01X331991D02*
G03I-574J0D01*
G37*
G36*
G01X327731Y1590094D02*
G03I-574J0D01*
G37*
G36*
G01X331991D02*
G03I-574J0D01*
G37*
G36*
G01X325231Y1602380D02*
G03I-574J0D01*
G37*
G36*
G01X333031D02*
G03I-574J0D01*
G37*
G36*
G01X325231Y1614292D02*
G03I-574J0D01*
G37*
G36*
G01X333031D02*
G03I-574J0D01*
G37*
G36*
G01X337291Y1602380D02*
G03I-574J0D01*
G37*
G36*
G01Y1614292D02*
G03I-574J0D01*
G37*
G36*
G01X386674Y853430D02*
X388620D01*
G03X389580Y853083I960J1154D01*
G03X390482Y853384I0J1502D01*
G01X390621Y853489D01*
X390786Y853324D01*
G02X390698Y852692I-283J-283D01*
G03X389928Y851381I731J-1311D01*
G03X391430Y849879I1502J0D01*
G03X392741Y850649I0J1501D01*
G02X393373Y850737I349J-195D01*
G01X394803Y849307D01*
Y846235D01*
X394673Y846186D01*
G03X393830Y844971I454J-1215D01*
G03X393941Y844444I1297J-2D01*
G01X393980Y844356D01*
X393139Y842761D01*
X393044Y842743D01*
G03X391982Y841467I236J-1276D01*
G03X393279Y840170I1297J0D01*
G03X394426Y840861I0J1297D01*
G01X394483Y840967D01*
X394803D01*
Y840325D01*
X398107Y837021D01*
Y823915D01*
X399037Y822985D01*
X411077D01*
X412010Y823918D01*
Y836212D01*
X413710Y837912D01*
X423354D01*
X423818Y837448D01*
Y785809D01*
X421939Y783930D01*
X375819D01*
X374219Y785530D01*
Y822640D01*
X360759Y836100D01*
X357549D01*
X352959Y840690D01*
Y843652D01*
G02X353611Y843963I400J0D01*
G03X354427Y843674I816J1008D01*
G03X355724Y844971I0J1297D01*
G03X354669Y846246I-1298J0D01*
G01X354579Y846263D01*
X353772Y847661D01*
X353803Y847747D01*
G03X353876Y848176I-1224J429D01*
G03X353771Y848685I-1298J-2D01*
G01X353718Y848809D01*
X355015Y850106D01*
X355045Y850120D01*
G03X355325Y850302I-619J1258D01*
G01X357085D01*
G03X358130Y849879I1045J1079D01*
G03X359453Y850670I0J1502D01*
G01X360507D01*
G03X361830Y849879I1323J711D01*
G03X363332Y851381I0J1502D01*
G03X363127Y852137I-1502J-1D01*
G01X364336Y853346D01*
X364361Y853360D01*
G03X364474Y853430I-681J1226D01*
G01X366420D01*
G03X368340I960J1154D01*
G01X370284D01*
G03X371874I795J1156D01*
G01X373820D01*
G03X375740I960J1154D01*
G01X377684D01*
G03X379274I795J1156D01*
G01X381220D01*
G03X383140I960J1154D01*
G01X385084D01*
G03X386674I795J1156D01*
G37*
G36*
G01X393081Y861339D02*
G02X393278Y861391I197J-347D01*
G02X393477Y861338I1J-398D01*
G03X395091Y860895I1653J2859D01*
G02X395486Y860495I-5J-400D01*
G01Y859962D01*
X394977Y859081D01*
X394887Y859064D01*
G03X393832Y857789I243J-1275D01*
G03X394379Y856730I1297J-1D01*
G02X394431Y856121I-231J-326D01*
G01X393989Y855679D01*
X393860Y855744D01*
G03X393520Y855859I-582J-1160D01*
G01X393430Y855876D01*
X392623Y857274D01*
X392654Y857360D01*
G03X392726Y857789I-1225J426D01*
G03X390132I-1297J0D01*
G03X391187Y856514I1298J0D01*
G01X391277Y856497D01*
X391598Y855941D01*
G02X391252Y855341I-346J-200D01*
G01X390759D01*
G03X388399I-1180J-757D01*
G01X386932D01*
G03X386120Y855859I-1054J-757D01*
G01X386030Y855876D01*
X385223Y857274D01*
X385254Y857360D01*
G03X385326Y857789I-1225J426D01*
G03X382732I-1297J0D01*
G03X383787Y856514I1298J0D01*
G01X383877Y856497D01*
X384198Y855941D01*
G02X383852Y855341I-346J-200D01*
G01X383359D01*
G03X380999I-1180J-757D01*
G01X379532D01*
G03X378720Y855859I-1054J-757D01*
G01X378630Y855876D01*
X377823Y857274D01*
X377854Y857360D01*
G03X377926Y857789I-1225J426D01*
G03X375332I-1297J0D01*
G03X376387Y856514I1298J0D01*
G01X376477Y856497D01*
X376798Y855941D01*
G02X376452Y855341I-346J-200D01*
G01X375959D01*
G03X373599I-1180J-757D01*
G01X372132D01*
G03X371320Y855859I-1054J-757D01*
G01X371230Y855876D01*
X370423Y857274D01*
X370454Y857360D01*
G03X370526Y857789I-1225J426D01*
G03X367932I-1297J0D01*
G03X368987Y856514I1298J0D01*
G01X369077Y856497D01*
X369398Y855941D01*
G02X369052Y855341I-346J-200D01*
G01X368559D01*
G03X366199I-1180J-757D01*
G01X364732D01*
G03X363920Y855859I-1054J-757D01*
G01X363830Y855876D01*
X363023Y857274D01*
X363054Y857360D01*
G03X363126Y857789I-1225J426D01*
G03X360532I-1297J0D01*
G03X361587Y856514I1298J0D01*
G01X361677Y856497D01*
X361998Y855941D01*
G02X361652Y855341I-346J-200D01*
G01X361159D01*
G03X358799I-1180J-757D01*
G01X357332D01*
G03X356520Y855859I-1054J-757D01*
G01X356430Y855876D01*
X355623Y857274D01*
X355654Y857360D01*
G03X355726Y857789I-1225J426D01*
G03X353132I-1297J0D01*
G03X354187Y856514I1298J0D01*
G01X354277Y856497D01*
X354598Y855941D01*
G02X354252Y855341I-346J-200D01*
G01X353759D01*
G03X352822Y855965I-1180J-757D01*
G01X352760Y855976D01*
X351756Y856980D01*
X351837Y857115D01*
G03X352026Y857789I-1107J674D01*
G03X351954Y858217I-1297J2D01*
G01X351923Y858304D01*
X352730Y859701D01*
X352820Y859718D01*
G03X353853Y860752I-242J1275D01*
G02X354071Y860914I197J-37D01*
G03X355992Y861288I358J3283D01*
G03X356027Y861307I-496J955D01*
G01X356081Y861339D01*
G02X356278Y861391I197J-347D01*
G02X356477Y861338I1J-398D01*
G03X358485Y860914I1652J2859D01*
G02X358703Y860752I21J-199D01*
G03X358753Y860565I1275J241D01*
G01X358784Y860478D01*
X357977Y859081D01*
X357887Y859064D01*
G03X356832Y857789I243J-1275D01*
G03X359426I1297J0D01*
G03X359354Y858217I-1297J2D01*
G01X359323Y858304D01*
X360130Y859701D01*
X360220Y859718D01*
G03X361253Y860752I-242J1275D01*
G02X361471Y860914I197J-37D01*
G03X363392Y861288I358J3283D01*
G03X363427Y861307I-496J955D01*
G01X363481Y861339D01*
G02X363678Y861391I197J-347D01*
G02X363877Y861338I1J-398D01*
G03X365885Y860914I1652J2859D01*
G02X366103Y860752I21J-199D01*
G03X366153Y860565I1275J241D01*
G01X366184Y860478D01*
X365377Y859081D01*
X365287Y859064D01*
G03X364232Y857789I243J-1275D01*
G03X366826I1297J0D01*
G03X366754Y858217I-1297J2D01*
G01X366723Y858304D01*
X367530Y859701D01*
X367620Y859718D01*
G03X368653Y860752I-242J1275D01*
G02X368871Y860914I197J-37D01*
G03X370792Y861288I358J3283D01*
G03X370827Y861307I-496J955D01*
G01X370881Y861339D01*
G02X371078Y861391I197J-347D01*
G02X371277Y861338I1J-398D01*
G03X373285Y860914I1652J2859D01*
G02X373503Y860752I21J-199D01*
G03X373553Y860565I1275J241D01*
G01X373584Y860478D01*
X372777Y859081D01*
X372687Y859064D01*
G03X371632Y857789I243J-1275D01*
G03X374226I1297J0D01*
G03X374154Y858217I-1297J2D01*
G01X374123Y858304D01*
X374930Y859701D01*
X375020Y859718D01*
G03X376053Y860752I-242J1275D01*
G02X376271Y860914I197J-37D01*
G03X378192Y861288I358J3283D01*
G03X378227Y861307I-496J955D01*
G01X378281Y861339D01*
G02X378478Y861391I197J-347D01*
G02X378677Y861338I1J-398D01*
G03X380685Y860914I1652J2859D01*
G02X380903Y860752I21J-199D01*
G03X380953Y860565I1275J241D01*
G01X380984Y860478D01*
X380177Y859081D01*
X380087Y859064D01*
G03X379032Y857789I243J-1275D01*
G03X381626I1297J0D01*
G03X381554Y858217I-1297J2D01*
G01X381523Y858304D01*
X382330Y859701D01*
X382420Y859718D01*
G03X383453Y860752I-242J1275D01*
G02X383671Y860914I197J-37D01*
G03X385592Y861288I358J3283D01*
G03X385627Y861307I-496J955D01*
G01X385681Y861339D01*
G02X385878Y861391I197J-347D01*
G02X386077Y861338I1J-398D01*
G03X388085Y860914I1652J2859D01*
G02X388303Y860752I21J-199D01*
G03X388353Y860565I1275J241D01*
G01X388384Y860478D01*
X387577Y859081D01*
X387487Y859064D01*
G03X386432Y857789I243J-1275D01*
G03X389026I1297J0D01*
G03X388954Y858217I-1297J2D01*
G01X388923Y858304D01*
X389730Y859701D01*
X389820Y859718D01*
G03X390853Y860752I-242J1275D01*
G02X391071Y860914I197J-37D01*
G03X392992Y861288I358J3283D01*
G03X393027Y861307I-496J955D01*
G01X393081Y861339D01*
G37*
G36*
G01X346287Y1346496D02*
Y1349554D01*
G02X346346Y1349696I200J0D01*
G01X346648Y1349998D01*
G02X346790Y1350057I142J-141D01*
G01X357468D01*
G02X357610Y1349998I0J-200D01*
G01X358388Y1349220D01*
G02X358447Y1349078I-141J-142D01*
G01Y1344287D01*
G02X358388Y1344145I-200J0D01*
G01X358206Y1343963D01*
G02X358064Y1343904I-142J141D01*
G01X352821D01*
G02X352679Y1343963I0J200D01*
G01X350951Y1345691D01*
G03X350809Y1345750I-142J-141D01*
G01X347033D01*
G02X346891Y1345809I0J200D01*
G01X346346Y1346354D01*
G02X346287Y1346496I141J142D01*
G37*
G36*
G01X343496Y1417464D02*
X344958Y1418926D01*
G02X345100Y1418985I142J-141D01*
G01X376714D01*
G02X376856Y1418926I0J-200D01*
G01X380878Y1414904D01*
G02X380937Y1414762I-141J-142D01*
G01Y1398538D01*
G02X380878Y1398396I-200J0D01*
G01X380409Y1397927D01*
G02X380267Y1397868I-142J141D01*
G01X344267D01*
G02X344125Y1397927I0J200D01*
G01X343496Y1398556D01*
G02X343437Y1398698I141J142D01*
G01Y1417322D01*
G02X343496Y1417464I200J0D01*
G37*
G36*
G01X339791Y1578182D02*
G03I-574J0D01*
G37*
G36*
G01X344051D02*
G03I-574J0D01*
G37*
G36*
G01X351851D02*
G03I-574J0D01*
G37*
G36*
G01X339791Y1590094D02*
G03I-574J0D01*
G37*
G36*
G01X344051D02*
G03I-574J0D01*
G37*
G36*
G01X351851D02*
G03I-574J0D01*
G37*
G36*
G01X345091Y1602380D02*
G03I-574J0D01*
G37*
G36*
G01Y1614292D02*
G03I-574J0D01*
G37*
G36*
G01X349351Y1602380D02*
G03I-574J0D01*
G37*
G36*
G01Y1614292D02*
G03I-574J0D01*
G37*
G36*
G01X361484Y757665D02*
G03I-557J0D01*
G37*
G36*
G01X363911Y1578088D02*
G03I-574J0D01*
G37*
G36*
G01X356111D02*
G03I-574J0D01*
G37*
G36*
G01X368171Y1578182D02*
G03I-574J0D01*
G37*
G36*
G01X363911Y1590094D02*
G03I-574J0D01*
G37*
G36*
G01X356111D02*
G03I-574J0D01*
G37*
G36*
G01X368171D02*
G03I-574J0D01*
G37*
G36*
G01X357151Y1602380D02*
G03I-574J0D01*
G37*
G36*
G01Y1614292D02*
G03I-574J0D01*
G37*
G36*
G01X369211D02*
G03I-574J0D01*
G37*
G36*
G01X361411D02*
G03I-574J0D01*
G37*
G36*
G01X369211Y1602286D02*
G03I-574J0D01*
G37*
G36*
G01X361411D02*
G03I-574J0D01*
G37*
G36*
G01X379220Y1335258D02*
X390364D01*
G02X390506Y1335199I0J-200D01*
G01X390543Y1335162D01*
G02X390602Y1335020I-141J-142D01*
G01Y1330924D01*
G02X390543Y1330782I-200J0D01*
G01X390250Y1330489D01*
G02X390108Y1330430I-142J141D01*
G01X385058D01*
G02X384916Y1330489I0J200D01*
G01X384011Y1331394D01*
G03X383869Y1331453I-142J-141D01*
G01X383791D01*
G02X383616Y1331555I-1J200D01*
G03X380998I-1309J-735D01*
G02X380823Y1331453I-174J98D01*
G01X379620D01*
G02X379478Y1331512I0J200D01*
G01X378806Y1332184D01*
G02X378747Y1332326I141J142D01*
G01Y1334785D01*
G02X378806Y1334927I200J0D01*
G01X379078Y1335199D01*
G02X379220Y1335258I142J-141D01*
G37*
G36*
G01X375971Y1578182D02*
G03I-574J0D01*
G37*
G36*
G01Y1590094D02*
G03I-574J0D01*
G37*
G36*
G01X373471Y1602380D02*
G03I-574J0D01*
G37*
G36*
G01X381271D02*
G03I-574J0D01*
G37*
G36*
G01X373471Y1614292D02*
G03I-574J0D01*
G37*
G36*
G01X381271D02*
G03I-574J0D01*
G37*
G36*
G01X461444Y855740D02*
X463847D01*
X464520Y855067D01*
Y852704D01*
X462330Y850514D01*
X458448D01*
X457353Y849419D01*
Y849313D01*
G02X457023Y849161I-200J0D01*
G03X456178Y849474I-845J-984D01*
G03X454880Y848176I0J-1298D01*
G03X455936Y846901I1298J0D01*
G01X456026Y846884D01*
X456833Y845486D01*
X456802Y845400D01*
G03X456730Y844971I1225J-426D01*
G03X458027Y843674I1297J0D01*
G03X458120Y843677I5J1297D01*
G01X458212Y843683D01*
X458953Y842942D01*
G02X458955Y842378I-283J-283D01*
G03X458582Y841467I924J-910D01*
G03X459879Y840170I1297J0D01*
G03X460790Y840543I1J1297D01*
G02X461354Y840541I281J-285D01*
G01X464222Y837673D01*
Y824397D01*
X466164Y822455D01*
X477004D01*
X478853Y824304D01*
Y839564D01*
X477434Y840983D01*
Y841779D01*
X478604Y842949D01*
X480771D01*
G02X481079Y842294I0J-400D01*
G03X480782Y841467I1000J-826D01*
G03X483376I1297J0D01*
G03X483265Y841994I-1297J2D01*
G01X483226Y842082D01*
X483683Y842949D01*
X488170D01*
G02X488478Y842294I0J-400D01*
G03X488180Y841467I1000J-827D01*
G03X490776I1298J0D01*
G03X490651Y842023I-1299J0D01*
G01X490608Y842112D01*
X491042Y842949D01*
X495070D01*
X495709Y842310D01*
Y842032D01*
X495692Y841993D01*
G03X495580Y841467I1186J-527D01*
G03X495692Y840941I1298J1D01*
G01X495709Y840902D01*
Y786070D01*
X493519Y783880D01*
X427989D01*
X425937Y785932D01*
Y837496D01*
X424350Y839083D01*
X412760D01*
X411040Y837363D01*
Y836658D01*
X411008Y836627D01*
Y825122D01*
X410604Y824717D01*
X400199D01*
X399735Y825180D01*
Y836983D01*
X395804Y840914D01*
Y843864D01*
G03X396424Y844971I-678J1107D01*
G03X396323Y845475I-1297J2D01*
G01X396270Y845599D01*
X396844Y846173D01*
X397236D01*
X397633Y845486D01*
X397602Y845400D01*
G03X397530Y844971I1225J-426D01*
G03X400124I1297J0D01*
G03X399971Y845584I-1297J2D01*
G02X400323Y846173I352J189D01*
G01X401031D01*
G02X401383Y845584I0J-400D01*
G03X401230Y844971I1144J-611D01*
G03X401341Y844444I1297J-2D01*
G01X401380Y844356D01*
X400539Y842761D01*
X400444Y842743D01*
G03X399382Y841467I236J-1276D01*
G03X401976I1297J0D01*
G03X401865Y841994I-1297J2D01*
G01X401826Y842082D01*
X402667Y843677D01*
X402762Y843695D01*
G03X403824Y844971I-236J1276D01*
G03X403671Y845584I-1297J2D01*
G02X404023Y846173I352J189D01*
G01X404636D01*
X405033Y845486D01*
X405002Y845400D01*
G03X404930Y844971I1225J-426D01*
G03X407524I1297J0D01*
G03X407371Y845584I-1297J2D01*
G02X407723Y846173I352J189D01*
G01X408431D01*
G02X408783Y845584I0J-400D01*
G03X408630Y844971I1144J-611D01*
G03X408741Y844444I1297J-2D01*
G01X408780Y844356D01*
X407939Y842761D01*
X407844Y842743D01*
G03X406782Y841467I236J-1276D01*
G03X409376I1297J0D01*
G03X409265Y841994I-1297J2D01*
G01X409226Y842082D01*
X410067Y843677D01*
X410162Y843695D01*
G03X411224Y844971I-236J1276D01*
G03X411071Y845584I-1297J2D01*
G02X411423Y846173I352J189D01*
G01X412036D01*
X412433Y845486D01*
X412402Y845400D01*
G03X412330Y844971I1225J-426D01*
G03X414924I1297J0D01*
G03X414771Y845584I-1297J2D01*
G02X415123Y846173I352J189D01*
G01X415831D01*
G02X416183Y845584I0J-400D01*
G03X416030Y844971I1144J-611D01*
G03X416141Y844444I1297J-2D01*
G01X416180Y844356D01*
X415339Y842761D01*
X415244Y842743D01*
G03X414182Y841467I236J-1276D01*
G03X416776I1297J0D01*
G03X416665Y841994I-1297J2D01*
G01X416626Y842082D01*
X417467Y843677D01*
X417562Y843695D01*
G03X418624Y844971I-236J1276D01*
G03X418471Y845584I-1297J2D01*
G02X418823Y846173I352J189D01*
G01X419436D01*
X419833Y845486D01*
X419802Y845400D01*
G03X419730Y844971I1225J-426D01*
G03X422324I1297J0D01*
G03X422171Y845584I-1297J2D01*
G02X422523Y846173I352J189D01*
G01X423231D01*
G02X423583Y845584I0J-400D01*
G03X423430Y844971I1144J-611D01*
G03X423541Y844444I1297J-2D01*
G01X423580Y844356D01*
X422739Y842761D01*
X422644Y842743D01*
G03X421582Y841467I236J-1276D01*
G03X424176I1297J0D01*
G03X424065Y841994I-1297J2D01*
G01X424026Y842082D01*
X424867Y843677D01*
X424962Y843695D01*
G03X426024Y844971I-236J1276D01*
G03X425871Y845584I-1297J2D01*
G02X426223Y846173I352J189D01*
G01X426836D01*
X427233Y845486D01*
X427202Y845400D01*
G03X427130Y844971I1225J-426D01*
G03X429724I1297J0D01*
G03X429571Y845584I-1297J2D01*
G02X429923Y846173I352J189D01*
G01X433386D01*
X434139Y845420D01*
Y843567D01*
X437166Y840540D01*
Y825060D01*
X440056Y822170D01*
X449964D01*
X452625Y824831D01*
Y840168D01*
X452779Y840205D01*
G03X453776Y841467I-300J1262D01*
G03X453665Y841994I-1297J2D01*
G01X453626Y842082D01*
X454467Y843677D01*
X454562Y843695D01*
G03X455624Y844971I-236J1276D01*
G03X453030I-1297J0D01*
G03X453141Y844444I1297J-2D01*
G01X453180Y844356D01*
X453117Y844235D01*
G02X452480Y844139I-354J187D01*
G01X451904Y844715D01*
X451916Y844812D01*
G03X451926Y844971I-1288J161D01*
G03X451238Y846116I-1297J0D01*
G01X451132Y846173D01*
Y850173D01*
X451238Y850229D01*
G03X451931Y851380I-609J1151D01*
G03X451758Y852028I-1302J0D01*
G01X451682Y852160D01*
X452868Y853346D01*
X452910Y853361D01*
G03X453701Y854152I-432J1223D01*
G01X453716Y854194D01*
X455262Y855740D01*
X458358D01*
G02X458716Y855162I0J-400D01*
G03X458580Y854584I1162J-578D01*
G03X461176I1298J0D01*
G03X461103Y855011I-1298J-2D01*
G01X461073Y855098D01*
X461444Y855740D01*
G37*
G36*
G01X437257Y863710D02*
X438102D01*
X438155Y863591D01*
G03X439853Y862732I1374J607D01*
G01X439960Y862756D01*
X440260Y862456D01*
X440773D01*
Y862146D01*
X440681Y862087D01*
G03X440080Y860993I697J-1095D01*
G03X441136Y859718I1298J0D01*
G01X441226Y859701D01*
X442034Y858302D01*
X442003Y858215D01*
G03X441932Y857789I1226J-423D01*
G03X444526I1297J0D01*
G03X443468Y859064I-1297J0D01*
G01X443378Y859081D01*
X442572Y860478D01*
X442603Y860564D01*
G03X442676Y860993I-1224J429D01*
G03X442622Y861363I-1298J0D01*
G02X443005Y861877I383J114D01*
G01X447152D01*
G02X447535Y861363I0J-400D01*
G03X447482Y860993I1244J-367D01*
G03X448537Y859718I1298J0D01*
G01X448627Y859701D01*
X449434Y858303D01*
X449404Y858216D01*
G03X449332Y857789I1225J-426D01*
G03X451926I1297J0D01*
G03X450869Y859064I-1297J0D01*
G01X450779Y859081D01*
X449973Y860478D01*
X450004Y860564D01*
G03X450076Y860993I-1225J426D01*
G03X450023Y861363I-1297J3D01*
G02X450406Y861877I383J114D01*
G01X452903D01*
X453810Y860970D01*
Y859098D01*
X453700Y859042D01*
G03X452928Y857790I629J-1252D01*
G03X453034Y857255I1403J0D01*
G01X453071Y857164D01*
X452392Y855988D01*
X452295Y855975D01*
G03X451077Y854585I184J-1390D01*
G03X451100Y854332I1403J0D01*
G01X451119Y854229D01*
X450520Y853630D01*
Y852888D01*
X450356Y852858D01*
G03X450013Y850012I275J-1477D01*
G01X450130Y849958D01*
Y849581D01*
G02X449506Y849250I-400J0D01*
G03X448778Y849474I-729J-1074D01*
G03X447480Y848176I0J-1298D01*
G03X448536Y846901I1298J0D01*
G01X448626Y846884D01*
X449434Y845486D01*
X449403Y845399D01*
G03X449330Y844971I1225J-429D01*
G03X450451Y843686I1297J0D01*
G01X450518Y843676D01*
X451488Y842706D01*
Y842307D01*
X451447Y842254D01*
G03X451182Y841467I1032J-786D01*
G03X451488Y840629I1297J-1D01*
G01Y825488D01*
X450032Y824032D01*
X440034D01*
X439027Y825039D01*
Y838719D01*
X439049Y838740D01*
Y841430D01*
X436744Y843735D01*
X436853Y843874D01*
G03X437126Y844671I-1024J796D01*
G03X437015Y845197I-1297J1D01*
G01X436976Y845286D01*
X437818Y846882D01*
X437913Y846900D01*
G03X438976Y848176I-234J1276D01*
G03X436380I-1298J0D01*
G03X436492Y847650I1298J1D01*
G01X436531Y847561D01*
X436155Y846847D01*
G02X435518Y846751I-354J187D01*
G01X434951Y847318D01*
G03X435276Y848176I-973J859D01*
G03X433978Y849474I-1298J0D01*
G03X432939Y848954I0J-1298D01*
G01X431317D01*
G03X430278Y849474I-1039J-778D01*
G03X428980Y848176I0J-1298D01*
G03X429008Y847912I1298J4D01*
G02X428616Y847430I-392J-82D01*
G01X427906D01*
X427772Y847661D01*
X427803Y847747D01*
G03X427876Y848176I-1224J429D01*
G03X425280I-1298J0D01*
G03X425308Y847912I1298J4D01*
G02X424916Y847430I-392J-82D01*
G01X420506D01*
X420372Y847661D01*
X420403Y847747D01*
G03X420476Y848176I-1224J429D01*
G03X417880I-1298J0D01*
G03X417908Y847912I1298J4D01*
G02X417516Y847430I-392J-82D01*
G01X413106D01*
X412972Y847661D01*
X413003Y847747D01*
G03X413076Y848176I-1224J429D01*
G03X410480I-1298J0D01*
G03X410508Y847912I1298J4D01*
G02X410116Y847430I-392J-82D01*
G01X405706D01*
X405572Y847661D01*
X405603Y847747D01*
G03X405676Y848176I-1224J429D01*
G03X403080I-1298J0D01*
G03X403108Y847912I1298J4D01*
G02X402716Y847430I-392J-82D01*
G01X400390D01*
X399440Y848380D01*
Y850118D01*
G03Y852642I-611J1262D01*
G01Y853108D01*
G02X400037Y853456I400J0D01*
G03X400678Y853286I642J1128D01*
G03X401976Y854584I0J1298D01*
G03X400920Y855859I-1298J0D01*
G01X400830Y855876D01*
X400023Y857274D01*
X400054Y857360D01*
G03X400126Y857789I-1225J426D01*
G03X399440Y858934I-1297J1D01*
G01Y860215D01*
X400480Y861255D01*
X401028D01*
X401070Y861234D01*
G03X402885Y860914I1458J2963D01*
G02X403103Y860752I21J-199D01*
G03X403153Y860565I1275J241D01*
G01X403184Y860478D01*
X402377Y859081D01*
X402287Y859064D01*
G03X401232Y857789I243J-1275D01*
G03X403826I1297J0D01*
G03X403754Y858217I-1297J2D01*
G01X403723Y858304D01*
X404530Y859701D01*
X404620Y859718D01*
G03X405653Y860752I-242J1275D01*
G02X405871Y860914I197J-37D01*
G03X407689Y861234I359J3283D01*
G01X407731Y861255D01*
X408428D01*
X408470Y861234D01*
G03X410285Y860914I1458J2963D01*
G02X410503Y860752I21J-199D01*
G03X410553Y860565I1275J241D01*
G01X410584Y860478D01*
X409777Y859081D01*
X409687Y859064D01*
G03X408632Y857789I243J-1275D01*
G03X411226I1297J0D01*
G03X411154Y858217I-1297J2D01*
G01X411123Y858304D01*
X411930Y859701D01*
X412020Y859718D01*
G03X413071Y860888I-242J1275D01*
G02X413424Y861252I399J-33D01*
G01X415107Y862935D01*
X416517D01*
G03X418668Y863516I813J1262D01*
G01X418724Y863625D01*
X419636D01*
X419692Y863516D01*
G03X421030Y862696I1338J682D01*
G03X422404Y863591I0J1502D01*
G01X422457Y863710D01*
X423303D01*
X423356Y863591D01*
G03X426104I1374J607D01*
G01X426157Y863710D01*
X427003D01*
X427056Y863591D01*
G03X429804I1374J607D01*
G01X429857Y863710D01*
X430703D01*
X430756Y863591D01*
G03X433504I1374J607D01*
G01X433557Y863710D01*
X434403D01*
X434456Y863591D01*
G03X437204I1374J607D01*
G01X437257Y863710D01*
G37*
G36*
G01X422371Y950170D02*
X427296D01*
X427686Y949781D01*
Y946775D01*
X425985Y945074D01*
Y940605D01*
X426354Y940236D01*
G03X426372Y940218I858J840D01*
G01X426692Y939898D01*
X427680Y938910D01*
X449385D01*
X451629Y936666D01*
X460901D01*
X461543Y937308D01*
Y937561D01*
X461544Y937562D01*
Y942743D01*
X461870Y943070D01*
X467070D01*
X467570Y942570D01*
Y941370D01*
X468572Y940368D01*
X469973D01*
X470183Y940158D01*
Y936491D01*
X469245Y935553D01*
X462439D01*
X460977Y934090D01*
Y930380D01*
X460766Y930169D01*
X457644D01*
X456905Y929430D01*
Y928746D01*
G02X456473Y928347I-400J0D01*
G03X456327Y928353I-147J-1796D01*
G03X454525Y926575I0J-1802D01*
G01X454523Y926378D01*
X453213D01*
G03X452805Y926209I0J-577D01*
G01X451028Y924432D01*
X450243D01*
X450095Y924579D01*
X450128Y924692D01*
G03X450182Y925079I-1348J385D01*
G03X447378I-1402J0D01*
G03X447475Y924566I1402J-1D01*
G02X447103Y924020I-372J-146D01*
G01X446756D01*
G02X446384Y924566I0J400D01*
G03X446481Y925079I-1305J512D01*
G03X443677I-1402J0D01*
G03X443774Y924566I1402J-1D01*
G02X443402Y924020I-372J-146D01*
G01X439356D01*
G02X438984Y924566I0J400D01*
G03X439081Y925079I-1305J512D01*
G03X436277I-1402J0D01*
G03X436291Y924884I1402J3D01*
G01X436307Y924767D01*
X435314Y924020D01*
X431956D01*
G02X431584Y924566I0J400D01*
G03X431681Y925079I-1305J512D01*
G03X428877I-1402J0D01*
G03X428974Y924566I1402J-1D01*
G02X428602Y924020I-372J-146D01*
G01X428100D01*
X427338Y924782D01*
X427327Y924845D01*
G03X427120Y925430I-1777J-300D01*
G01Y935236D01*
X425436Y936920D01*
X407310D01*
X404880Y934490D01*
X404281D01*
X403924Y934847D01*
X403914Y934911D01*
G03X403887Y935039I-1384J-225D01*
G01X403881Y935063D01*
Y936110D01*
X401976Y938015D01*
X401967Y938081D01*
G03X400863Y939185I-1289J-185D01*
G01X400797Y939194D01*
X400099Y939892D01*
Y940817D01*
X400103Y940837D01*
G03X400130Y941100I-1275J264D01*
G03X400103Y941363I-1302J-1D01*
G01X400099Y941383D01*
Y941834D01*
X401324Y943059D01*
X401349Y943072D01*
G03X401911Y943634I-670J1232D01*
G01X401924Y943659D01*
X403224Y944958D01*
X403354D01*
X404100Y945705D01*
Y948105D01*
X405024Y949028D01*
X409884D01*
X410096Y949241D01*
X412590D01*
G03X412622Y949240I54J1200D01*
G01X420160D01*
G03X420191Y949241I-23J1201D01*
G01X421441D01*
X422319Y950118D01*
X422371Y950170D01*
G37*
G36*
G01X402295Y977230D02*
X412009D01*
X412534Y976705D01*
Y970655D01*
X411859Y969980D01*
X403639D01*
X402939Y969280D01*
Y968537D01*
G02X402537Y968137I-400J0D01*
G01X402529D01*
G03Y965333I0J-1402D01*
G01X402537D01*
G02X402939Y964933I2J-400D01*
G01Y963080D01*
X405300Y960719D01*
Y955945D01*
X406325Y954920D01*
X408869D01*
X409849Y953940D01*
Y950410D01*
X409469Y950030D01*
X404609D01*
X403099Y948520D01*
Y946120D01*
X402939Y945960D01*
X400217D01*
G02X399909Y946615I0J400D01*
G03X400231Y947509I-1080J894D01*
G03X397427I-1402J0D01*
G03X397749Y946615I1402J0D01*
G02X397441Y945960I-308J-255D01*
G01X396365D01*
G02X396072Y946632I0J400D01*
G03X396416Y947509I-943J876D01*
G03X393842I-1287J0D01*
G03X394186Y946632I1287J-1D01*
G02X393893Y945960I-293J-272D01*
G01X393519D01*
X392658Y946821D01*
X392713Y946946D01*
G03X392831Y947509I-1284J563D01*
G03X391429Y948911I-1402J0D01*
G01X391413D01*
G02X391009Y949311I-4J400D01*
G01Y952115D01*
G02X391413Y952515I400J0D01*
G01X391429D01*
G03Y955319I0J1402D01*
G01X391413D01*
G02X391009Y955719I-4J400D01*
G01Y958524D01*
G02X391413Y958924I400J0D01*
G01X391429D01*
G03Y961728I0J1402D01*
G01X391413D01*
G02X391009Y962128I-4J400D01*
G01Y964933D01*
G02X391413Y965333I400J0D01*
G01X391429D01*
G03Y968137I0J1402D01*
G01X391413D01*
G02X391009Y968537I-4J400D01*
G01Y971341D01*
G02X391413Y971741I400J0D01*
G01X391429D01*
G03Y974545I0J1402D01*
G01X391413D01*
G02X391009Y974945I-4J400D01*
G01Y976470D01*
X391769Y977230D01*
X392157D01*
Y976981D01*
X392134Y976938D01*
G03X391990Y976347I1144J-592D01*
G03X394566I1288J0D01*
G03X394512Y976716I-1288J0D01*
G02X394895Y977230I383J114D01*
G01X395242D01*
G02X395627Y976723I0J-400D01*
G03X395576Y976347I1351J-375D01*
G03X398380I1402J0D01*
G03X398329Y976723I-1402J1D01*
G02X398714Y977230I385J107D01*
G01X399061D01*
G02X399444Y976716I0J-400D01*
G03X399390Y976347I1234J-369D01*
G03X401966I1288J0D01*
G03X401912Y976716I-1288J0D01*
G02X402295Y977230I383J114D01*
G37*
G36*
G01X410165Y1037140D02*
X414115D01*
X414285Y1036970D01*
Y1030810D01*
X414057Y1030582D01*
X410527D01*
X410135Y1030190D01*
Y1027630D01*
X410495Y1027270D01*
X411435D01*
X411575Y1027130D01*
Y1023647D01*
X413411Y1021811D01*
X425761D01*
X426663Y1022713D01*
X427232D01*
X427634Y1022312D01*
Y1022311D01*
X427714Y1022230D01*
Y1018480D01*
X426287Y1017053D01*
G03X426271Y1017036I867J-832D01*
G01X426270Y1017035D01*
X425935Y1016700D01*
Y1016369D01*
X425686Y1016120D01*
X419645D01*
X419125Y1015600D01*
Y1015043D01*
X419110Y1015007D01*
G03Y1013933I1294J-537D01*
G01X419125Y1013897D01*
Y1013365D01*
X419580Y1012910D01*
X425603D01*
X425751Y1012760D01*
X425754D01*
X426095Y1012420D01*
Y1011561D01*
X426454Y1011202D01*
X426455Y1011201D01*
G03X426471Y1011184I883J815D01*
G01X427664Y1009991D01*
Y1009959D01*
X427665D01*
Y1006570D01*
X427231Y1006136D01*
X426411D01*
X426336Y1006212D01*
G03X426317Y1006230I-836J-863D01*
G01X425982Y1006565D01*
X425516D01*
G03X425485Y1006566I-54J-1200D01*
G01X413004D01*
G03X412973Y1006565I23J-1201D01*
G01X412507D01*
X412172Y1006230D01*
X412171Y1006229D01*
G03X412154Y1006213I815J-883D01*
G01X411946Y1006005D01*
G03X411930Y1005988I867J-832D01*
G01X411929Y1005987D01*
X411585Y1005643D01*
Y1001916D01*
X411584D01*
Y1001780D01*
X408975D01*
X408165Y1000970D01*
Y998830D01*
X408695Y998300D01*
X413515D01*
X414415Y999200D01*
Y1000430D01*
X414694Y1000708D01*
X414745Y1000760D01*
X417925D01*
X418335Y1000350D01*
Y999080D01*
X419050Y998365D01*
X425499D01*
X425558Y998306D01*
X425559D01*
X426044Y997820D01*
Y997192D01*
G03X426045Y997161I1201J23D01*
G01Y996660D01*
X427645Y995060D01*
Y992030D01*
X427216Y991601D01*
X426916D01*
X426167Y992350D01*
X406455D01*
X406450Y992346D01*
X406133Y992029D01*
G03X406117Y992012I867J-832D01*
G01X406116Y992011D01*
X405781Y991676D01*
Y991210D01*
G03X405780Y991179I1200J-54D01*
G01Y985247D01*
G03X405781Y985216I1201J23D01*
G01Y984750D01*
X406116Y984415D01*
X406117Y984414D01*
G03X406133Y984397I883J815D01*
G01X406185Y984345D01*
G03X406202Y984329I832J867D01*
G01X406203Y984328D01*
X406551Y983980D01*
X413415D01*
X413763Y984328D01*
X413764Y984329D01*
G03X413781Y984345I-815J883D01*
G01X413903Y984467D01*
G03X413919Y984484I-867J832D01*
G01X413920Y984485D01*
X414255Y984820D01*
Y985286D01*
G03X414256Y985317I-1200J54D01*
G01Y985960D01*
X414618Y986322D01*
X417972D01*
X418440Y985854D01*
X418454Y985840D01*
Y985235D01*
G03X418455Y985204I1201J23D01*
G01Y984690D01*
X419235Y983910D01*
X425605D01*
X425795Y983720D01*
Y982720D01*
X426292Y982223D01*
X426293Y982222D01*
G03X426309Y982205I883J815D01*
G01X427634Y980880D01*
Y977680D01*
X427230Y977276D01*
X427192Y977238D01*
X426712D01*
X425994Y977955D01*
X412700D01*
X412424Y978232D01*
X403943D01*
G02X403608Y978850I0J400D01*
G03X403816Y979552I-1079J702D01*
G03X402973Y980761I-1287J1D01*
G01X402931Y980776D01*
X402435Y981273D01*
X399839D01*
X399307Y981805D01*
Y996865D01*
X400842Y998400D01*
X402398D01*
X402434Y998385D01*
G03X402962Y998282I527J1299D01*
G03X404364Y999684I0J1402D01*
G03X403163Y1001071I-1401J0D01*
G01X402992Y1001096D01*
Y1004681D01*
X403163Y1004706D01*
G03X404364Y1006093I-200J1387D01*
G03X403361Y1007437I-1402J0D01*
G01X403312Y1007452D01*
X403135Y1007629D01*
X403494Y1007988D01*
X405664D01*
X405669Y1007993D01*
X411142D01*
X411160Y1007975D01*
X411817D01*
X413337Y1009495D01*
Y1013321D01*
X413343Y1013327D01*
X413337Y1013333D01*
Y1020175D01*
X412177Y1021335D01*
X410937D01*
X410931Y1021341D01*
X404605D01*
X404409Y1021537D01*
Y1027653D01*
X405405Y1028649D01*
G03X405642Y1028989I-832J832D01*
G01X405657Y1029022D01*
X405832Y1029197D01*
Y1032837D01*
X408565Y1035570D01*
X408595D01*
X410165Y1037140D01*
G37*
G36*
G01X401310Y1649352D02*
X410715D01*
X410763Y1649221D01*
G03X412456Y1648036I1693J617D01*
G03X412617Y1648043I2J1802D01*
G01X412710Y1648052D01*
X413190Y1647572D01*
Y1633192D01*
X412120Y1632122D01*
X401870D01*
X400240Y1633752D01*
Y1648282D01*
X401310Y1649352D01*
G37*
G36*
G01X413420Y929937D02*
X418382D01*
X418559Y929760D01*
Y927910D01*
X418699Y927770D01*
X418709D01*
X419179Y927300D01*
Y926026D01*
X418875Y925721D01*
X418195D01*
X416238Y927678D01*
X415872D01*
X413387D01*
X413239Y927826D01*
Y929756D01*
X413420Y929937D01*
G37*
G36*
G01X412039Y927750D02*
X412199Y927910D01*
Y929790D01*
X411949Y930040D01*
X406609D01*
X405259Y928690D01*
Y927780D01*
X405449Y927590D01*
X411249D01*
X411879D01*
X412039Y927750D01*
G37*
G36*
G01X407725Y935918D02*
X425021D01*
X426118Y934821D01*
Y926742D01*
G02X425688Y926343I-400J0D01*
G03X425550Y926348I-134J-1797D01*
G03X424769Y926170I0J-1802D01*
G01X424728Y926150D01*
X422825D01*
G03X421635Y926646I-1191J-1181D01*
G01X421272D01*
X419569Y928348D01*
Y930910D01*
X418989Y931490D01*
X406589D01*
X406389Y931690D01*
Y934583D01*
X407725Y935918D01*
G37*
G36*
G01X413835Y971790D02*
X417885D01*
X418235Y971440D01*
Y970452D01*
X419114Y969573D01*
X419632D01*
G03X419663Y969572I54J1200D01*
G01X425047D01*
X425618Y969002D01*
X427510Y967110D01*
X427511D01*
X427762Y966858D01*
Y963308D01*
X427276Y962822D01*
X426295D01*
X426160Y962957D01*
X425973Y963145D01*
G03X425958Y963159I-828J-872D01*
G01X425957Y963160D01*
X425621Y963496D01*
X406138D01*
X405836Y963194D01*
Y963180D01*
X405465Y962810D01*
X404625D01*
X403975Y963460D01*
Y968870D01*
X404084Y968978D01*
X412274D01*
X412745Y969450D01*
X412765D01*
X413635Y970320D01*
Y971590D01*
X413835Y971790D01*
G37*
G36*
G01X405048Y1020340D02*
X410516D01*
X410522Y1020334D01*
X411762D01*
X412336Y1019760D01*
Y1009910D01*
X411420Y1008994D01*
X405204D01*
X404559Y1009640D01*
Y1019850D01*
X405048Y1020340D01*
G37*
G36*
G01X414606Y1029715D02*
X417925D01*
G03X417956Y1029714I54J1200D01*
G01X424964D01*
X425674Y1029005D01*
Y1023140D01*
X425346Y1022812D01*
X413826D01*
X413009Y1023629D01*
Y1027390D01*
X412459Y1027940D01*
X412181D01*
X411850Y1028272D01*
X411136D01*
Y1029538D01*
X411180Y1029580D01*
X414472D01*
X414606Y1029715D01*
G37*
G36*
G01X413480Y1337058D02*
X421482D01*
G02X421624Y1336999I0J-200D01*
G01X422578Y1336045D01*
G02X422637Y1335903I-141J-142D01*
G01Y1330839D01*
G02X422578Y1330697I-200J0D01*
G01X422131Y1330250D01*
G02X421989Y1330191I-142J141D01*
G01X417548D01*
G02X417471Y1330206I-1J200D01*
G01X417403Y1330235D01*
G02X417338Y1330278I76J185D01*
G01X415412Y1332204D01*
G03X415347Y1332247I-141J-142D01*
G01X415279Y1332276D01*
G03X415202Y1332291I-76J-185D01*
G01X414734D01*
X414716Y1332295D01*
G03X414435Y1332321I-278J-1476D01*
G03X414154Y1332295I-3J-1502D01*
G01X414136Y1332291D01*
X413502D01*
G02X413360Y1332350I0J200D01*
G01X412786Y1332924D01*
G02X412727Y1333066I141J142D01*
G01Y1336305D01*
G02X412786Y1336447I200J0D01*
G01X413338Y1336999D01*
G02X413480Y1337058I142J-141D01*
G37*
G36*
G01X418744Y1420602D02*
Y1404719D01*
X419200Y1404263D01*
X435611D01*
X436020Y1404672D01*
Y1409547D01*
X436459Y1409986D01*
X438042D01*
X438527Y1410471D01*
Y1412851D01*
X438178Y1413200D01*
X436581D01*
X436020Y1413761D01*
Y1420809D01*
X435474Y1421355D01*
X419497D01*
X418744Y1420602D01*
G37*
G36*
G01X417220Y1629972D02*
X415330Y1631862D01*
X415230D01*
Y1637622D01*
X415490Y1637882D01*
X423750D01*
X424480Y1637152D01*
Y1629092D01*
X425330Y1628242D01*
X432220D01*
X433390Y1627072D01*
Y1625092D01*
X433170Y1624872D01*
X431190D01*
X430380Y1624062D01*
Y1620132D01*
X431400Y1619112D01*
X434986D01*
X436032Y1620158D01*
X441639D01*
X442199Y1619598D01*
Y1617543D01*
X444350Y1615392D01*
Y1614222D01*
X443430Y1613302D01*
X432720D01*
X429560Y1616462D01*
Y1617032D01*
X427220Y1619372D01*
X426350D01*
X417220Y1628502D01*
Y1629972D01*
G37*
G36*
G01X422640Y1654940D02*
X425530Y1652050D01*
Y1640582D01*
X424820Y1639872D01*
X415690D01*
X414930Y1640632D01*
Y1653800D01*
X416070Y1654940D01*
X422640D01*
G37*
G36*
G01X434520Y1612012D02*
X438970D01*
X439880Y1611102D01*
Y1607970D01*
X439435Y1607525D01*
X434775D01*
X434170Y1608130D01*
Y1611662D01*
X434520Y1612012D01*
G37*
G36*
G01X435890Y1637572D02*
X446620D01*
X448150Y1636042D01*
Y1628392D01*
X448660Y1627882D01*
Y1622582D01*
X447690Y1621612D01*
X436060D01*
X434790Y1620342D01*
X431586D01*
X431382Y1620547D01*
Y1622824D01*
X431800Y1623242D01*
X433690D01*
X434810Y1624362D01*
Y1628672D01*
X433860Y1629622D01*
X428640D01*
X428290Y1629972D01*
Y1632292D01*
X428780Y1632782D01*
X433540D01*
X435150Y1634392D01*
Y1636832D01*
X435890Y1637572D01*
G37*
G36*
G01X434360Y1642862D02*
X445370D01*
X446020Y1642212D01*
Y1640762D01*
X443832Y1638574D01*
X435475D01*
X434984Y1638082D01*
X433490D01*
X432700Y1638872D01*
Y1641202D01*
X434360Y1642862D01*
G37*
G36*
G01X427420Y1643542D02*
X427520Y1643642D01*
X430820D01*
X431530Y1642932D01*
Y1635232D01*
X431270Y1634972D01*
X426420D01*
X425620Y1635772D01*
Y1638752D01*
X427420Y1640552D01*
Y1643542D01*
G37*
G36*
G01X443161Y1648412D02*
X444620D01*
X445586Y1647446D01*
X445591Y1647371D01*
G03X447090Y1645970I1499J101D01*
G03X447577Y1646051I0J1502D01*
G01X447609Y1646062D01*
X449280D01*
X449320Y1646044D01*
G03X450560I620J1367D01*
G01X450600Y1646062D01*
X451370D01*
X451977Y1645455D01*
G02X451740Y1644774I-282J-283D01*
G03X450408Y1643282I170J-1492D01*
G03X451910Y1641780I1502J0D01*
G03X453402Y1643112I0J1502D01*
G02X454083Y1643349I398J-45D01*
G01X457970Y1639462D01*
Y1635975D01*
G03X457176Y1634481I1009J-1494D01*
G03X457891Y1633044I1802J0D01*
G01X457970Y1632984D01*
Y1632732D01*
X457180Y1631942D01*
Y1630806D01*
G03Y1629094I1233J-856D01*
G01Y1625850D01*
G03Y1624138I1233J-856D01*
G01Y1621942D01*
X456440Y1621202D01*
X450720D01*
X449960Y1621962D01*
Y1630542D01*
X449350Y1631152D01*
Y1636752D01*
X447030Y1639072D01*
Y1642622D01*
X445760Y1643892D01*
X443710D01*
X442150Y1645452D01*
X428590D01*
X428060Y1645982D01*
Y1648112D01*
X428360Y1648412D01*
X436919D01*
X436957Y1648395D01*
G03X437562Y1648268I604J1375D01*
G03X438167Y1648395I1J1502D01*
G01X438205Y1648412D01*
X441875D01*
X441913Y1648395D01*
G03X442518Y1648268I604J1375D01*
G03X443123Y1648395I1J1502D01*
G01X443161Y1648412D01*
G37*
G36*
G01X455327Y1079231D02*
G03X456612Y1078389I1285J560D01*
G03X456783Y1078399I4J1402D01*
G01X456854Y1078408D01*
X457036Y1078291D01*
X457061Y1078240D01*
G03X457358Y1077729I3252J1548D01*
G01X457375Y1077705D01*
X457412Y1077589D01*
X457368Y1077465D01*
X457349Y1077440D01*
G03X457060Y1076587I1114J-853D01*
G03X458462Y1075185I1402J0D01*
G01X458465D01*
G03X458711Y1075207I-1J1402D01*
G01X458729Y1075210D01*
X459693D01*
G03X460420Y1075418I-1J1377D01*
G01X460443Y1075432D01*
X460563Y1075468D01*
X460618Y1075453D01*
G03X460931Y1075410I315J1134D01*
G01X461398D01*
X461445Y1075382D01*
G03X462162Y1075185I717J1206D01*
G03Y1077989I0J1402D01*
G03X461611Y1077876I0J-1402D01*
G03X461276Y1078500I-3149J-1288D01*
G01X461259Y1078524D01*
X461224Y1078637D01*
X461284Y1078780D01*
X461311Y1078807D01*
G03X461710Y1079681I-999J984D01*
G01X461716Y1079759D01*
X462031Y1080049D01*
X462293D01*
X462608Y1079759D01*
X462614Y1079681D01*
G03X464003Y1078389I1398J110D01*
G01X464032D01*
G03X464180Y1078399I-20J1402D01*
G03X465414Y1079791I-168J1392D01*
G03X464334Y1081156I-1403J0D01*
G01X464180Y1081192D01*
Y1081729D01*
G02X464865Y1082010I400J0D01*
G03X465862Y1081593I998J985D01*
G03Y1084397I0J1402D01*
G03X464865Y1083980I1J-1402D01*
G02X464180Y1084261I-285J281D01*
G01Y1084799D01*
X464334Y1084836D01*
G03Y1087564I-323J1364D01*
G01X464180Y1087601D01*
Y1088136D01*
G02X464864Y1088417I400J0D01*
G03X465861Y1088001I997J987D01*
G03Y1090805I0J1402D01*
G03X464864Y1090389I0J-1403D01*
G02X464180Y1090670I-284J281D01*
G01Y1090792D01*
X465980Y1092592D01*
X466299D01*
X466323Y1092419D01*
G03X469101I1389J189D01*
G01X469125Y1092592D01*
X469999D01*
X470023Y1092419D01*
G03X472801I1389J188D01*
G01X472825Y1092592D01*
X473699D01*
X473723Y1092419D01*
G03X476501I1389J188D01*
G01X476525Y1092592D01*
X477399D01*
X477423Y1092419D01*
G03X480201I1389J188D01*
G01X480225Y1092592D01*
X481099D01*
X481123Y1092419D01*
G03X483901I1389J188D01*
G01X483925Y1092592D01*
X484798D01*
X484822Y1092419D01*
G03X487600I1389J189D01*
G01X487624Y1092592D01*
X488498D01*
X488522Y1092419D01*
G03X491300I1389J189D01*
G01X491324Y1092592D01*
X492199D01*
X492223Y1092419D01*
G03X495001I1389J189D01*
G01X495025Y1092592D01*
X496012D01*
X496037Y1092421D01*
G03X498585I1274J187D01*
G01X498610Y1092592D01*
X499712D01*
X499737Y1092421D01*
G03X502285I1274J187D01*
G01X502310Y1092592D01*
X503412D01*
X503437Y1092421D01*
G03X505985I1274J187D01*
G01X506010Y1092592D01*
X507112D01*
X507137Y1092421D01*
G03X509685I1274J187D01*
G01X509710Y1092592D01*
X510699D01*
X510723Y1092419D01*
G03X513501I1389J189D01*
G01X513525Y1092592D01*
X514399D01*
X514423Y1092419D01*
G03X517201I1389J189D01*
G01X517225Y1092592D01*
X518098D01*
X518122Y1092419D01*
G03X520900I1389J189D01*
G01X520924Y1092592D01*
X521912D01*
X521937Y1092421D01*
G03X524485I1274J187D01*
G01X524510Y1092592D01*
X525612D01*
X525637Y1092421D01*
G03X528185I1274J187D01*
G01X528210Y1092592D01*
X529312D01*
X529337Y1092421D01*
G03X531885I1274J187D01*
G01X531910Y1092592D01*
X533011D01*
X533036Y1092421D01*
G03X535584I1274J187D01*
G01X535609Y1092592D01*
X536598D01*
X536622Y1092419D01*
G03X539400I1389J189D01*
G01X539424Y1092592D01*
X543998D01*
X544022Y1092419D01*
G03X545411Y1091206I1389J189D01*
G03X546813Y1092608I0J1402D01*
G03X545869Y1093933I-1402J0D01*
G02X545717Y1094594I131J378D01*
G01X545830Y1094707D01*
G02X546368Y1094732I283J-283D01*
G03X547261Y1094411I893J1082D01*
G03X548663Y1095813I0J1402D01*
G03X548342Y1096706I-1403J0D01*
G02X548367Y1097244I308J255D01*
G01X566545Y1115422D01*
Y1315133D01*
G03X566546Y1315163I-1200J55D01*
G01Y1334522D01*
G03X566545Y1334564I-1202J-8D01*
G01Y1335254D01*
X576956Y1345666D01*
Y1410046D01*
X550029Y1436973D01*
G02X550312Y1437656I283J283D01*
G01X552286D01*
G03X552788Y1438157I0J502D01*
G01Y1444257D01*
G03X552286Y1444758I-501J0D01*
G01X546186D01*
G03X545684Y1444257I0J-502D01*
G01Y1442283D01*
G02X545002Y1442000I-400J0D01*
G01X541890Y1445112D01*
X477640D01*
X476590Y1446162D01*
Y1493272D01*
X481170Y1497852D01*
X634180D01*
X638540Y1493492D01*
Y1397902D01*
X634500Y1393862D01*
Y1391586D01*
X634494Y1391561D01*
G03X634438Y1391132I1645J-433D01*
G01Y1324791D01*
X631881Y1322234D01*
X618780D01*
G03X617577Y1321735I1J-1702D01*
G01X609617Y1313775D01*
G03X609118Y1312572I1203J-1204D01*
G01Y1077411D01*
X607401Y1075694D01*
X601260D01*
G03X600594Y1075558I1J-1702D01*
G01X600557Y1075542D01*
X600140D01*
X595681Y1071084D01*
X549540D01*
G03X548709Y1070867I1J-1702D01*
G02X548443Y1070934I-98J174D01*
G03X547262Y1071580I-1181J-757D01*
G03X546003Y1070794I0J-1401D01*
G01X545948Y1070682D01*
X542238D01*
X541927Y1070371D01*
X541840Y1070374D01*
G03X540100Y1069971I-129J-3400D01*
G03X540062Y1069950I550J-1040D01*
G01X540045Y1069940D01*
X540041Y1069938D01*
G03X540008Y1069920I547J-1042D01*
G03X538615Y1068385I1703J-2945D01*
G02X538379Y1068275I-182J83D01*
G03X538011Y1068326I-368J-1302D01*
G03X536701Y1067307I0J-1352D01*
G02X536488Y1067157I-194J49D01*
G03X535703Y1067141I-324J-3387D01*
G03X534311Y1068376I-1392J-167D01*
G03X532919Y1067142I0J-1402D01*
G03X532073Y1067150I-455J-3372D01*
G02X531857Y1067299I-22J199D01*
G03X529365I-1246J-325D01*
G02X529149Y1067151I-193J50D01*
G03X528373Y1067150I-384J-3381D01*
G02X528157Y1067299I-22J199D01*
G03X526911Y1068262I-1246J-325D01*
G03X525665Y1067298I0J-1287D01*
G02X525449Y1067150I-193J51D01*
G03X525061Y1067172I-386J-3380D01*
G03X524603Y1067141I0J-3402D01*
G03X523211Y1068376I-1392J-167D01*
G03X521819Y1067142I0J-1402D01*
G03X520973Y1067150I-455J-3372D01*
G02X520757Y1067299I-22J199D01*
G03X518265I-1246J-325D01*
G02X518049Y1067151I-193J50D01*
G03X517203Y1067141I-383J-3381D01*
G03X515811Y1068376I-1392J-167D01*
G03X514419Y1067142I0J-1402D01*
G03X513573Y1067150I-455J-3372D01*
G02X513357Y1067299I-22J199D01*
G03X510865I-1246J-325D01*
G02X510649Y1067151I-193J50D01*
G03X509803Y1067141I-383J-3381D01*
G03X508411Y1068376I-1392J-167D01*
G03X507019Y1067142I0J-1402D01*
G03X506173Y1067150I-455J-3372D01*
G02X505957Y1067299I-22J199D01*
G03X503465I-1246J-325D01*
G02X503249Y1067151I-193J50D01*
G03X502473Y1067150I-384J-3381D01*
G02X502257Y1067299I-22J199D01*
G03X499765I-1246J-325D01*
G02X499549Y1067151I-193J50D01*
G03X498703Y1067141I-383J-3381D01*
G03X497311Y1068376I-1392J-167D01*
G03X495919Y1067142I0J-1402D01*
G03X495073Y1067150I-455J-3372D01*
G02X494857Y1067299I-22J199D01*
G03X492365I-1246J-325D01*
G02X492149Y1067151I-193J50D01*
G03X491303Y1067141I-383J-3381D01*
G03X489911Y1068376I-1392J-167D01*
G03X488519Y1067142I0J-1402D01*
G03X487673Y1067150I-455J-3372D01*
G02X487457Y1067299I-22J199D01*
G03X486211Y1068262I-1246J-325D01*
G03X484965Y1067298I0J-1287D01*
G02X484749Y1067150I-193J51D01*
G03X483904Y1067141I-387J-3380D01*
G03X482512Y1068376I-1392J-167D01*
G03X481120Y1067142I0J-1402D01*
G03X480203Y1067141I-455J-3372D01*
G03X478811Y1068376I-1392J-167D01*
G03X477419Y1067142I0J-1402D01*
G03X476503Y1067141I-454J-3372D01*
G03X475111Y1068376I-1392J-167D01*
G03X473719Y1067142I0J-1402D01*
G03X472803Y1067141I-454J-3372D01*
G03X471411Y1068376I-1392J-167D01*
G03X470163Y1067614I0J-1403D01*
G02X469651Y1067428I-356J182D01*
G01X468875Y1067758D01*
X468842Y1067802D01*
G03X467711Y1068376I-1131J-827D01*
G03X466309Y1066974I0J-1402D01*
G01Y1066940D01*
G02X465910Y1066530I-400J-10D01*
G01X465812D01*
G02X465413Y1066940I1J400D01*
G01Y1066974D01*
G03X462609I-1402J0D01*
G01Y1066940D01*
G02X462210Y1066530I-400J-10D01*
G01X462112D01*
G02X461713Y1066940I1J400D01*
G01Y1066974D01*
G03X458909I-1402J0D01*
G03X459247Y1066061I1402J0D01*
G01X459368Y1065920D01*
X458614Y1065166D01*
X458526Y1065171D01*
G03X458462Y1065172I-54J-1401D01*
G03X457060Y1063770I0J-1402D01*
G03X457061Y1063706I1402J-10D01*
G01X457066Y1063618D01*
X456002Y1062554D01*
X450498D01*
X448602Y1064450D01*
Y1065553D01*
X448619Y1065592D01*
G03X448912Y1066914I-3108J1382D01*
G01Y1066974D01*
G02X449046Y1067223I298J0D01*
G01X449082Y1067243D01*
G03X449144Y1067280I-572J1028D01*
G01X449148Y1067283D01*
X449150Y1067284D01*
G03X450009Y1068042I-1789J2893D01*
G01X450069Y1068116D01*
X450315D01*
G03X450699Y1068823I-2954J2062D01*
G03X451062Y1068776I360J1355D01*
G03Y1071580I0J1402D01*
G03X450891Y1071570I-4J-1402D01*
G01X450820Y1071561D01*
X450638Y1071678D01*
X450613Y1071729D01*
G03X450315Y1072241I-3252J-1550D01*
G01X450298Y1072265D01*
X450261Y1072381D01*
X450305Y1072505D01*
X450324Y1072530D01*
G03X450447Y1074045I-1114J853D01*
G01X450423Y1074090D01*
Y1074690D01*
X450452Y1074738D01*
G03X450612Y1075036I-3090J1851D01*
G01X450637Y1075087D01*
X450819Y1075204D01*
X450890Y1075195D01*
G03X451061Y1075185I167J1392D01*
G03Y1077989I0J1402D01*
G03X450847Y1077973I-3J-1402D01*
G01X450699Y1077950D01*
X450580Y1078206D01*
X450669Y1078309D01*
X451316Y1078956D01*
X451402Y1078959D01*
X451789Y1078944D01*
X451847Y1078878D01*
X451848Y1078877D01*
G03X452911Y1078389I1063J914D01*
G03X454265Y1079428I0J1402D01*
G03X455050Y1079404I502J3567D01*
G01X455120Y1079409D01*
X455304Y1079283D01*
X455327Y1079231D01*
G37*
G36*
G01X443960Y1337032D02*
X454185D01*
G02X454327Y1336973I0J-200D01*
G01X454788Y1336512D01*
G02X454847Y1336370I-141J-142D01*
G01Y1330762D01*
G02X454788Y1330620I-200J0D01*
G01X454606Y1330438D01*
G02X454464Y1330379I-142J141D01*
G01X449156D01*
G02X449014Y1330438I0J200D01*
G01X447837Y1331615D01*
X447825Y1331633D01*
G03X447377Y1332081I-1262J-814D01*
G01X447359Y1332093D01*
X447258Y1332194D01*
G03X447116Y1332253I-142J-141D01*
G01X447011D01*
X446983Y1332261D01*
G03X446563Y1332321I-420J-1442D01*
G03X446143Y1332261I0J-1502D01*
G01X446115Y1332253D01*
X444120D01*
G02X443978Y1332312I0J200D01*
G01X443156Y1333134D01*
G02X443097Y1333276I141J142D01*
G01Y1336169D01*
G02X443156Y1336311I200J0D01*
G01X443818Y1336973D01*
G02X443960Y1337032I142J-141D01*
G37*
G36*
G01X492211Y875924D02*
G03X493179Y875816I969J4295D01*
G03X494147Y875924I-1J4403D01*
G03X495029Y875612I882J1091D01*
G03X495910Y875923I0J1403D01*
G03X497848Y875924I967J4296D01*
G03X498226Y875705I883J1089D01*
G03X499286Y873931I4204J1308D01*
G03X499280Y873810I1292J-125D01*
G03X500037Y872631I1297J0D01*
G03X500387Y871751I4242J1178D01*
G01X500410Y871708D01*
Y870627D01*
X500038D01*
X500012Y870798D01*
G03X498729Y871904I-1283J-191D01*
G03X497432Y870606I0J-1297D01*
G03X497504Y870178I1297J-2D01*
G01X497535Y870091D01*
X496728Y868693D01*
X496638Y868676D01*
G03X495580Y867401I239J-1275D01*
G03X498176I1298J0D01*
G03X498103Y867828I-1298J-2D01*
G01X498073Y867915D01*
X498881Y869314D01*
X498971Y869331D01*
G03X500012Y870414I-242J1275D01*
G01X500038Y870585D01*
X500410D01*
Y869503D01*
X500387Y869460D01*
G03X500075Y868709I3892J-2057D01*
G03X499177Y867401I504J-1308D01*
G03X500026Y866113I1401J0D01*
G03X500385Y865236I3906J1087D01*
G01X500410Y865191D01*
Y864608D01*
X500076D01*
X500025Y864731D01*
G03X498729Y865599I-1296J-534D01*
G03Y862795I0J-1402D01*
G03X499726Y863211I0J1403D01*
G02X500410Y862930I284J-281D01*
G01Y862289D01*
X500259Y862251D01*
G03Y859735I319J-1258D01*
G01X500410Y859697D01*
Y858903D01*
G02X499708Y858640I-400J0D01*
G03X498729Y859086I-979J-851D01*
G03X497432Y857789I0J-1297D01*
G03X497504Y857361I1297J-2D01*
G01X497535Y857274D01*
X496728Y855876D01*
X496638Y855859D01*
G03X495580Y854584I239J-1275D01*
G03X498176I1298J0D01*
G03X498103Y855011I-1298J-2D01*
G01X498073Y855098D01*
X498881Y856497D01*
X498971Y856514D01*
G03X500012Y857597I-242J1275D01*
G01X500038Y857768D01*
X500410D01*
Y856686D01*
X500387Y856643D01*
G03X500114Y856013I3891J-2060D01*
G03X499110Y854275I466J-1428D01*
G03X498264Y852809I3310J-2887D01*
G03Y849953I466J-1428D01*
G03X499286Y848296I4166J1426D01*
G03X499280Y848176I1292J-125D01*
G03X500005Y847012I1297J0D01*
G03X500386Y846038I3989J999D01*
G01X500410Y845994D01*
Y845768D01*
X500044Y845402D01*
X499882Y845564D01*
X499868Y845589D01*
G03X498727Y846268I-1141J-619D01*
G03X497430Y844971I0J-1297D01*
G03X497541Y844444I1297J-2D01*
G01X497580Y844356D01*
X497190Y843615D01*
X496430D01*
G02X496099Y844240I0J400D01*
G03X496324Y844971I-1072J730D01*
G03X495269Y846246I-1298J0D01*
G01X495179Y846263D01*
X494372Y847661D01*
X494403Y847747D01*
G03X494476Y848176I-1224J429D01*
G03X491880I-1298J0D01*
G03X492936Y846901I1298J0D01*
G01X493026Y846884D01*
X493833Y845486D01*
X493802Y845400D01*
G03X493730Y844971I1225J-426D01*
G03X493819Y844497I1297J-2D01*
G02X493447Y843950I-372J-147D01*
G01X492907D01*
G02X492535Y844497I0J400D01*
G03X492624Y844971I-1208J472D01*
G03X490030I-1297J0D01*
G03X490168Y844389I1296J0D01*
G01X490213Y844297D01*
X490033Y843950D01*
X489207D01*
G02X488835Y844497I0J400D01*
G03X488924Y844971I-1208J472D01*
G03X487869Y846246I-1298J0D01*
G01X487779Y846263D01*
X486972Y847661D01*
X487003Y847747D01*
G03X487076Y848176I-1224J429D01*
G03X484480I-1298J0D01*
G03X485536Y846901I1298J0D01*
G01X485626Y846884D01*
X486433Y845486D01*
X486402Y845400D01*
G03X486330Y844971I1225J-426D01*
G03X486419Y844497I1297J-2D01*
G02X486047Y843950I-372J-147D01*
G01X485507D01*
G02X485135Y844497I0J400D01*
G03X485224Y844971I-1208J472D01*
G03X482630I-1297J0D01*
G03X482741Y844444I1297J-2D01*
G01X482780Y844356D01*
X482567Y843950D01*
X481807D01*
G02X481435Y844497I0J400D01*
G03X481524Y844971I-1208J472D01*
G03X480469Y846246I-1298J0D01*
G01X480379Y846263D01*
X479572Y847661D01*
X479603Y847747D01*
G03X479676Y848176I-1224J429D01*
G03X477080I-1298J0D01*
G03X478136Y846901I1298J0D01*
G01X478226Y846884D01*
X479033Y845486D01*
X479002Y845400D01*
G03X478930Y844971I1225J-426D01*
G03X479019Y844497I1297J-2D01*
G02X478647Y843950I-372J-147D01*
G01X478189D01*
X476432Y842194D01*
Y840568D01*
X477559Y839442D01*
Y825267D01*
X476812Y824520D01*
X466714D01*
X466420Y824814D01*
Y838192D01*
X464634Y839978D01*
G02X464620Y840528I283J282D01*
G03X464981Y841467I-1041J939D01*
G03X463579Y842869I-1402J0D01*
G03X462640Y842508I0J-1402D01*
G02X462090Y842522I-268J297D01*
G01X461545Y843067D01*
X461867Y843677D01*
X461962Y843695D01*
G03X463024Y844971I-236J1276D01*
G03X461727Y846268I-1297J0D01*
G03X460436Y845100I0J-1297D01*
G02X459755Y844857I-398J40D01*
G01X459272Y845340D01*
X459257Y845385D01*
G03X458720Y846068I-1230J-414D01*
G01Y849020D01*
X459213Y849512D01*
X462162D01*
G02X462496Y848892I0J-400D01*
G03X462280Y848176I1082J-717D01*
G03X463336Y846901I1298J0D01*
G01X463426Y846884D01*
X464233Y845486D01*
X464202Y845400D01*
G03X464130Y844971I1225J-426D01*
G03X466724I1297J0D01*
G03X465669Y846246I-1298J0D01*
G01X465579Y846263D01*
X464772Y847661D01*
X464803Y847747D01*
G03X464876Y848176I-1224J429D01*
G03X464219Y849304I-1297J0D01*
G02X464134Y849934I198J347D01*
G01X464446Y850246D01*
G03X465430Y849879I983J1134D01*
G03X466932Y851381I0J1502D01*
G03X465687Y852861I-1502J0D01*
G01X465522Y852890D01*
Y855482D01*
X465194Y855809D01*
G02X465466Y856492I283J283D01*
G03X466726Y857789I-38J1297D01*
G03X465668Y859064I-1297J0D01*
G01X465578Y859081D01*
X464772Y860478D01*
X464803Y860564D01*
G03X464876Y860993I-1224J429D01*
G03X462280I-1298J0D01*
G03X463336Y859718I1298J0D01*
G01X463426Y859701D01*
X464234Y858302D01*
X464203Y858215D01*
G03X464132Y857794I1226J-423D01*
G02X463449Y857513I-400J2D01*
G01X463307Y857655D01*
X463034D01*
X463025Y857846D01*
G03X460433I-1296J-57D01*
G01X460424Y857655D01*
X459334D01*
X459325Y857846D01*
G03X458268Y859064I-1296J-57D01*
G01X458178Y859081D01*
X457372Y860478D01*
X457403Y860564D01*
G03X457476Y860993I-1224J429D01*
G03X456810Y862126I-1297J0D01*
G01X456707Y862184D01*
Y862649D01*
G02X457312Y862992I400J0D01*
G03X458029Y862795I717J1206D01*
G03Y865599I0J1402D01*
G03X457312Y865402I0J-1403D01*
G02X456707Y865745I-205J343D01*
G01Y866096D01*
X456816Y866152D01*
G03Y868650I-637J1249D01*
G01X456707Y868706D01*
Y869181D01*
G02X457324Y869517I400J0D01*
G03X458029Y869308I706J1089D01*
G03X459326Y870606I0J1297D01*
G03X458268Y871881I-1297J0D01*
G01X458178Y871898D01*
X457372Y873295D01*
X457403Y873381D01*
G03X457476Y873810I-1224J429D01*
G03X457473Y873891I-1298J-8D01*
G03X458459Y875387I-2877J2969D01*
G01X458979Y875907D01*
X459082Y875888D01*
G03X460848Y875924I795J4331D01*
G03X461729Y875612I882J1090D01*
G03X462611Y875924I0J1403D01*
G03X463579Y875816I969J4295D01*
G03X464547Y875924I-1J4403D01*
G03X465429Y875612I882J1091D01*
G03X466310Y875923I0J1403D01*
G03X468248Y875924I967J4296D01*
G03X469129Y875612I882J1090D01*
G03X470011Y875924I0J1403D01*
G03X470979Y875816I969J4295D01*
G03X471947Y875924I-1J4403D01*
G03X472829Y875612I882J1091D01*
G03X473710Y875923I0J1403D01*
G03X475648Y875924I967J4296D01*
G03X476529Y875612I882J1090D01*
G03X477411Y875924I0J1403D01*
G03X478379Y875816I969J4295D01*
G03X479347Y875924I-1J4403D01*
G03X480229Y875612I882J1091D01*
G03X481110Y875923I0J1403D01*
G03X483048Y875924I967J4296D01*
G03X483929Y875612I882J1090D01*
G03X484811Y875924I0J1403D01*
G03X485779Y875816I969J4295D01*
G03X486747Y875924I-1J4403D01*
G03X487629Y875612I882J1091D01*
G03X488510Y875923I0J1403D01*
G03X490448Y875924I967J4296D01*
G03X491329Y875612I882J1090D01*
G03X492211Y875924I0J1403D01*
G37*
G36*
G01X462750Y934345D02*
X470290D01*
X470515Y934120D01*
Y931010D01*
X472675Y928850D01*
Y924930D01*
X471985Y924240D01*
X464751D01*
X464035Y924956D01*
G03X463203Y925300I-831J-832D01*
G01X457965D01*
Y925799D01*
X457981Y925837D01*
G03X458129Y926551I-1654J715D01*
G03X457981Y927265I-1802J-1D01*
G01X457965Y927303D01*
Y928890D01*
X458205Y929130D01*
X461185D01*
X462125Y930070D01*
Y933720D01*
X462750Y934345D01*
G37*
G36*
G01X463074Y957318D02*
X466596D01*
X466766Y957148D01*
X467095Y956820D01*
Y955580D01*
X468016Y954658D01*
Y949266D01*
X467320Y948570D01*
X455065D01*
X454838Y948344D01*
X454765Y948270D01*
X453815D01*
X453742Y948344D01*
X453446Y948640D01*
Y954270D01*
X454060Y954884D01*
X461063D01*
G03X461094Y954885I-23J1201D01*
G01X461560D01*
X461895Y955220D01*
X461896Y955221D01*
G03X461913Y955237I-815J883D01*
G01X462031Y955356D01*
X462060Y955370D01*
G03X462826Y956620I-637J1250D01*
G03X462795Y956912I-1402J-1D01*
G01X462773Y957018D01*
X463074Y957318D01*
G37*
G36*
G01X463621Y971966D02*
X466959D01*
X467325Y971600D01*
Y970100D01*
X468105Y969320D01*
X476835D01*
X477254Y968900D01*
Y964368D01*
G03Y962692I1124J-838D01*
G01Y959656D01*
X476704Y959106D01*
X475854D01*
X475492Y959468D01*
Y962950D01*
X475098Y963344D01*
X455184D01*
X454854Y963015D01*
X454852Y963013D01*
G03X454831Y962992I839J-860D01*
G01X454697Y962858D01*
X454055D01*
X453538Y963376D01*
Y967332D01*
X455555Y969350D01*
X462125D01*
X462462Y969687D01*
X462463Y969688D01*
G03X462480Y969704I-815J883D01*
G01X462713Y969937D01*
G03X462729Y969954I-867J832D01*
G01X462730Y969955D01*
X463065Y970290D01*
Y970756D01*
G03X463066Y970787I-1200J54D01*
G01Y971410D01*
X463106Y971451D01*
Y971452D01*
X463621Y971966D01*
G37*
G36*
G01X475745Y1023310D02*
X476845D01*
X477095Y1023060D01*
Y983323D01*
X477080Y983286D01*
G03Y982226I1298J-530D01*
G01X477095Y982189D01*
Y977301D01*
X476714Y976920D01*
X475782D01*
X474761Y977941D01*
X467882D01*
G03X467851Y977942I-54J-1200D01*
G01X454884D01*
Y977940D01*
X453805D01*
X453416Y978330D01*
Y982040D01*
X453536Y982161D01*
Y982162D01*
X455215Y983840D01*
X461465D01*
X461818Y984193D01*
X461819Y984194D01*
G03X461836Y984210I-815J883D01*
G01X461878Y984253D01*
X461919Y984268D01*
G03X462826Y985580I-495J1312D01*
G03X462795Y985872I-1402J-1D01*
G01X462773Y985979D01*
X463124Y986330D01*
X466830D01*
X467064Y986096D01*
Y985727D01*
G03X467065Y985696I1201J23D01*
G01Y985230D01*
X467400Y984895D01*
X467401Y984894D01*
G03X467417Y984877I883J815D01*
G01X468004Y984291D01*
G03X468018Y984277I857J843D01*
G01X468019Y984276D01*
X468355Y983940D01*
X474099D01*
X474470Y984311D01*
X474482Y984323D01*
X475254Y985094D01*
G03X475277Y985117I-838J861D01*
G01X475278Y985119D01*
X475607Y985447D01*
Y985913D01*
G03X475608Y985944I-1200J54D01*
G01Y990958D01*
G03X475607Y990990I-1201J-22D01*
G01Y991583D01*
X475031Y992159D01*
X474438D01*
G03X474406Y992160I-54J-1200D01*
G01X455236D01*
X455216Y992140D01*
X454005D01*
X453666Y992478D01*
Y992479D01*
X453626Y992520D01*
Y996270D01*
X454245Y996890D01*
X455705Y998350D01*
X461475D01*
X461818Y998693D01*
X461819Y998694D01*
G03X461836Y998710I-815J883D01*
G01X461878Y998753D01*
X461919Y998768D01*
G03X462826Y1000080I-495J1312D01*
G03X462794Y1000379I-1402J1D01*
G01X462771Y1000486D01*
X463191Y1000906D01*
X466648D01*
X466854Y1000698D01*
X466856D01*
X467176Y1000378D01*
X467354Y1000200D01*
Y999688D01*
G03X467355Y999656I1201J22D01*
G01Y999190D01*
X467690Y998855D01*
X467691Y998854D01*
G03X467707Y998837I883J815D01*
G01X467824Y998721D01*
G03X467838Y998707I857J843D01*
G01X467839Y998706D01*
X468175Y998370D01*
X474507D01*
X475518Y999381D01*
Y1006018D01*
X474890Y1006646D01*
X454848D01*
X454512Y1006310D01*
X454511Y1006309D01*
G03X454497Y1006295I843J-857D01*
G01X454414Y1006212D01*
X453953D01*
X453908Y1006258D01*
X453786Y1006378D01*
Y1006379D01*
X453566Y1006600D01*
Y1009560D01*
X453786Y1009781D01*
Y1009782D01*
X455575Y1011570D01*
Y1012819D01*
X455805Y1013048D01*
X461104D01*
G03X461135Y1013049I-23J1201D01*
G01X461601D01*
X461728Y1013176D01*
X461770Y1013191D01*
G03X462697Y1014510I-475J1319D01*
G03X462528Y1015178I-1402J1D01*
G01X462504Y1015223D01*
Y1015616D01*
X462503D01*
Y1015762D01*
X461977Y1016288D01*
X454237D01*
X453610Y1016915D01*
Y1022685D01*
X453913Y1022988D01*
X454470D01*
X455497Y1021961D01*
X474396D01*
X475745Y1023310D01*
G37*
G36*
G01X466670Y1037870D02*
X468175D01*
X468260Y1037785D01*
G03X468724Y1037592I465J464D01*
G01X473375D01*
X474270Y1036698D01*
Y1032195D01*
X473910Y1031835D01*
X471770D01*
X470455Y1030520D01*
X466555D01*
X466320Y1030754D01*
Y1037520D01*
X466670Y1037870D01*
G37*
G36*
G01X456030Y1029445D02*
X467570D01*
X468365Y1028650D01*
Y1023350D01*
X467978Y1022962D01*
X456032D01*
X455525Y1023470D01*
Y1028940D01*
X456030Y1029445D01*
G37*
G36*
G01X457307Y1038170D02*
X464025D01*
X464245Y1037950D01*
Y1030790D01*
X463925Y1030470D01*
X456875D01*
X456175Y1031170D01*
Y1037280D01*
G02X456368Y1037480I200J0D01*
G03X456809Y1037672I-23J656D01*
G01X457307Y1038170D01*
G37*
G36*
G01X471921Y935815D02*
X476603D01*
X477204Y935214D01*
Y932254D01*
G03Y930722I1173J-766D01*
G01Y929309D01*
X476935Y929040D01*
X474448D01*
X471516Y931972D01*
Y934535D01*
X471465Y934586D01*
Y935359D01*
X471921Y935815D01*
G37*
G36*
G01X469798Y948640D02*
X476029D01*
X477325Y947344D01*
Y945070D01*
G03X477118Y944632I1053J-766D01*
G01X477104Y944579D01*
X476685Y944160D01*
X469822D01*
X469320Y944662D01*
Y948162D01*
X469798Y948640D01*
G37*
G36*
G01X477124Y958110D02*
X479475D01*
X480694Y956891D01*
X480706Y956833D01*
G03X481428Y955880I1372J289D01*
G01X481535Y955824D01*
Y952011D01*
X481428Y951955D01*
G03Y949471I652J-1242D01*
G01X481535Y949415D01*
Y946550D01*
X481045Y946060D01*
X480025D01*
X476415Y949670D01*
X469912D01*
X469320Y950262D01*
Y954162D01*
X469726Y954568D01*
X474257D01*
G03X474655Y954637I-3J1202D01*
G01X474687Y954648D01*
X475134D01*
X476340Y955855D01*
Y957535D01*
X476910Y958104D01*
X477119D01*
X477124Y958110D01*
G37*
G36*
G01X468775Y943100D02*
X475655D01*
X476035Y942720D01*
Y937190D01*
X475745Y936900D01*
X471965D01*
X471685Y937180D01*
Y939920D01*
X471184Y940420D01*
Y940573D01*
X470388Y941370D01*
X468987D01*
X468572Y941785D01*
Y942896D01*
X468775Y943100D01*
G37*
G36*
G01X469484Y976940D02*
X474346D01*
X475367Y975918D01*
X476246D01*
X477425Y974740D01*
Y970966D01*
G03X477073Y970449I954J-1028D01*
G01X477023Y970322D01*
X468520D01*
X468326Y970515D01*
Y972015D01*
X468193Y972148D01*
X468686Y972640D01*
G03X468702Y972657I-867J832D01*
G01X468703Y972658D01*
X469065Y973020D01*
Y976520D01*
X469484Y976940D01*
G37*
G36*
G01X475665Y1032740D02*
X477165D01*
X477565Y1032340D01*
Y1029167D01*
X477546Y1029126D01*
G03X477409Y1028523I1265J-604D01*
G03X477546Y1027920I1402J1D01*
G01X477565Y1027879D01*
Y1024800D01*
X477300Y1024535D01*
X475470D01*
X474085Y1023150D01*
X469905D01*
X469665Y1023390D01*
Y1029320D01*
X469864Y1029518D01*
X470870D01*
X472141Y1030790D01*
X474315D01*
X475465Y1031940D01*
Y1032540D01*
X475665Y1032740D01*
G37*
G36*
G01X475570Y1337087D02*
X485574D01*
G02X485716Y1337028I0J-200D01*
G01X486146Y1336598D01*
G02X486205Y1336456I-141J-142D01*
G01Y1331915D01*
X486227Y1331893D01*
Y1331098D01*
G02X486168Y1330956I-200J0D01*
G01X485886Y1330674D01*
G02X485744Y1330615I-142J141D01*
G01X480961D01*
G02X480819Y1330674I0J200D01*
G01X480064Y1331429D01*
X480049Y1331460D01*
G03X478691Y1332321I-1358J-640D01*
G03X477565Y1331814I-1J-1502D01*
G02X477416Y1331746I-150J132D01*
G01X476190D01*
G02X476048Y1331805I0J200D01*
G01X474966Y1332887D01*
G02X474907Y1333029I141J142D01*
G01Y1336424D01*
G02X474966Y1336566I200J0D01*
G01X475428Y1337028D01*
G02X475570Y1337087I142J-141D01*
G37*
G36*
G01X483485Y1578182D02*
G03I-574J0D01*
G37*
G36*
G01X479225D02*
G03I-574J0D01*
G37*
G36*
G01X471425D02*
G03I-574J0D01*
G37*
G36*
G01X483485Y1590094D02*
G03I-574J0D01*
G37*
G36*
G01X479225D02*
G03I-574J0D01*
G37*
G36*
G01X471425D02*
G03I-574J0D01*
G37*
G36*
G01X484525Y1614292D02*
G03I-574J0D01*
G37*
G36*
G01Y1602380D02*
G03I-574J0D01*
G37*
G36*
G01X476725D02*
G03I-574J0D01*
G37*
G36*
G01Y1614292D02*
G03I-574J0D01*
G37*
G36*
G01X887008Y142878D02*
X1011024D01*
G02X1022898Y131004I0J-11874D01*
G03X1022904Y127139I1291667J73D01*
G02Y127067I-11880J-36D01*
G01Y54252D01*
G03X1026772Y50384I3868J0D01*
G01X1518118D01*
G02X1529998Y38504I0J-11880D01*
G01Y15466D01*
X1529977Y15423D01*
G03X1528452Y12480I2077J-2943D01*
G03X1529199Y10283I3604J0D01*
G03X1529920Y9558I2889J2152D01*
G01X1529998Y9402D01*
Y4000D01*
X1792064D01*
Y9351D01*
X1792147Y9512D01*
G03X1792960Y14545I-2105J2922D01*
G03X1792128Y15392I-2951J-2067D01*
G01X1792064Y15517D01*
Y38504D01*
G02X1803945Y50384I11881J-1D01*
G01X1849606D01*
G03X1853474Y54252I0J3868D01*
G01Y70591D01*
X1853572Y70761D01*
G03X1854844Y71565I-9875J17032D01*
G01X1854889Y71596D01*
X1855001Y71603D01*
X1855363Y71412D01*
G02X1855470Y71235I-93J-177D01*
G01Y54252D01*
G02X1849606Y48388I-5864J0D01*
G01X1803945D01*
G03X1794061Y38504I0J-9884D01*
G01Y5140D01*
X1794070D01*
Y3937D01*
G02X1792134Y2001I-1936J0D01*
G01X1529929D01*
G02X1527993Y3937I0J1936D01*
G01Y5140D01*
X1528002D01*
Y38504D01*
G03X1518118Y48388I-9884J0D01*
G01X1026772D01*
G02X1020908Y54252I0J5864D01*
G01Y127067D01*
G02X1020898Y131004I774993J3937D01*
G03X1011024Y140878I-9874J0D01*
G01X887008D01*
G03X877134Y131004I0J-9874D01*
G03X877124Y127067I774993J-3937D01*
G01Y54252D01*
G02X871260Y48388I-5864J0D01*
G01X774417D01*
G03X764533Y38504I0J-9884D01*
G01Y25740D01*
X764542D01*
Y24724D01*
G02X762606Y22788I-1936J0D01*
G01X500402D01*
G02X498466Y24724I0J1936D01*
G01Y25740D01*
X498475D01*
Y30489D01*
G02X498675Y30688I200J-1D01*
G01X498769Y30665D01*
G03X499475Y30489I706J1328D01*
G03X499978Y30576I-1J1503D01*
G02X500176Y30539I67J-189D01*
G03X500391Y30367I2356J2724D01*
G01X500472Y30208D01*
Y24787D01*
X762536D01*
Y30209D01*
X762617Y30368D01*
G03Y36166I-2138J2899D01*
G01X762536Y36325D01*
Y38504D01*
G02X774417Y50384I11881J-1D01*
G01X871260D01*
G03X875128Y54252I0J3868D01*
G01Y127067D01*
X875134Y131004D01*
G02X887008Y142878I11874J0D01*
G37*
G36*
G01X500730Y106272D02*
X505480D01*
X506120Y105632D01*
Y105472D01*
X506500Y105092D01*
X508970D01*
X509080Y104982D01*
Y104702D01*
X508960Y104582D01*
X506240D01*
X506040Y104382D01*
Y103782D01*
X506170Y103652D01*
X509040D01*
X509150Y103542D01*
Y103252D01*
X508930Y103032D01*
X506060D01*
Y102452D01*
X506240Y102272D01*
X509030D01*
X509120Y102182D01*
Y101922D01*
X508920Y101722D01*
X506130D01*
X506070Y101662D01*
Y100782D01*
X505930Y100642D01*
X500850D01*
X500520Y100972D01*
Y101632D01*
X500330Y101822D01*
X497550D01*
X497480Y101892D01*
Y102222D01*
X497580Y102322D01*
X500500D01*
X500580Y102402D01*
Y103152D01*
X500520Y103212D01*
X497530D01*
X497450Y103292D01*
Y103582D01*
X497580Y103712D01*
X500470D01*
X500530Y103772D01*
Y104372D01*
X500320Y104582D01*
X497570D01*
X497490Y104662D01*
Y104962D01*
X497600Y105072D01*
X499960D01*
X500670Y105782D01*
Y106212D01*
X500730Y106272D01*
G37*
G36*
G01X495545Y1578182D02*
G03I-574J0D01*
G37*
G36*
G01X491285D02*
G03I-574J0D01*
G37*
G36*
G01X495545Y1590094D02*
G03I-574J0D01*
G37*
G36*
G01X491285D02*
G03I-574J0D01*
G37*
G36*
G01X500845Y1614292D02*
G03I-574J0D01*
G37*
G36*
G01Y1602380D02*
G03I-574J0D01*
G37*
G36*
G01X488785Y1614292D02*
G03I-574J0D01*
G37*
G36*
G01Y1602380D02*
G03I-574J0D01*
G37*
G36*
G01X496585D02*
G03I-574J0D01*
G37*
G36*
G01Y1614292D02*
G03I-574J0D01*
G37*
G36*
G01X508350Y1350564D02*
X517005D01*
G02X517147Y1350505I0J-200D01*
G01X517999Y1349653D01*
G02X518058Y1349511I-141J-142D01*
G01Y1345083D01*
G02X517999Y1344941I-200J0D01*
G01X517942Y1344884D01*
G02X517800Y1344825I-142J141D01*
G01X512275D01*
X512180Y1344883D01*
X512154Y1344933D01*
G03X509484I-1335J-688D01*
G01X509458Y1344883D01*
X509363Y1344825D01*
X508190D01*
G02X508048Y1344884I0J200D01*
G01X507316Y1345616D01*
G02X507257Y1345758I141J142D01*
G01Y1349471D01*
G02X507316Y1349613I200J0D01*
G01X508208Y1350505D01*
G02X508350Y1350564I142J-141D01*
G37*
G36*
G01X507605Y1578182D02*
G03I-574J0D01*
G37*
G36*
G01X515405D02*
G03I-574J0D01*
G37*
G36*
G01X503345D02*
G03I-574J0D01*
G37*
G36*
G01X507605Y1590094D02*
G03I-574J0D01*
G37*
G36*
G01X515405D02*
G03I-574J0D01*
G37*
G36*
G01X503345D02*
G03I-574J0D01*
G37*
G36*
G01X512905Y1614292D02*
G03I-574J0D01*
G37*
G36*
G01Y1602380D02*
G03I-574J0D01*
G37*
G36*
G01X508645Y1614292D02*
G03I-574J0D01*
G37*
G36*
G01Y1602380D02*
G03I-574J0D01*
G37*
G36*
G01X531725Y1578182D02*
G03I-574J0D01*
G37*
G36*
G01X519665D02*
G03I-574J0D01*
G37*
G36*
G01X527465D02*
G03I-574J0D01*
G37*
G36*
G01X531725Y1590094D02*
G03I-574J0D01*
G37*
G36*
G01X519665D02*
G03I-574J0D01*
G37*
G36*
G01X527465D02*
G03I-574J0D01*
G37*
G36*
G01X532765Y1614292D02*
G03I-574J0D01*
G37*
G36*
G01Y1602380D02*
G03I-574J0D01*
G37*
G36*
G01X524965Y1614292D02*
G03I-574J0D01*
G37*
G36*
G01Y1602380D02*
G03I-574J0D01*
G37*
G36*
G01X520705D02*
G03I-574J0D01*
G37*
G36*
G01Y1614292D02*
G03I-574J0D01*
G37*
G36*
G01X539908Y1371831D02*
X548542D01*
G02X548684Y1371772I0J-200D01*
G01X549850Y1370607D01*
G02X549909Y1370465I-141J-142D01*
G01Y1366998D01*
G02X549850Y1366856I-200J0D01*
G01X549714Y1366720D01*
G02X549572Y1366661I-142J141D01*
G01X544849D01*
G02X544708Y1366719I0J200D01*
G01X544480Y1366945D01*
X544449Y1367017D01*
Y1367057D01*
G03X542947Y1368545I-1502J-14D01*
G03X542666Y1368519I-3J-1502D01*
G01X542648Y1368515D01*
X539758D01*
G02X539616Y1368574I0J200D01*
G01X539496Y1368694D01*
G02X539437Y1368836I141J142D01*
G01Y1371360D01*
G02X539496Y1371502I200J0D01*
G01X539766Y1371772D01*
G02X539908Y1371831I142J-141D01*
G37*
G36*
G01X543785Y1578182D02*
G03I-574J0D01*
G37*
G36*
G01X539525D02*
G03I-574J0D01*
G37*
G36*
G01X543785Y1590094D02*
G03I-574J0D01*
G37*
G36*
G01X539525D02*
G03I-574J0D01*
G37*
G36*
G01X549085Y1614292D02*
G03I-574J0D01*
G37*
G36*
G01Y1602380D02*
G03I-574J0D01*
G37*
G36*
G01X537025D02*
G03I-574J0D01*
G37*
G36*
G01Y1614292D02*
G03I-574J0D01*
G37*
G36*
G01X544825Y1602380D02*
G03I-574J0D01*
G37*
G36*
G01Y1614292D02*
G03I-574J0D01*
G37*
G36*
G01X552713Y113527D02*
Y110327D01*
Y107999D01*
X552763Y107949D01*
X553245D01*
X553413Y108117D01*
Y110327D01*
Y113527D01*
Y115808D01*
X553314Y115907D01*
X552820D01*
X552713Y115800D01*
Y113527D01*
G37*
G36*
G01D02*
Y110327D01*
Y107999D01*
X552763Y107949D01*
X553245D01*
X553413Y108117D01*
Y110327D01*
Y113527D01*
Y115808D01*
X553314Y115907D01*
X552820D01*
X552713Y115800D01*
Y113527D01*
G37*
G36*
G01X554287D02*
Y110327D01*
Y108005D01*
X554399Y107893D01*
X554914D01*
X554987Y107966D01*
Y110327D01*
Y113527D01*
Y115940D01*
X554921Y116006D01*
X554394D01*
X554287Y115899D01*
Y113527D01*
G37*
G36*
G01D02*
Y110327D01*
Y108005D01*
X554399Y107893D01*
X554914D01*
X554987Y107966D01*
Y110327D01*
Y113527D01*
Y115940D01*
X554921Y116006D01*
X554394D01*
X554287Y115899D01*
Y113527D01*
G37*
G36*
G01X555845Y1578182D02*
G03I-574J0D01*
G37*
G36*
G01X563645D02*
G03I-574J0D01*
G37*
G36*
G01X551585D02*
G03I-574J0D01*
G37*
G36*
G01X555845Y1590094D02*
G03I-574J0D01*
G37*
G36*
G01X563645D02*
G03I-574J0D01*
G37*
G36*
G01X551585D02*
G03I-574J0D01*
G37*
G36*
G01X561145Y1614292D02*
G03I-574J0D01*
G37*
G36*
G01Y1602380D02*
G03I-574J0D01*
G37*
G36*
G01X556885Y1614292D02*
G03I-574J0D01*
G37*
G36*
G01Y1602380D02*
G03I-574J0D01*
G37*
G36*
G01X579965Y1578182D02*
G03I-574J0D01*
G37*
G36*
G01X567905D02*
G03I-574J0D01*
G37*
G36*
G01X575705D02*
G03I-574J0D01*
G37*
G36*
G01X579965Y1590094D02*
G03I-574J0D01*
G37*
G36*
G01X567905D02*
G03I-574J0D01*
G37*
G36*
G01X575705D02*
G03I-574J0D01*
G37*
G36*
G01X581005Y1614292D02*
G03I-574J0D01*
G37*
G36*
G01X573205D02*
G03I-574J0D01*
G37*
G36*
G01X581005Y1602380D02*
G03I-574J0D01*
G37*
G36*
G01X573205D02*
G03I-574J0D01*
G37*
G36*
G01X568945D02*
G03I-574J0D01*
G37*
G36*
G01Y1614292D02*
G03I-574J0D01*
G37*
G36*
G01X593882Y155572D02*
X596600D01*
X597270Y154902D01*
Y140762D01*
X596020Y139512D01*
X587120D01*
X585620Y141012D01*
Y154612D01*
X586580Y155572D01*
X591538D01*
G03X593882I1172J771D01*
G37*
G36*
G01X592025Y1578182D02*
G03I-574J0D01*
G37*
G36*
G01X587765D02*
G03I-574J0D01*
G37*
G36*
G01X592025Y1590094D02*
G03I-574J0D01*
G37*
G36*
G01X587765D02*
G03I-574J0D01*
G37*
G36*
G01X597325Y1614292D02*
G03I-574J0D01*
G37*
G36*
G01Y1602380D02*
G03I-574J0D01*
G37*
G36*
G01X585265D02*
G03I-574J0D01*
G37*
G36*
G01Y1614292D02*
G03I-574J0D01*
G37*
G36*
G01X593065Y1602380D02*
G03I-574J0D01*
G37*
G36*
G01Y1614292D02*
G03I-574J0D01*
G37*
G36*
G01X612688Y156600D02*
X624992D01*
X626688Y154904D01*
Y142587D01*
X626690Y142586D01*
Y141702D01*
X627390Y141002D01*
X633790D01*
X634090Y140702D01*
Y137702D01*
X633590Y137202D01*
X613090D01*
X611190Y139102D01*
Y155102D01*
X612688Y156600D01*
G37*
G36*
G01X609410Y163822D02*
X636450D01*
X638825Y161447D01*
Y157267D01*
X638890Y157202D01*
Y146754D01*
X636963Y142102D01*
X628590D01*
X627690Y143002D01*
Y156802D01*
X626890Y157602D01*
X611590D01*
X609690Y155702D01*
Y142402D01*
X609290Y142002D01*
X606290D01*
X604890Y143402D01*
Y159302D01*
X605571Y159983D01*
X605688Y159943D01*
G03X606260Y159850I571J1709D01*
G03X608062Y161652I0J1802D01*
G03X607969Y162224I-1802J1D01*
G01X607929Y162341D01*
X609410Y163822D01*
G37*
G36*
G01X630528Y1015823D02*
X643617D01*
X644543Y1014897D01*
Y1010507D01*
X645611Y1009439D01*
X653304D01*
X653650Y1009092D01*
Y1002818D01*
G02X653125Y1002438I-400J0D01*
G03X652577Y1002526I-548J-1662D01*
G03X650826Y1000775I0J-1751D01*
G01Y993984D01*
X649227Y992385D01*
Y991300D01*
X649223Y991281D01*
G03X649197Y991011I1376J-269D01*
G03X649223Y990741I1402J-1D01*
G01X649227Y990722D01*
Y987574D01*
X647957Y986304D01*
X647266D01*
G02X646927Y986917I0J400D01*
G03X647143Y987664I-1186J748D01*
G03X644339I-1402J0D01*
G03X644555Y986917I1402J1D01*
G02X644216Y986304I-339J-213D01*
G01X638566D01*
G02X638227Y986917I0J400D01*
G03X638443Y987664I-1186J748D01*
G03X635639I-1402J0D01*
G03X635855Y986917I1402J1D01*
G02X635516Y986304I-339J-213D01*
G01X621268D01*
X621247Y986325D01*
X617067D01*
X612800Y990592D01*
Y1014462D01*
X613516Y1015178D01*
X629884D01*
X630528Y1015823D01*
G37*
G36*
G01X599825Y1578182D02*
G03I-574J0D01*
G37*
G36*
G01X604085D02*
G03I-574J0D01*
G37*
G36*
G01X611885D02*
G03I-574J0D01*
G37*
G36*
G01X599825Y1590094D02*
G03I-574J0D01*
G37*
G36*
G01X604085D02*
G03I-574J0D01*
G37*
G36*
G01X611885D02*
G03I-574J0D01*
G37*
G36*
G01X609385Y1602380D02*
G03I-574J0D01*
G37*
G36*
G01Y1614292D02*
G03I-574J0D01*
G37*
G36*
G01X605125Y1602380D02*
G03I-574J0D01*
G37*
G36*
G01Y1614292D02*
G03I-574J0D01*
G37*
G36*
G01X626764Y747585D02*
G03I-557J0D01*
G37*
G36*
G01X620210Y985324D02*
X620832D01*
X620853Y985302D01*
X645752D01*
X646764Y984291D01*
Y979660D01*
X645546Y978442D01*
X633357D01*
X631225Y980573D01*
G03X630337Y980942I-889J-887D01*
G01X619748D01*
X619660Y981029D01*
Y984774D01*
X620210Y985324D01*
G37*
G36*
G01X636613Y1028874D02*
X647541D01*
X651630Y1024785D01*
Y1014515D01*
G03X651773Y1013933I1256J0D01*
G01X651796Y1013890D01*
Y1010791D01*
X645714D01*
X645544Y1010960D01*
Y1015312D01*
X645312Y1015544D01*
Y1016268D01*
X644509Y1017071D01*
X630690D01*
X630444Y1016824D01*
X630113D01*
X629799Y1016510D01*
X617652D01*
X617057Y1017105D01*
Y1024725D01*
X618137Y1025805D01*
X633544D01*
X636613Y1028874D01*
G37*
G36*
G01X620730Y1314082D02*
X857580D01*
X860800Y1310862D01*
Y1260242D01*
X860522Y1259964D01*
X845603D01*
X845561Y1259985D01*
G03X844941Y1260129I-619J-1258D01*
G03X844321Y1259985I-1J-1402D01*
G01X844279Y1259964D01*
X831101D01*
G03X829861Y1260478I-1239J-1237D01*
G01X828799D01*
G03X828631Y1260470I-1J-1751D01*
G02X828258Y1261088I-38J398D01*
G03X828552Y1262074I-1508J986D01*
G03X824948I-1802J0D01*
G03X825615Y1260675I1801J0D01*
G02X825363Y1259964I-252J-311D01*
G01X816964D01*
X816948Y1259967D01*
G03X816743Y1259984I-206J-1240D01*
G01X813732D01*
G03X812440Y1260529I-1291J-1257D01*
G03X811130Y1259964I0J-1801D01*
G01X801401D01*
G03X800161Y1260478I-1239J-1237D01*
G01X799099D01*
G03X797914Y1260017I-1J-1751D01*
G01X797857Y1259964D01*
X797280D01*
Y1260311D01*
X797420Y1260355D01*
G03X798682Y1262074I-540J1719D01*
G03X795078I-1802J0D01*
G03X795745Y1260675I1801J0D01*
G02X795493Y1259964I-252J-311D01*
G01X787906D01*
X787890Y1259967D01*
G03X787685Y1259984I-206J-1240D01*
G01X784830D01*
X784777Y1260102D01*
G03X783130Y1261174I-1647J-729D01*
G03X781475Y1260085I0J-1802D01*
G01X781423Y1259964D01*
X771701D01*
G03X770461Y1260478I-1239J-1237D01*
G01X769399D01*
G03X768214Y1260017I-1J-1751D01*
G01X768157Y1259964D01*
X767480D01*
Y1260311D01*
X767620Y1260355D01*
G03X768882Y1262074I-540J1719D01*
G03X765278I-1802J0D01*
G03X765945Y1260675I1801J0D01*
G02X765693Y1259964I-252J-311D01*
G01X759627D01*
X759248Y1260342D01*
G03X758360Y1260710I-888J-887D01*
G01X755418D01*
X754804Y1261325D01*
X754801Y1261405D01*
G03X753000Y1263154I-1801J-53D01*
G03X751198Y1261352I0J-1802D01*
G03X751390Y1260543I1802J0D01*
G02X751032Y1259964I-358J-179D01*
G01X742001D01*
G03X740761Y1260478I-1239J-1237D01*
G01X739429D01*
G02X739093Y1261096I0J400D01*
G03X739382Y1262074I-1513J979D01*
G03X735778I-1802J0D01*
G03X736067Y1261096I1802J1D01*
G02X735731Y1260478I-336J-218D01*
G01X734634D01*
G03X733394Y1259964I-1J-1751D01*
G01X727329D01*
X727313Y1259967D01*
G03X727108Y1259984I-206J-1240D01*
G01X724992D01*
G03X723700Y1260529I-1291J-1257D01*
G03X722390Y1259964I0J-1801D01*
G01X712301D01*
G03X711061Y1260478I-1239J-1237D01*
G01X709999D01*
X709950D01*
G02X709603Y1261095I-11J400D01*
G03X709892Y1262074I-1514J979D01*
G03X706288I-1802J0D01*
G03X707001Y1260638I1803J0D01*
G02X706841Y1260283I-121J-159D01*
G03X706598Y1260306I-239J-1233D01*
G01X704947D01*
G03X704085Y1259964I0J-1257D01*
G01X701444D01*
X701283Y1260124D01*
G03X700395Y1260492I-888J-887D01*
G01X696946D01*
X695904Y1261535D01*
X695901Y1261615D01*
G03X694100Y1263364I-1801J-53D01*
G03X692298Y1261562I0J-1802D01*
G03X692588Y1260582I1801J0D01*
G02X692252Y1259964I-335J-218D01*
G01X682601D01*
G03X681361Y1260478I-1239J-1237D01*
G01X680299D01*
G03X679114Y1260017I-1J-1751D01*
G01X679057Y1259964D01*
X678380D01*
Y1260311D01*
X678520Y1260355D01*
G03X679782Y1262074I-540J1719D01*
G03X676178I-1802J0D01*
G03X676845Y1260675I1801J0D01*
G02X676593Y1259964I-252J-311D01*
G01X666360D01*
X666311Y1260092D01*
G03X662949I-1681J-650D01*
G01X662900Y1259964D01*
X652901D01*
G03X651661Y1260478I-1239J-1237D01*
G01X650599D01*
G03X650023Y1260381I-1J-1751D01*
G02X649491Y1260768I-132J378D01*
G03X649492Y1260812I-1801J63D01*
G03X647690Y1262614I-1802J0D01*
G03X645889Y1260865I0J-1802D01*
G01X645886Y1260785D01*
X645065Y1259964D01*
X635403D01*
G03X634213Y1260430I-1190J-1285D01*
G03X633077Y1260012I-1J-1751D01*
G01X633021Y1259964D01*
X632480D01*
Y1260311D01*
X632620Y1260355D01*
G03X633882Y1262074I-540J1719D01*
G03X630278I-1802J0D01*
G03X631540Y1260355I1802J0D01*
G01X631680Y1260311D01*
Y1259964D01*
X631173D01*
X631116Y1260017D01*
G03X629931Y1260478I-1184J-1290D01*
G03X629053Y1260242I0J-1751D01*
G01X627835D01*
G03X626887Y1259964I-1J-1751D01*
G01X621680D01*
X621673Y1259971D01*
X619350D01*
G03X618549Y1260172I-802J-1501D01*
G01X618114D01*
G03X617992Y1260167I9J-1702D01*
G01X617901Y1260161D01*
X616907Y1261155D01*
Y1310259D01*
X620730Y1314082D01*
G37*
G36*
G01X616145Y1578182D02*
G03I-574J0D01*
G37*
G36*
G01X628205D02*
G03I-574J0D01*
G37*
G36*
G01X623945D02*
G03I-574J0D01*
G37*
G36*
G01X616145Y1590094D02*
G03I-574J0D01*
G37*
G36*
G01X628205D02*
G03I-574J0D01*
G37*
G36*
G01X623945D02*
G03I-574J0D01*
G37*
G36*
G01X629245Y1602380D02*
G03I-574J0D01*
G37*
G36*
G01Y1614292D02*
G03I-574J0D01*
G37*
G36*
G01X621445D02*
G03I-574J0D01*
G37*
G36*
G01Y1602380D02*
G03I-574J0D01*
G37*
G36*
G01X617185Y1614292D02*
G03I-574J0D01*
G37*
G36*
G01Y1602380D02*
G03I-574J0D01*
G37*
G36*
G01X644410Y1389602D02*
X665570D01*
X666770Y1388402D01*
Y1377592D01*
X664570Y1375392D01*
Y1359432D01*
X663000Y1357862D01*
X656960D01*
X654770Y1355672D01*
Y1324422D01*
X655100Y1324092D01*
X670498D01*
G02X670786Y1323414I0J-400D01*
G03X669590Y1320778I2307J-2636D01*
G03X676596I3503J0D01*
G03X675400Y1323414I-3503J0D01*
G02X675688Y1324092I288J278D01*
G01X694844D01*
G02X695130Y1323413I-1J-400D01*
G03X693963Y1320803I2335J-2610D01*
G03X700969I3503J0D01*
G03X699802Y1323413I-3502J0D01*
G02X700088Y1324092I287J279D01*
G01X719244D01*
G02X719530Y1323413I-1J-400D01*
G03X718363Y1320803I2335J-2610D01*
G03X725369I3503J0D01*
G03X724202Y1323413I-3502J0D01*
G02X724488Y1324092I287J279D01*
G01X734746D01*
X735418Y1323420D01*
G02X735560Y1323361I0J-200D01*
G01X736425Y1322496D01*
G02X736484Y1322354I-141J-142D01*
G01Y1315262D01*
X647760D01*
X642060Y1320962D01*
Y1387252D01*
X644410Y1389602D01*
G37*
G36*
G01X648065Y1578088D02*
G03I-574J0D01*
G37*
G36*
G01X640265Y1578182D02*
G03I-574J0D01*
G37*
G36*
G01X636005D02*
G03I-574J0D01*
G37*
G36*
G01X648065Y1590094D02*
G03I-574J0D01*
G37*
G36*
G01X640265D02*
G03I-574J0D01*
G37*
G36*
G01X636005D02*
G03I-574J0D01*
G37*
G36*
G01X645565Y1614292D02*
G03I-574J0D01*
G37*
G36*
G01Y1602380D02*
G03I-574J0D01*
G37*
G36*
G01X633505D02*
G03I-574J0D01*
G37*
G36*
G01Y1614292D02*
G03I-574J0D01*
G37*
G36*
G01X641305D02*
G03I-574J0D01*
G37*
G36*
G01Y1602380D02*
G03I-574J0D01*
G37*
G36*
G01X662953Y212702D02*
X665970D01*
X667730Y210942D01*
Y200172D01*
X668560Y199342D01*
Y195002D01*
X667660Y194102D01*
X661230D01*
X658500Y196832D01*
Y211302D01*
X659900Y212702D01*
X662167D01*
X662192Y212696D01*
G03X662560Y212650I369J1456D01*
G03X662928Y212696I-1J1502D01*
G01X662953Y212702D01*
G37*
G36*
G01X659320Y409662D02*
X663820D01*
X664120Y409362D01*
Y403462D01*
X663720Y403062D01*
X659620D01*
X659120Y403562D01*
Y409462D01*
X659320Y409662D01*
G37*
G36*
G01X657820Y401462D02*
X663220D01*
X663420Y401262D01*
Y398462D01*
X663220Y398262D01*
X657820D01*
X657620Y398462D01*
Y401262D01*
X657820Y401462D01*
G37*
G36*
G01X700566Y1332178D02*
X694346D01*
G03X693964Y1331778I20J-401D01*
G01Y1325576D01*
G03X693986Y1325447I402J2D01*
G01X693997Y1325415D01*
Y1325182D01*
X676770D01*
G02X676578Y1325439I0J200D01*
G03X676594Y1325552I-385J112D01*
G01Y1328233D01*
X676595Y1331752D01*
G03X676194Y1332154I-402J0D01*
G01X669993D01*
G03X669592Y1331752I0J-401D01*
G01Y1325552D01*
G03X669608Y1325439I401J-1D01*
G02X669416Y1325182I-192J-57D01*
G01X656820D01*
X656210Y1325792D01*
Y1354577D01*
X658405Y1356772D01*
X733850D01*
X735979Y1354643D01*
Y1325881D01*
X735280Y1325182D01*
X725335D01*
Y1325415D01*
X725346Y1325447D01*
G03X725368Y1325576I-380J131D01*
G01Y1331777D01*
G03X724966Y1332178I-401J0D01*
G01X718746D01*
G03X718364Y1331778I20J-401D01*
G01Y1325576D01*
G03X718386Y1325447I402J2D01*
G01X718397Y1325415D01*
Y1325182D01*
X700935D01*
Y1325415D01*
X700946Y1325447D01*
G03X700968Y1325576I-380J131D01*
G01Y1331777D01*
G03X700566Y1332178I-401J0D01*
G37*
G36*
G01X723001Y1391791D02*
X736476D01*
X737790Y1393105D01*
Y1417215D01*
X738520Y1417945D01*
X747470D01*
X751537D01*
X753080Y1416402D01*
Y1373172D01*
X755940Y1370312D01*
X764640D01*
X767330Y1367622D01*
Y1316912D01*
X765680Y1315262D01*
X734570D01*
Y1322982D01*
X734990Y1323402D01*
X736510D01*
X737670Y1324562D01*
Y1355392D01*
X735288Y1357774D01*
X660508D01*
X660311Y1357971D01*
Y1385191D01*
X659020Y1386482D01*
Y1389054D01*
X660311Y1390345D01*
X661090Y1391124D01*
X661889Y1391923D01*
X668916D01*
X670217Y1393224D01*
Y1400530D01*
X670681Y1400994D01*
X677094D01*
X677236Y1400935D01*
X677418Y1400753D01*
G02X677460Y1400692I-141J-142D01*
G01Y1392189D01*
X677858Y1391791D01*
X691774D01*
X694673D01*
X695706D01*
X696630Y1392715D01*
Y1401185D01*
X695200Y1402615D01*
Y1412285D01*
X697880Y1414965D01*
X699960D01*
X700580Y1414345D01*
Y1413375D01*
X699912Y1412707D01*
X699380Y1412175D01*
Y1392639D01*
X699912Y1392107D01*
X700230Y1391788D01*
X701240D01*
X705853D01*
X707480Y1393415D01*
Y1400315D01*
X708157Y1400992D01*
X715088D01*
X715640Y1400440D01*
Y1392795D01*
X716644Y1391791D01*
X723001D01*
G37*
G36*
G01X652325Y1578182D02*
G03I-574J0D01*
G37*
G36*
G01X660125D02*
G03I-574J0D01*
G37*
G36*
G01X652325Y1590094D02*
G03I-574J0D01*
G37*
G36*
G01X660125D02*
G03I-574J0D01*
G37*
G36*
G01X657625Y1602380D02*
G03I-574J0D01*
G37*
G36*
G01Y1614292D02*
G03I-574J0D01*
G37*
G36*
G01X653365Y1602286D02*
G03I-574J0D01*
G37*
G36*
G01Y1614292D02*
G03I-574J0D01*
G37*
G36*
G01X668700Y213702D02*
X675550D01*
X676520Y212732D01*
Y198292D01*
X674020Y195792D01*
X671430D01*
X670640Y196582D01*
Y199452D01*
X668732Y201360D01*
Y211357D01*
X668700Y211388D01*
Y213702D01*
G37*
G36*
G01X675895Y409662D02*
X680395D01*
X680695Y409362D01*
Y403462D01*
X680295Y403062D01*
X676195D01*
X675695Y403562D01*
Y409462D01*
X675895Y409662D01*
G37*
G36*
G01X674395Y401462D02*
X679795D01*
X679995Y401262D01*
Y398462D01*
X679795Y398262D01*
X674395D01*
X674195Y398462D01*
Y401262D01*
X674395Y401462D01*
G37*
G36*
G01X665620Y409562D02*
X671720D01*
X672120Y409162D01*
Y398462D01*
X671920Y398262D01*
X665520D01*
X665320Y398462D01*
Y409262D01*
X665620Y409562D01*
G37*
G36*
G01X672164Y742835D02*
G03I-557J0D01*
G37*
G36*
G01X689350Y1435332D02*
X723947D01*
X736600Y1422685D01*
Y1393585D01*
X735817Y1392802D01*
X716853D01*
X716706Y1392949D01*
Y1400870D01*
X720483Y1404647D01*
G03X720542Y1404789I-141J142D01*
G01Y1413227D01*
G03X720483Y1413369I-200J0D01*
G01X717940Y1415912D01*
G03X717798Y1415971I-142J-141D01*
G01X710653D01*
G03X704587I-3033J-6310D01*
G01X697196D01*
G03X697054Y1415912I0J-200D01*
G01X694031Y1412889D01*
G03X693972Y1412747I141J-142D01*
G01Y1400618D01*
G03X694031Y1400476I200J0D01*
G01X695480Y1399027D01*
Y1393865D01*
X694417Y1392802D01*
X679243D01*
X678410Y1393635D01*
Y1401685D01*
X681816Y1405091D01*
G03X681875Y1405233I-141J142D01*
G01Y1413810D01*
X689041Y1420976D01*
G03X689100Y1421118I-141J142D01*
G01Y1435082D01*
X689350Y1435332D01*
G37*
G36*
G01X677383Y1411137D02*
X676900Y1410654D01*
X675734D01*
X674711Y1411677D01*
X665704D01*
X665051Y1412330D01*
Y1414660D01*
X665350Y1414959D01*
X668105D01*
X676837D01*
X677812Y1413984D01*
Y1411566D01*
X677383Y1411137D01*
G37*
G36*
G01X681810Y1422388D02*
X667830D01*
X667136Y1423082D01*
Y1435328D01*
Y1435694D01*
X668030Y1436588D01*
X682390D01*
X682980Y1435998D01*
Y1423558D01*
X681810Y1422388D01*
G37*
G36*
G01X665425Y1602380D02*
G03I-574J0D01*
G37*
G36*
G01Y1614292D02*
G03I-574J0D01*
G37*
G36*
G01X693150Y110362D02*
X706610D01*
Y102382D01*
G03X706978Y101494I1255J0D01*
G01X708160Y100311D01*
Y98980D01*
X707222Y98041D01*
G03X706854Y97153I887J-888D01*
G01Y87369D01*
G02X706230Y87037I-400J0D01*
G03X705390Y87294I-840J-1244D01*
G03X704044Y86459I0J-1502D01*
G02X703541Y86263I-359J177D01*
G03X703000Y86364I-541J-1401D01*
G03X701510Y85051I0J-1502D01*
G03X701426Y84825I1130J-549D01*
G02X700977Y84533I-387J103D01*
G03X700741Y84552I-238J-1483D01*
G03Y81548I0J-1502D01*
G03X700933Y81560I2J1502D01*
G02X701384Y81164I51J-397D01*
G01Y79297D01*
G03X701752Y78409I1255J0D01*
G01X702014Y78146D01*
Y77896D01*
X702250D01*
Y76544D01*
X700925D01*
G03X700242Y76342I0J-1256D01*
G03X699269Y75722I259J-1480D01*
G01X694970D01*
X692050Y78642D01*
Y109262D01*
X693150Y110362D01*
G37*
G36*
G01X680220Y93762D02*
Y101682D01*
X684500Y105962D01*
X688020D01*
X688700Y105282D01*
Y89762D01*
X688450Y89512D01*
X685850D01*
X685410Y89952D01*
Y92162D01*
X684710Y92862D01*
X681120D01*
X680220Y93762D01*
G37*
G36*
G01X696117Y409662D02*
X700320D01*
X700620Y409362D01*
Y403462D01*
X700220Y403062D01*
X696120D01*
X695620Y403562D01*
Y409111D01*
X695910Y409401D01*
G03X696117Y409662I-1030J1030D01*
G37*
G36*
G01X694320Y401462D02*
X699720D01*
X699920Y401262D01*
Y398462D01*
X699720Y398262D01*
X694320D01*
X694120Y398462D01*
Y401262D01*
X694320Y401462D01*
G37*
G36*
G01X682195Y409562D02*
X688206D01*
Y408212D01*
X688201Y408189D01*
G03X688178Y407986I867J-201D01*
G01Y406932D01*
X688305D01*
X688361Y406822D01*
G03X688414Y406726I1300J655D01*
G01Y404866D01*
X688178D01*
Y403812D01*
G03X688600Y403055I890J0D01*
G01X688695Y402997D01*
Y402507D01*
X689480Y401722D01*
X691370D01*
X691960Y401132D01*
Y398992D01*
X691230Y398262D01*
X682095D01*
X681895Y398462D01*
Y409262D01*
X682195Y409562D01*
G37*
G36*
G01X712676Y456642D02*
X712730D01*
X713638Y455734D01*
Y455733D01*
X714321Y455051D01*
X714580Y454792D01*
X714800Y454572D01*
Y453706D01*
G03Y451612I774J-1047D01*
G01Y450557D01*
G03Y448463I774J-1047D01*
G01Y444257D01*
G03Y442163I774J-1047D01*
G01Y441108D01*
G03Y439014I774J-1047D01*
G01Y438142D01*
X714580Y437922D01*
X714321Y437663D01*
X713638Y436981D01*
Y436980D01*
X712910Y436252D01*
X712536D01*
X711635Y437154D01*
X711426D01*
Y437307D01*
X711195Y437664D01*
X710503D01*
X710272Y437307D01*
Y437154D01*
X710095D01*
X709475Y436534D01*
X709075D01*
X708455Y437154D01*
X708276D01*
Y437307D01*
X708045Y437664D01*
X707353D01*
X707122Y437307D01*
Y437154D01*
X706885D01*
X706150Y436418D01*
X705415Y437154D01*
X705128D01*
Y437307D01*
X704896Y437664D01*
X704204D01*
X703974Y437307D01*
Y437154D01*
X701978D01*
Y437307D01*
X701746Y437664D01*
X701054D01*
X700824Y437307D01*
Y437154D01*
X700525D01*
X699765Y436393D01*
X699025Y437134D01*
X698828D01*
Y437307D01*
X698597Y437664D01*
X697905D01*
X697674Y437307D01*
Y437134D01*
X697445D01*
X696825Y436514D01*
X696515D01*
X695895Y437134D01*
X695678D01*
Y437307D01*
X695447Y437664D01*
X694755D01*
X694524Y437307D01*
Y437134D01*
X694265D01*
X693384Y436252D01*
X693000D01*
X691140Y438112D01*
Y439007D01*
G03Y441115I-763J1054D01*
G01Y442156D01*
G03Y444264I-763J1054D01*
G01Y448456D01*
G03Y450564I-763J1054D01*
G01Y451605D01*
G03Y453713I-763J1054D01*
G01Y454682D01*
X693100Y456642D01*
X693244D01*
X694325Y455560D01*
X694524D01*
Y455413D01*
X694755Y455056D01*
X695447D01*
X695678Y455413D01*
Y455560D01*
X695875D01*
X696515Y456200D01*
X696805D01*
X697445Y455560D01*
X697674D01*
Y455413D01*
X697905Y455056D01*
X698597D01*
X698828Y455413D01*
Y455560D01*
X699025D01*
X699665Y456200D01*
X699955D01*
X700595Y455560D01*
X700822D01*
Y455413D01*
X701054Y455056D01*
X701746D01*
X701976Y455413D01*
Y455560D01*
X703972D01*
Y455413D01*
X704204Y455056D01*
X704896D01*
X705126Y455413D01*
Y455560D01*
X705345D01*
X705995Y456210D01*
X706245D01*
X706895Y455560D01*
X707122D01*
Y455413D01*
X707353Y455056D01*
X708045D01*
X708276Y455413D01*
Y455560D01*
X708465D01*
X709105Y456200D01*
X709445D01*
X710085Y455560D01*
X710272D01*
Y455413D01*
X710503Y455056D01*
X711195D01*
X711426Y455413D01*
Y455560D01*
X711595D01*
X712676Y456642D01*
G37*
G36*
G01X686699Y446922D02*
X688257Y448480D01*
G03X688531Y448860I-1028J1030D01*
G02X689238Y448877I358J-178D01*
G03X689610Y448457I1138J633D01*
G01Y447578D01*
X689850Y447338D01*
X690138D01*
Y445368D01*
X689840D01*
X689610Y445138D01*
Y444263D01*
G03X689074Y443210I766J-1053D01*
G03X689600Y442165I1301J0D01*
G01Y441282D01*
X688990Y440672D01*
Y439408D01*
X689590Y438808D01*
Y438168D01*
X689860Y437898D01*
X690138D01*
Y437697D01*
X691310Y436526D01*
Y435838D01*
X691080Y435608D01*
X690400D01*
X686320Y439688D01*
Y441585D01*
G02X686839Y441967I400J0D01*
G03X687226Y441908I388J1243D01*
G01X687227D01*
G03Y444512I0J1302D01*
G01X687226D01*
G03X686839Y444453I1J-1302D01*
G02X686320Y444835I-119J382D01*
G01Y446649D01*
G03X686699Y446922I-651J1303D01*
G37*
G36*
G01X692620Y433342D02*
Y434072D01*
X694680Y436132D01*
X695480D01*
X696100Y435512D01*
X697240D01*
X697860Y436132D01*
X698610D01*
X699110Y435632D01*
Y435262D01*
X696700Y432852D01*
X693110D01*
X692620Y433342D01*
G37*
G36*
G01X690280Y456998D02*
X690970D01*
X691310Y456658D01*
Y456268D01*
X690138Y455097D01*
Y454818D01*
X689830D01*
X689610Y454598D01*
Y453892D01*
X688970Y453252D01*
Y452078D01*
X689610Y451438D01*
Y450563D01*
G03X689238Y450143I766J-1053D01*
G02X688531Y450160I-349J195D01*
G03X687417Y450954I-1303J-650D01*
G01X687349Y450963D01*
X686390Y451922D01*
Y453108D01*
X690280Y456998D01*
G37*
G36*
G01X693080Y460312D02*
X712970D01*
X713540Y459742D01*
Y458922D01*
X711180Y456562D01*
X710500D01*
X709860Y457202D01*
X708690D01*
X708050Y456562D01*
X707310D01*
X706660Y457212D01*
X705580D01*
X704930Y456562D01*
X701010D01*
X700370Y457202D01*
X699250D01*
X698610Y456562D01*
X697860D01*
X697220Y457202D01*
X696100D01*
X695460Y456562D01*
X694740D01*
X692610Y458692D01*
Y459842D01*
X693080Y460312D01*
G37*
G36*
G01X696120Y488662D02*
X689520D01*
X689420Y488762D01*
Y493162D01*
X689620Y493362D01*
X696120D01*
X696320Y493162D01*
Y488862D01*
X696120Y488662D01*
G37*
G36*
G01X682420Y492462D02*
X687620D01*
X687820Y492262D01*
Y489262D01*
X687620Y489062D01*
X682420D01*
X682220Y489262D01*
Y492262D01*
X682420Y492462D01*
G37*
G36*
G01X699334Y480542D02*
X698484Y479692D01*
X690610D01*
X689540Y480762D01*
X684320D01*
X684020Y481062D01*
Y487062D01*
X684320Y487362D01*
X696120D01*
X696520Y486962D01*
Y485327D01*
X699334Y482513D01*
Y480542D01*
G37*
G36*
G01X727973Y134762D02*
X752199D01*
X756192Y130769D01*
Y99048D01*
G02X755611Y98691I-400J0D01*
G03X754800Y98884I-811J-1609D01*
G03Y95280I0J-1802D01*
G03X755893Y95650I-1J1802D01*
G02X756463Y95561I242J-318D01*
G03X757693Y94922I1229J862D01*
G01X759126D01*
Y94273D01*
G02X758474Y93963I-400J1D01*
G03X757340Y94364I-1133J-1401D01*
G03Y90760I0J-1802D01*
G03X758767Y91462I0J1801D01*
G01X758827Y91540D01*
X759126D01*
Y90935D01*
X758548Y90358D01*
G03X758108Y89296I1062J-1062D01*
G01Y83001D01*
G03X758548Y81939I1502J0D01*
G01X760443Y80045D01*
G02X760160Y79362I-283J-283D01*
G01X759710D01*
G03X759362Y79578I-830J-949D01*
G01X755272Y81273D01*
X754983Y81562D01*
Y84962D01*
X751064Y88881D01*
X751182Y89021D01*
G03X751535Y89988I-1148J967D01*
G03X751005Y91133I-1502J0D01*
G02Y91743I259J305D01*
G03X751535Y92888I-972J1145D01*
G03X748531I-1502J0D01*
G03X749061Y91743I1502J0D01*
G02Y91133I-259J-305D01*
G03X748811Y90862I971J-1146D01*
G01X741626D01*
X741625Y91061D01*
G03X738021I-1802J-9D01*
G01X738020Y90862D01*
X729027D01*
X729018Y91053D01*
G03X727518Y92486I-1500J-69D01*
G03X726054Y91320I0J-1502D01*
G02X725844Y91165I-195J44D01*
G03X725750Y91168I-87J-1253D01*
G01X719570D01*
X718446Y92292D01*
Y106354D01*
G03X718078Y107242I-1255J0D01*
G01X712871Y112450D01*
G02X713065Y113123I283J283D01*
G03X713997Y113776I-332J1465D01*
G02X714669I336J-216D01*
G03X715933Y113086I1264J813D01*
G03X717435Y114588I0J1502D01*
G03X716905Y115733I-1502J0D01*
G02Y116343I259J305D01*
G03X717435Y117488I-972J1145D01*
G03X715933Y118990I-1502J0D01*
G03X714669Y118300I0J-1503D01*
G02X713997I-336J216D01*
G03X712733Y118990I-1264J-813D01*
G03X711600Y118474I0J-1502D01*
G02X710898Y118737I-302J263D01*
G01Y119125D01*
X721945Y130172D01*
X722862D01*
G03X723750Y130540I0J1255D01*
G01X727973Y134762D01*
G37*
G36*
G01X702120Y409562D02*
X708220D01*
X708620Y409162D01*
Y398462D01*
X708420Y398262D01*
X702020D01*
X701820Y398462D01*
Y409262D01*
X702120Y409562D01*
G37*
G36*
G01X706820Y435672D02*
X707300Y436152D01*
X708040D01*
X708660Y435532D01*
X709890D01*
X710510Y436152D01*
X711220D01*
X713340Y434032D01*
Y433262D01*
X713000Y432922D01*
X708830D01*
X706820Y434932D01*
Y435672D01*
G37*
G36*
G01X700940Y436152D02*
X705000D01*
X705580Y435572D01*
Y435092D01*
X705818Y434854D01*
Y434517D01*
X707040Y433296D01*
Y433292D01*
X706560Y432812D01*
X699450D01*
X698980Y433282D01*
Y433716D01*
X700112Y434847D01*
Y435324D01*
X700940Y436152D01*
G37*
G36*
G01X710545Y483562D02*
X710345Y483762D01*
Y489662D01*
X710845Y490162D01*
X714945D01*
X715345Y489762D01*
Y483862D01*
X715045Y483562D01*
X710545D01*
G37*
G36*
G01X708645Y491862D02*
X708445Y492062D01*
Y496487D01*
X708820Y496862D01*
X714660D01*
X715380Y496142D01*
Y492361D01*
X714881Y491862D01*
X708645D01*
G37*
G36*
G01X701600Y490847D02*
X702245Y491492D01*
Y494762D01*
X702445Y494962D01*
X706120D01*
X706520Y494562D01*
Y491162D01*
X707420Y490262D01*
X708820D01*
X709045Y490037D01*
Y484062D01*
X708645Y483662D01*
X702545D01*
X701600Y484607D01*
Y490847D01*
G37*
G36*
G01X715526Y1411112D02*
X715043Y1410629D01*
X713877D01*
X712854Y1411652D01*
X703847D01*
X703194Y1412305D01*
Y1414635D01*
X703493Y1414934D01*
X706248D01*
X714980D01*
X715955Y1413959D01*
Y1411541D01*
X715526Y1411112D01*
G37*
G36*
G01X707200Y1593220D02*
X719560D01*
X720227Y1592553D01*
Y1592186D01*
X720226Y1592185D01*
Y1586301D01*
X720227D01*
Y1586118D01*
X721152Y1585193D01*
X721335D01*
Y1585192D01*
X726602D01*
X727502Y1584293D01*
Y1578943D01*
X727052Y1578493D01*
X714782D01*
G02X714413Y1579048I0J400D01*
G03X714554Y1579683I-1361J635D01*
G03X713052Y1581185I-1502J0D01*
G03X712302Y1580984I1J-1502D01*
G01X708561D01*
X706552Y1582993D01*
Y1586434D01*
X707146D01*
Y1586198D01*
X708199D01*
G03X708794Y1586426I0J890D01*
G01X712103D01*
G03X712991Y1586795I-1J1256D01*
G01X714685Y1588488D01*
X714739Y1588502D01*
G03X715882Y1589960I-358J1458D01*
G03X714380Y1591462I-1502J0D01*
G03X713392Y1591091I0J-1501D01*
G02X712755Y1591251I-263J302D01*
G03X711350Y1592222I-1405J-531D01*
G03X709848Y1590720I0J-1502D01*
G03X710317Y1589630I1501J0D01*
G02X710042Y1588940I-275J-290D01*
G01X708794D01*
G03X708199Y1589168I-595J-662D01*
G01X707146D01*
Y1588932D01*
X706540D01*
Y1592560D01*
X707200Y1593220D01*
G37*
G36*
G01X713820Y409662D02*
X718320D01*
X718620Y409362D01*
Y403462D01*
X718220Y403062D01*
X714120D01*
X713620Y403562D01*
Y405584D01*
G03Y408060I-849J1238D01*
G01Y409462D01*
X713820Y409662D01*
G37*
G36*
G01X712320Y401462D02*
X717720D01*
X717920Y401262D01*
Y398462D01*
X717720Y398262D01*
X712320D01*
X712120Y398462D01*
Y401262D01*
X712320Y401462D01*
G37*
G36*
G01X720120Y409562D02*
X726220D01*
X726620Y409162D01*
Y398462D01*
X726420Y398262D01*
X720020D01*
X719820Y398462D01*
Y409262D01*
X720120Y409562D01*
G37*
G36*
G01X757844Y495248D02*
X766934D01*
X767900Y494281D01*
Y492359D01*
X767570Y492028D01*
X759453D01*
G03X758565Y491660I0J-1255D01*
G01X758166Y491262D01*
X748637D01*
X739200Y481825D01*
G02X738620Y481841I-282J283D01*
G03X737621Y482308I-999J-835D01*
G03X736319Y481006I0J-1302D01*
G03X736786Y480007I1302J0D01*
G02X736802Y479427I-267J-298D01*
G01X732901Y475526D01*
G02X732320Y475542I-283J283D01*
G03X731321Y476009I-999J-835D01*
G03X730019Y474707I0J-1302D01*
G03X730486Y473708I1302J0D01*
G02X730502Y473127I-267J-298D01*
G01X730010Y472635D01*
Y465892D01*
X729993Y465853D01*
G03X729869Y465359I1329J-596D01*
G02X729470Y465358I-200J14D01*
G03X728172Y466560I-1298J-100D01*
G03Y463956I0J-1302D01*
G03X728571Y464019I-1J1302D01*
G01X728774Y463687D01*
X728467Y463380D01*
X728367Y463395D01*
G03X728172Y463410I-197J-1287D01*
G03X726870Y462108I0J-1302D01*
G03X726885Y461913I1302J2D01*
G01X726900Y461813D01*
X726593Y461506D01*
X726261Y461709D01*
G03X726324Y462108I-1239J400D01*
G03X723720I-1302J0D01*
G03X723735Y461908I1302J-3D01*
G03X724379Y460975I1287J200D01*
G02X724373Y460263I-185J-354D01*
G03X723718Y459608I649J-1304D01*
G02X723011Y459592I-358J179D01*
G03X721873Y460261I-1138J-633D01*
G03X720571Y458959I0J-1302D01*
G03X721257Y457812I1302J0D01*
G02X721224Y457113I-210J-340D01*
G03X720569Y456458I649J-1304D01*
G02X719867Y456430I-359J177D01*
G03X718723Y457111I-1144J-620D01*
G03Y454507I0J-1302D01*
G03X719867Y455188I0J1301D01*
G02X720569Y455160I343J-205D01*
G03X720669Y454989I1304J648D01*
G01Y453156D01*
X720656Y453122D01*
G03X720571Y452676I1217J-463D01*
G01Y452664D01*
Y452659D01*
G03X720656Y452196I1302J0D01*
G01X720669Y452162D01*
Y450007D01*
X720656Y449973D01*
G03X720571Y449527I1217J-463D01*
G01Y449515D01*
Y449510D01*
G03X720656Y449047I1302J0D01*
G01X720669Y449013D01*
Y443961D01*
X720482Y443774D01*
G02X719858Y443847I-283J283D01*
G03X718723Y444512I-1135J-636D01*
G03X717421Y443210I0J-1302D01*
G03X718086Y442075I1301J0D01*
G02X718159Y441451I-210J-341D01*
G01X717580Y440872D01*
Y440686D01*
X717559Y440644D01*
G03X717421Y440061I1164J-583D01*
G03X717559Y439478I1302J0D01*
G01X717580Y439436D01*
Y439352D01*
X718170Y438762D01*
Y438222D01*
X715670Y435722D01*
X714980D01*
X714640Y436062D01*
Y436566D01*
X715029Y436955D01*
X715802Y437727D01*
Y437902D01*
X716120D01*
X716340Y438122D01*
Y439008D01*
G03Y441114I-766J1053D01*
G01Y442157D01*
G03X716876Y443210I-766J1053D01*
G03X716861Y443410I-1302J3D01*
G03X716340Y444263I-1287J-200D01*
G01Y445142D01*
X716100Y445382D01*
X715802D01*
Y447352D01*
X716110D01*
X716340Y447582D01*
Y448457D01*
G03X716876Y449510I-766J1053D01*
G03X716350Y450556I-1303J0D01*
G01Y451614D01*
G03X716876Y452659I-775J1045D01*
G03X716360Y453697I-1302J0D01*
G01Y454552D01*
X716090Y454822D01*
X715802D01*
Y454987D01*
X715029Y455759D01*
X714640Y456148D01*
Y457343D01*
G02X715156Y457726I400J0D01*
G03X715574Y457657I418J1232D01*
G03X716876Y458959I0J1302D01*
G03X716861Y459159I-1302J3D01*
G03X715821Y460238I-1287J-200D01*
G01X715639Y460421D01*
X715898Y460680D01*
X717140D01*
X717648Y461188D01*
X717789Y461062D01*
G03X717831Y461026I933J1046D01*
G03X718722Y460706I891J1081D01*
G01X718723D01*
G03X720125Y462108I0J1402D01*
G03X719769Y463042I-1403J0D01*
G01X719643Y463183D01*
X720817Y464357D01*
X721008Y464284D01*
X721034Y464262D01*
G03X721873Y463956I839J997D01*
G03Y466560I0J1302D01*
G03X721790Y466557I5J-1302D01*
G01X721770D01*
G02X721576Y466803I1J200D01*
G01X721586Y466846D01*
X721596Y466866D01*
G03X721626Y466932I-1311J636D01*
G03X721692Y467118I-1336J579D01*
G03X721873Y467105I184J1289D01*
G03X723175Y468407I0J1302D01*
G03X721937Y469707I-1302J0D01*
G02X721746Y469907I9J200D01*
G01Y470057D01*
G02X721937Y470257I200J0D01*
G03X723175Y471557I-64J1300D01*
G03X722001Y472853I-1302J0D01*
G01X721811Y473043D01*
X722219Y473451D01*
X722265Y473466D01*
G03X723114Y474315I-392J1241D01*
G01X723129Y474361D01*
X723434Y474666D01*
X723617Y474484D01*
X723777Y474324D01*
X723792Y474280D01*
G03X725022Y473405I1230J427D01*
G03X726324Y474707I0J1302D01*
G03X725450Y475937I-1303J0D01*
G01X725406Y475952D01*
X725245Y476112D01*
X725063Y476295D01*
X725368Y476600D01*
X725414Y476615D01*
G03X726263Y477464I-392J1241D01*
G01X726278Y477510D01*
X726686Y477918D01*
X726874Y477730D01*
X726884Y477664D01*
G03X728172Y476554I1288J192D01*
G03X729474Y477856I0J1302D01*
G03X728300Y479152I-1302J0D01*
G01X728110Y479342D01*
X728489Y479721D01*
X728546Y479733D01*
G03X729545Y480732I-274J1273D01*
G01X729557Y480789D01*
X741146Y492378D01*
X741241Y492369D01*
G03X741420Y492360I180J1793D01*
G03X743222Y494162I0J1802D01*
G03X743212Y494352I-1802J0D01*
G01X743204Y494436D01*
X744016Y495248D01*
X750767D01*
X750816Y495119D01*
G03X754184I1684J644D01*
G01X754233Y495248D01*
X755440D01*
G03X756642Y494770I1203J1274D01*
G03X757844Y495248I-1J1752D01*
G37*
G36*
G01X721752Y1592293D02*
X726852D01*
X727552Y1591593D01*
Y1586893D01*
X726854Y1586194D01*
X721750D01*
X721228Y1586716D01*
Y1591770D01*
X721752Y1592293D01*
G37*
G36*
G01X740620Y409662D02*
X744535D01*
X745320Y408877D01*
Y403562D01*
X744820Y403062D01*
X740720D01*
X740320Y403462D01*
Y409362D01*
X740620Y409662D01*
G37*
G36*
G01X741220Y401462D02*
X746620D01*
X746722Y401360D01*
Y400004D01*
G03X746808Y399509I1456J-2D01*
G01X746820Y399476D01*
Y398462D01*
X746620Y398262D01*
X741220D01*
X741020Y398462D01*
Y401262D01*
X741220Y401462D01*
G37*
G36*
G01X735793Y409562D02*
X738820D01*
X739120Y409262D01*
Y398462D01*
X738920Y398262D01*
X732520D01*
X732320Y398462D01*
Y409162D01*
X732720Y409562D01*
X734647D01*
X734683Y409547D01*
G03X735757I537J1294D01*
G01X735793Y409562D01*
G37*
G36*
G01X821220Y1575770D02*
X841290D01*
X846710Y1570350D01*
X858090D01*
X863110Y1575370D01*
X883920D01*
X888260Y1571030D01*
X900640D01*
X905340Y1575730D01*
X939930D01*
X941040Y1574620D01*
Y1566550D01*
X943220Y1564370D01*
X957790D01*
X958110Y1564050D01*
Y1560536D01*
X958088Y1560515D01*
Y1557955D01*
X958110Y1557934D01*
Y1549490D01*
X958840Y1548760D01*
X967390D01*
X968150Y1549520D01*
Y1553434D01*
X968182Y1553465D01*
Y1558992D01*
X969110Y1559920D01*
X980889D01*
X981400Y1559409D01*
Y1549410D01*
X982020Y1548790D01*
X990990D01*
X991530Y1549330D01*
Y1560240D01*
X991800Y1560510D01*
X1004630D01*
X1004850Y1560290D01*
Y1549210D01*
X1005320Y1548740D01*
X1014310D01*
X1015070Y1549500D01*
Y1560230D01*
X1015350Y1560510D01*
X1027970D01*
X1028240Y1560240D01*
Y1549450D01*
X1029200Y1548490D01*
X1037130D01*
X1038280Y1549640D01*
Y1560010D01*
X1038780Y1560510D01*
X1051340D01*
X1051590Y1560260D01*
Y1549180D01*
X1052530Y1548240D01*
X1060360D01*
X1061580Y1549460D01*
Y1560240D01*
X1061850Y1560510D01*
X1074600D01*
X1074810Y1560300D01*
Y1549360D01*
X1075950Y1548220D01*
X1083850D01*
X1084840Y1549210D01*
Y1560050D01*
X1085300Y1560510D01*
X1097330D01*
X1098190Y1559650D01*
Y1541150D01*
X1092210Y1535170D01*
X1059650D01*
X1024070Y1499590D01*
X748030D01*
X728920Y1518700D01*
Y1565820D01*
X731590Y1568490D01*
Y1574250D01*
X732810Y1575470D01*
X758220D01*
X765150Y1568540D01*
X774310D01*
X781000Y1575230D01*
X799850D01*
X804370Y1570710D01*
X816160D01*
X821220Y1575770D01*
G37*
G36*
G01X747949Y1595379D02*
X745522Y1592951D01*
Y1591251D01*
X745422Y1591151D01*
X744022D01*
X742590Y1589719D01*
Y1579472D01*
X731504D01*
X729738D01*
X729122Y1580088D01*
Y1595682D01*
Y1599994D01*
G03X731577Y1602518I-70J2524D01*
G03X730422Y1604639I-2525J0D01*
G01Y1607951D01*
X729622Y1608751D01*
Y1626162D01*
X759355Y1655895D01*
X777695D01*
X812960Y1691160D01*
Y1714140D01*
X817460Y1718640D01*
X900700D01*
X907010Y1712330D01*
X907140Y1712200D01*
Y1685420D01*
Y1666600D01*
Y1664042D01*
Y1663772D01*
X914822Y1656090D01*
X915558Y1655354D01*
X922265D01*
X923001Y1656090D01*
X926800D01*
X973550D01*
X974830Y1654810D01*
Y1641510D01*
X974838Y1641502D01*
Y1637493D01*
X977708Y1634624D01*
X996558D01*
X1003053Y1628128D01*
X1045717D01*
X1049842Y1632253D01*
Y1633782D01*
X1050550Y1634490D01*
X1050754D01*
X1050755Y1634488D01*
X1102212D01*
X1103140Y1633560D01*
Y1607480D01*
X1102240Y1606580D01*
X943180D01*
X935490Y1598890D01*
X926730D01*
X920790Y1592950D01*
Y1579732D01*
X907330D01*
Y1592932D01*
X906522Y1593740D01*
Y1604418D01*
X897900Y1613040D01*
X888092D01*
X879522Y1604470D01*
Y1593670D01*
X878810Y1592958D01*
Y1579372D01*
X865340D01*
Y1593002D01*
X864622Y1593720D01*
Y1603900D01*
X855922Y1612600D01*
X845130D01*
X837480Y1604950D01*
Y1593680D01*
X836780Y1592980D01*
Y1579772D01*
X823370D01*
Y1592852D01*
X822622Y1593600D01*
Y1604078D01*
X813690Y1613010D01*
X803262D01*
X795522Y1605270D01*
Y1593622D01*
X794790Y1592890D01*
Y1579232D01*
X781370D01*
Y1592990D01*
X775990Y1598370D01*
X750940D01*
X748916Y1596346D01*
X748882Y1596330D01*
G03X747964Y1595413I729J-1648D01*
G01X747949Y1595379D01*
G37*
G36*
G01X757411Y134762D02*
X765099D01*
X771533Y128328D01*
Y100018D01*
X769660Y98146D01*
G03X769220Y97084I1062J-1062D01*
G01Y84666D01*
X766382Y81828D01*
X762907D01*
X761112Y83623D01*
Y88674D01*
X761689Y89251D01*
G03X762128Y90313I-1062J1061D01*
G01Y95923D01*
G03X761689Y96985I-1501J1D01*
G01X761189Y97485D01*
G03X760127Y97924I-1061J-1062D01*
G01X759194D01*
Y110082D01*
G02X759762Y110446I400J1D01*
G03X760390Y110308I629J1364D01*
G03Y113312I0J1502D01*
G03X759762Y113174I1J-1502D01*
G02X759194Y113538I-168J363D01*
G01Y131391D01*
G03X758755Y132453I-1501J1D01*
G01X757128Y134079D01*
G02X757411Y134762I283J283D01*
G37*
G36*
G01X760510Y450012D02*
X781240D01*
Y447003D01*
G02X780668Y446642I-400J0D01*
G03X780020Y446789I-648J-1355D01*
G03Y443785I0J-1502D01*
G03X780668Y443932I0J1502D01*
G02X781240Y443571I172J-361D01*
G01Y443153D01*
G02X780668Y442792I-400J0D01*
G03X780020Y442939I-648J-1355D01*
G03Y439935I0J-1502D01*
G03X780668Y440082I0J1502D01*
G02X781240Y439721I172J-361D01*
G01Y436702D01*
X761344D01*
G02X761032Y437353I0J400D01*
G03X761342Y438232I-1091J879D01*
G03X760614Y439461I-1401J0D01*
G01X760510Y439518D01*
Y441136D01*
X760682Y441160D01*
G03Y444134I-213J1487D01*
G01X760510Y444158D01*
Y450012D01*
G37*
G36*
G01X825375Y204724D02*
G02I-19685J0D01*
G37*
G36*
G01X793370Y589862D02*
G03I-650J0D01*
G37*
G36*
G01X790370Y581862D02*
G03I-650J0D01*
G37*
G36*
G01X783750Y593582D02*
G03I-650J0D01*
G37*
G36*
G01X829950Y451910D02*
X839960D01*
X840080Y451790D01*
G02X839764Y451109I-283J-282D01*
G03X839640Y451114I-122J-1497D01*
G03X838138Y449612I0J-1502D01*
G03X839632Y448110I1502J0D01*
G02X839981Y447519I-2J-400D01*
G03X839798Y446800I1319J-719D01*
G03X842802I1502J0D01*
G03X841308Y448302I-1502J0D01*
G02X840959Y448893I2J400D01*
G03X841142Y449612I-1319J719D01*
G03X841137Y449736I-1502J2D01*
G02X841818Y450052I399J33D01*
G01X846836Y445034D01*
X846710Y444893D01*
G03X846328Y443892I1121J-1001D01*
G03X847830Y442390I1502J0D01*
G03X848831Y442772I0J1503D01*
G01X848972Y442898D01*
X860520Y431350D01*
X860527Y431279D01*
G03X862137Y429669I1793J183D01*
G01X862208Y429662D01*
X873980Y417890D01*
Y385750D01*
X873600D01*
X871527Y383677D01*
X871397Y383745D01*
G03X870700Y383917I-698J-1330D01*
G03X869198Y382415I0J-1502D01*
G03X869370Y381718I1502J1D01*
G01X869438Y381588D01*
X863568Y375718D01*
X862581Y375306D01*
G02X862028Y375707I-154J369D01*
G03X862033Y375826I-1497J122D01*
G03X859029I-1502J0D01*
G03X859284Y374989I1501J0D01*
G02X859116Y374401I-332J-223D01*
G03X858356Y373631I617J-1369D01*
G01X858321Y373548D01*
X810670Y358060D01*
X806130D01*
X803700Y360490D01*
X803702Y360574D01*
Y360600D01*
G03X803634Y361047I-1503J0D01*
G01X803625Y361076D01*
Y377485D01*
X821250Y395110D01*
Y426236D01*
G02X821663Y426636I400J0D01*
G03X821720Y426635I60J1801D01*
G03Y430239I0J1802D01*
G03X821663Y430238I3J-1802D01*
G02X821250Y430638I-13J400D01*
G01Y443210D01*
X829950Y451910D01*
G37*
G36*
G01X799370Y585362D02*
G03I-650J0D01*
G37*
G36*
G01X798870Y597362D02*
G03I-650J0D01*
G37*
G36*
G01X809510Y603802D02*
G03I-650J0D01*
G37*
G36*
G01X798370Y617862D02*
G03I-650J0D01*
G37*
G36*
G01X820330Y140472D02*
X827270D01*
X827840Y139902D01*
Y133922D01*
X827530Y133612D01*
X820640D01*
X819910Y134342D01*
Y140052D01*
X820330Y140472D01*
G37*
G36*
G01X815690Y590772D02*
G03I-650J0D01*
G37*
G36*
G01X857040Y1420330D02*
G02I-15800J0D01*
G37*
G36*
G01X838720Y107862D02*
X839640Y108782D01*
X852950D01*
X855640Y106092D01*
Y99262D01*
X853300Y96922D01*
X839470D01*
X838720Y97672D01*
Y107862D01*
G37*
G36*
G01X832350Y596962D02*
G03I-650J0D01*
G37*
G36*
G01X844460Y221112D02*
X845030Y221682D01*
X849320D01*
X850600Y220402D01*
Y208392D01*
X850140Y207932D01*
X845780D01*
X844460Y209252D01*
Y221112D01*
G37*
G36*
G01X857348Y594011D02*
G03I-650J0D01*
G37*
G36*
G01X902089Y477386D02*
X915430D01*
X915895Y476921D01*
Y472644D01*
X915802Y472551D01*
X913794D01*
X913763Y472713D01*
G03X912288Y473932I-1475J-283D01*
G03X911297Y473559I0J-1503D01*
G02X910646Y473761I-264J301D01*
G03X909190Y474894I-1456J-369D01*
G03X907732Y473751I0J-1501D01*
G01X907718Y473697D01*
X906532Y472510D01*
G03X906164Y471622I887J-888D01*
G01Y471176D01*
X904983Y469995D01*
X901717D01*
X901465Y470247D01*
X901488Y470354D01*
G03X901522Y470672I-1468J318D01*
G03X901407Y471248I-1502J0D01*
G01X901392Y471285D01*
Y476689D01*
X902089Y477386D01*
G37*
G36*
G01X913560Y493141D02*
X918904D01*
X919324Y492721D01*
Y491311D01*
X919104Y491091D01*
X914654D01*
X909924Y486361D01*
Y480761D01*
X909664Y480501D01*
X898981D01*
X898420Y481062D01*
Y491182D01*
X898889Y491651D01*
X906164D01*
X907015Y490800D01*
X910993D01*
X912318Y492126D01*
X912671D01*
G03X913560Y493022I-1J890D01*
G01Y493141D01*
G37*
G36*
G01X948424Y321653D02*
G02I-19685J0D01*
G37*
G36*
G01X913545Y488262D02*
X914900D01*
X916456Y486706D01*
Y485046D01*
X917387Y484115D01*
X920800D01*
X921494Y483421D01*
Y474491D01*
X921034Y474031D01*
X917724D01*
X917314Y474441D01*
Y478501D01*
X915834Y479981D01*
X910974D01*
X910767Y480188D01*
X910926Y480346D01*
Y485642D01*
X913545Y488262D01*
G37*
G36*
G01X933639Y478741D02*
X934194Y478186D01*
Y471641D01*
X933384Y470831D01*
X928414D01*
X925984Y473261D01*
X923994D01*
X923084Y474171D01*
Y478151D01*
X923674Y478741D01*
X933639D01*
G37*
G36*
G01X931574Y487231D02*
X933817D01*
X934547Y486501D01*
X938800D01*
X941944Y483357D01*
Y476121D01*
X941494Y475671D01*
X935684D01*
X935304Y476051D01*
Y478630D01*
X934222Y479712D01*
X934084D01*
X934054Y479742D01*
X923366D01*
X922954Y480154D01*
Y483916D01*
X923390Y484352D01*
X927044D01*
X928155Y485463D01*
X930693D01*
X931208Y485978D01*
Y486865D01*
X931574Y487231D01*
G37*
G36*
G01X930008Y504811D02*
X930194D01*
X930894Y504111D01*
Y504045D01*
G03X930538Y502986I1395J-1058D01*
G03X930894Y501927I1751J-1D01*
G01Y499947D01*
X930877Y499908D01*
G03X930751Y499314I1341J-595D01*
G03X930877Y498720I1467J1D01*
G01X930894Y498681D01*
Y494521D01*
X929922Y493549D01*
X929825Y493560D01*
G03X929654Y493570I-171J-1457D01*
G03X928943Y493386I0J-1466D01*
G01X928898Y493361D01*
X928680D01*
X927989Y494052D01*
X925959D01*
X925308Y493401D01*
X925184Y493452D01*
G03X924623Y493564I-562J-1355D01*
G03X923878Y493361I0J-1467D01*
G01X921916D01*
X921873Y493384D01*
G03X921189Y493553I-684J-1298D01*
G03X920505Y493384I0J-1467D01*
G01X920462Y493361D01*
X920100D01*
X919504Y493957D01*
Y494832D01*
X919509Y494854D01*
G03Y495500I-1431J323D01*
G01X919504Y495522D01*
Y496981D01*
X919525Y497023D01*
G03Y498331I-1312J654D01*
G01X919504Y498373D01*
Y500081D01*
X919525Y500123D01*
G03Y501431I-1312J654D01*
G01X919504Y501473D01*
Y502812D01*
X919515Y502844D01*
G03X919598Y503330I-1384J486D01*
G03X919515Y503816I-1467J0D01*
G01X919504Y503848D01*
Y504221D01*
X920094Y504811D01*
X920333D01*
X920376Y504788D01*
G03X921060Y504619I684J1298D01*
G03X921744Y504788I0J1467D01*
G01X921787Y504811D01*
X923040D01*
G03X924526I743J1265D01*
G01X925882D01*
G03X927392I755J1259D01*
G01X928554D01*
X928597Y504788D01*
G03X929281Y504619I684J1298D01*
G03X929965Y504788I0J1467D01*
G01X930008Y504811D01*
G37*
G36*
G01X926374Y493051D02*
X927574D01*
X927904Y492721D01*
Y491231D01*
X930024Y489111D01*
Y486757D01*
X929780Y486513D01*
X927183D01*
X926291Y485621D01*
X918360D01*
X917834Y486147D01*
Y489691D01*
X918184Y490041D01*
X925354D01*
X925934Y490621D01*
Y491437D01*
X925953Y491477D01*
G03X926090Y492097I-1330J619D01*
G03X926020Y492544I-1467J-1D01*
G01X925983Y492660D01*
X926374Y493051D01*
G37*
G36*
G01X923270Y998852D02*
X934800D01*
X941270Y992382D01*
Y989652D01*
G02X940665Y989309I-400J0D01*
G03X939740Y989564I-924J-1547D01*
G03Y985960I0J-1802D01*
G03X940665Y986215I1J1802D01*
G02X941270Y985872I205J-343D01*
G01Y984252D01*
X936250Y979232D01*
Y965222D01*
X935910Y964882D01*
X919400D01*
X916500Y967782D01*
Y978592D01*
X918290Y980382D01*
X927310D01*
X927690Y980002D01*
Y978252D01*
X927900Y978042D01*
X932460D01*
X933270Y978852D01*
Y986892D01*
X934340Y987962D01*
X935870D01*
Y989656D01*
X936062Y989847D01*
Y991867D01*
X935870Y992058D01*
Y992632D01*
X934840Y993662D01*
X923480D01*
X922930Y994212D01*
Y998512D01*
X923270Y998852D01*
G37*
G36*
G01X921690Y992602D02*
X931860D01*
X932590Y991872D01*
X934640D01*
X935060Y991452D01*
Y990262D01*
X934330Y989532D01*
X932670D01*
X932120Y988982D01*
Y979952D01*
X931780Y979612D01*
X929820D01*
X929010Y980422D01*
Y981532D01*
X928760Y981782D01*
X923100D01*
X921560Y983322D01*
Y992472D01*
X921690Y992602D01*
G37*
G36*
G01X932620Y194399D02*
X939813D01*
G02X940196Y193884I0J-400D01*
G03X940132Y193451I1438J-434D01*
G03X941634Y191949I1502J0D01*
G03X943039Y192921I0J1501D01*
G02X943590Y193139I374J-141D01*
G03X944250Y192986I661J1350D01*
G03X945437Y193567I0J1503D01*
G02X946035Y193605I316J-245D01*
G01X950730Y188910D01*
Y183380D01*
X950260Y182910D01*
X942442D01*
G02X942076Y183470I1J400D01*
G03X942226Y184190I-1653J720D01*
G03X940424Y185992I-1802J0D01*
G03X938787Y184944I0J-1803D01*
G02X938061I-363J167D01*
G03X936424Y185992I-1637J-755D01*
G03X934644Y184473I0J-1802D01*
G02X933967Y184253I-395J63D01*
G01X932520Y185700D01*
Y188499D01*
X932320Y188699D01*
Y194099D01*
X932620Y194399D01*
G37*
G36*
G01X930590Y379861D02*
Y386951D01*
X931116Y387477D01*
X939468D01*
X940571Y386374D01*
Y379808D01*
X939836Y379073D01*
X931378D01*
X930590Y379861D01*
G37*
G36*
G01X933800Y498732D02*
X935710D01*
X936150Y498292D01*
Y493192D01*
X936128Y493170D01*
Y492626D01*
X938334Y490420D01*
Y488216D01*
X937939Y487821D01*
X935085D01*
X934290Y488616D01*
Y492752D01*
X933725Y493317D01*
X933710Y493354D01*
G03X933535Y493680I-1622J-661D01*
G01X933500Y493731D01*
Y494202D01*
X933300Y494402D01*
X932464D01*
X932444Y494406D01*
G03X932233Y494437I-360J-1714D01*
G01X932159Y494443D01*
X931896Y494706D01*
Y496828D01*
X933800Y498732D01*
G37*
G36*
G01X938550Y969442D02*
X939270Y970162D01*
X951020D01*
X951870Y969312D01*
Y961142D01*
X951150Y960422D01*
X939660D01*
X938550Y961532D01*
Y969442D01*
G37*
G36*
G01X942916Y987138D02*
X944394D01*
X944911Y986621D01*
Y973033D01*
X943680Y971802D01*
X938670D01*
X938010Y972462D01*
Y979182D01*
X941670Y982842D01*
Y983236D01*
X942272Y983837D01*
Y986494D01*
X942916Y987138D01*
G37*
G36*
G01X992930Y204559D02*
Y191769D01*
X989010Y187849D01*
X956210D01*
X951780Y192279D01*
Y196959D01*
X961460Y206639D01*
X965020D01*
X965800Y207419D01*
X990070D01*
X992930Y204559D01*
G37*
G36*
G01X988020Y388662D02*
X992270D01*
X992456Y388476D01*
Y381302D01*
X991656Y380502D01*
X986856D01*
X985878Y379524D01*
Y375352D01*
G02X985168Y375099I-400J0D01*
G03X983770Y375764I-1398J-1137D01*
G03X981968Y373962I0J-1802D01*
G03X983754Y372160I1802J0D01*
G02X984033Y371477I-4J-400D01*
G01X982830Y370274D01*
X969068D01*
X967309Y372033D01*
X945193D01*
X942777Y374449D01*
Y384220D01*
X943355Y384798D01*
X947084D01*
X948660Y383222D01*
X957643D01*
X958746Y382119D01*
X963527D01*
X964170Y382762D01*
X968763D01*
G02X969073Y382109I0J-400D01*
G03X968873Y381541I690J-562D01*
G01X968874D01*
Y380363D01*
X968873D01*
G03X968992Y379913I890J-5D01*
G01X969018Y379867D01*
Y378327D01*
G03X969254Y377595I1257J1D01*
G03X970730Y376370I1476J277D01*
G03X972232Y377872I0J1502D01*
G03X971532Y379142I-1502J0D01*
G01Y379702D01*
X972884D01*
Y379466D01*
X973937D01*
G03X974827Y380363I0J890D01*
G01X974826D01*
Y381541D01*
X974827D01*
G03X974708Y381991I-890J5D01*
G01X974682Y382037D01*
Y382762D01*
X976870D01*
G03X979028I1079J1442D01*
G01X982120D01*
X988020Y388662D01*
G37*
G36*
G01X955357Y385271D02*
X955279Y385349D01*
Y390392D01*
X955594Y390707D01*
X958904D01*
X962633Y386978D01*
Y383669D01*
X962265Y383301D01*
X960216D01*
X958246Y385271D01*
X955357D01*
G37*
G36*
G01X948439Y410022D02*
X983142D01*
X987452Y405712D01*
X995183D01*
X995767Y405128D01*
Y403543D01*
X995266Y403042D01*
X993486D01*
X992291Y401847D01*
Y395036D01*
X991707Y394452D01*
X988145D01*
X987619Y394978D01*
Y400652D01*
X981002Y407269D01*
X966639D01*
G03X965141I-749J-1303D01*
G01X950246D01*
X949254Y406277D01*
X949218Y406262D01*
G03X948260Y405304I702J-1660D01*
G01X948245Y405268D01*
X947799Y404822D01*
Y400374D01*
X948864Y399309D01*
X948873Y399241D01*
G03X950429Y397685I1787J231D01*
G01X950497Y397676D01*
X954362Y393811D01*
Y390891D01*
X954278Y390807D01*
Y386002D01*
X953755Y385480D01*
X949606D01*
X948949Y386137D01*
Y386247D01*
X948856D01*
X944463Y390640D01*
Y406046D01*
X948439Y410022D01*
G37*
G36*
G01X947060Y971712D02*
X945680Y973092D01*
Y991792D01*
X946730Y992842D01*
X963190D01*
X964680Y991352D01*
Y973272D01*
X963120Y971712D01*
X947060D01*
G37*
G36*
G01X1079941Y1565441D02*
X1079000Y1564500D01*
X973468D01*
X970968Y1567000D01*
X944540D01*
X943610Y1567930D01*
Y1600280D01*
X944830Y1601500D01*
X1078000D01*
X1078059Y1601441D01*
X1080000Y1599500D01*
Y1565500D01*
X1079941Y1565441D01*
G37*
G36*
G01X1180870Y1734620D02*
X1184560Y1730930D01*
Y1700017D01*
X1171088Y1686545D01*
G03X1171080Y1686537I884J-892D01*
G01X1150413Y1665869D01*
G03X1150114Y1665394I887J-890D01*
G03X1150044Y1664981I1187J-414D01*
G01Y1647186D01*
X1148058Y1645200D01*
G02X1147572Y1645139I-282J283D01*
G03X1149931Y1653543I-13793J8405D01*
G03X1117627I-16152J0D01*
G03X1127351Y1638725I16152J0D01*
G02X1126987Y1638490I-364J165D01*
G01X1052330D01*
X1049842Y1640978D01*
Y1654047D01*
X1043817Y1660072D01*
X992753D01*
X991311Y1658629D01*
X985960Y1663980D01*
X968760D01*
X954565Y1678175D01*
Y1727225D01*
X955990Y1728650D01*
X1090410D01*
X1096380Y1734620D01*
X1150000D01*
G02X1150379Y1734344I-1J-400D01*
G03X1135606Y1714961I5329J-19383D01*
G03X1175810I20102J0D01*
G03X1161039Y1734343I-20102J0D01*
G02X1161418Y1734620I380J-123D01*
G01X1180870D01*
G37*
G36*
G01X962220Y217499D02*
X973240D01*
X974170Y216569D01*
Y211069D01*
X972740Y209639D01*
X962140D01*
X961720Y210059D01*
Y211703D01*
G03Y213633I-1017J965D01*
G01Y216999D01*
X962220Y217499D01*
G37*
G36*
G01X967528Y352968D02*
X968228Y353668D01*
X980528D01*
X982328Y351868D01*
Y340468D01*
X981628Y339768D01*
X968128D01*
X967528Y340368D01*
Y352968D01*
G37*
G36*
G01X967370Y511362D02*
G03I-650J0D01*
G37*
G36*
G01X959240Y1560250D02*
X966410D01*
X967180Y1559480D01*
Y1553880D01*
X966400Y1553100D01*
X965380D01*
X964400Y1554080D01*
Y1556270D01*
X962540Y1558130D01*
X959600D01*
X959330D01*
X959090Y1558370D01*
Y1560100D01*
X959240Y1560250D01*
G37*
G36*
G01X960490Y1564340D02*
X965940D01*
X970500D01*
X971565Y1563275D01*
Y1562146D01*
X970669Y1561250D01*
X970175D01*
X966300D01*
X960870D01*
X959650D01*
X959560D01*
X959140Y1561670D01*
Y1564050D01*
X959430Y1564340D01*
X959550D01*
X960490D01*
G37*
G36*
G01X986020Y392662D02*
X986320Y392962D01*
X991620D01*
X992220Y392362D01*
Y389962D01*
X992020Y389762D01*
X986920D01*
X986020Y390662D01*
Y392662D01*
G37*
G36*
G01X984370Y512362D02*
G03I-650J0D01*
G37*
G36*
G01X994410Y1656070D02*
X1042160D01*
X1045840Y1652390D01*
Y1633910D01*
X1044060Y1632130D01*
X1004710D01*
X998216Y1638626D01*
X979365D01*
X978840Y1639150D01*
Y1652740D01*
X980460Y1654360D01*
X992700D01*
X994410Y1656070D01*
G37*
G36*
G01X1042553Y291154D02*
X1071159D01*
X1072468Y289845D01*
Y266920D01*
X1065773Y260225D01*
Y245777D01*
X1065515Y245518D01*
X1025005D01*
X1019105Y247962D01*
X997909Y269158D01*
Y274907D01*
X999302Y276300D01*
X1027699D01*
X1042553Y291154D01*
G37*
G36*
G01X1005500Y381362D02*
X1009823D01*
Y371062D01*
X1007623Y368862D01*
X1005723D01*
X1004000Y370585D01*
Y374565D01*
X1004463Y375029D01*
G03X1004832Y375917I-887J889D01*
G01Y379777D01*
X1004858Y379823D01*
G03X1004977Y380273I-771J445D01*
G01X1004976D01*
Y380838D01*
X1005500Y381362D01*
G37*
G36*
G01X995931Y402291D02*
X1017399D01*
X1019094Y400596D01*
Y398939D01*
X1019104Y398929D01*
Y378454D01*
X1019080Y378430D01*
X1015432D01*
X1012000Y381862D01*
X1010824D01*
Y382364D01*
X1005498D01*
X1005000Y382862D01*
X1000500D01*
X999986Y382348D01*
X999905Y382347D01*
G03X999173Y381951I8J-890D01*
G01X999114Y381862D01*
X994500D01*
X993500Y382862D01*
X993458D01*
Y388891D01*
X993456Y388892D01*
Y401302D01*
X994194Y402040D01*
X995681D01*
X995931Y402291D01*
G37*
G36*
G01X1022804Y416188D02*
X1028150D01*
X1028863Y415475D01*
Y394938D01*
X1028864Y394937D01*
Y394462D01*
X1027226Y392824D01*
X1021045D01*
X1020106Y393764D01*
Y399344D01*
X1020105D01*
Y401012D01*
X1017679Y403438D01*
X1002919D01*
X1002389Y403968D01*
Y415468D01*
X1003109Y416188D01*
X1008612D01*
X1008619Y415995D01*
G03X1010420Y414260I1801J67D01*
G03X1012154Y415572I0J1802D01*
G01X1012195Y415718D01*
X1014581D01*
G03X1015176Y415488I597J660D01*
G01X1016230D01*
Y415724D01*
X1017611D01*
G03X1018838Y415222I1228J1250D01*
G01X1021239D01*
G03X1022804Y416188I0J1751D01*
G37*
G36*
G01X1000370Y512862D02*
G03I-650J0D01*
G37*
G36*
G01X1032040Y1420330D02*
G02I-15800J0D01*
G37*
G36*
G01X1021253Y387362D02*
X1022923D01*
X1027658Y382627D01*
X1027673Y382583D01*
G03X1028607Y381649I1421J487D01*
G01X1028651Y381634D01*
X1028871Y381414D01*
X1033772D01*
X1037720Y385362D01*
X1048500D01*
X1049000Y384862D01*
Y378862D01*
X1047600Y377462D01*
X1043020D01*
X1041467Y375909D01*
Y371215D01*
X1041020Y370768D01*
X1013679D01*
X1013123Y371324D01*
Y376962D01*
X1014004Y377843D01*
X1014603D01*
X1015017Y377428D01*
X1019495D01*
X1020106Y378039D01*
Y378476D01*
X1020153Y378524D01*
Y386262D01*
X1021253Y387362D01*
G37*
G36*
G01X1009370Y498362D02*
G03I-650J0D01*
G37*
G36*
G01X1012370Y589362D02*
G03I-650J0D01*
G37*
G36*
G01X1019370Y592362D02*
G03I-650J0D01*
G37*
G36*
G01X1022370Y601862D02*
G03I-650J0D01*
G37*
G36*
G01X1011280Y748741D02*
G03I-650J0D01*
G37*
G36*
G01X1080018Y1339052D02*
X1245720D01*
X1249307Y1335465D01*
Y1261325D01*
X1247846Y1259864D01*
X1225399D01*
G03X1222979I-1210J-710D01*
G01X1222725D01*
G02X1222327Y1260226I0J400D01*
G03X1220931Y1261495I-1396J-133D01*
G03X1219622Y1260595I0J-1402D01*
G01X1219573Y1260466D01*
X1219145D01*
G03X1218686Y1260375I0J-1201D01*
G01X1217956Y1260073D01*
G03X1217620Y1259864I458J-1111D01*
G01X1211823D01*
X1211375Y1260311D01*
G03X1211335Y1260350I-897J-880D01*
G03X1209790Y1261225I-1545J-927D01*
G03X1208498Y1260680I-1J-1802D01*
G01X1205229D01*
G03X1204341Y1260311I1J-1256D01*
G01X1203893Y1259864D01*
X1199232D01*
X1199048Y1260047D01*
G03X1198160Y1260416I-889J-887D01*
G01X1197623D01*
X1196726Y1261312D01*
Y1261508D01*
X1196781Y1261566D01*
G03X1197272Y1262802I-1310J1236D01*
G03X1195470Y1264604I-1802J0D01*
G03X1194976Y1264535I0J-1803D01*
G02X1194466Y1264920I-110J385D01*
G01Y1266338D01*
G03X1195392Y1267912I-875J1574D01*
G03X1195034Y1268989I-1802J-1D01*
G01Y1273042D01*
X1193636Y1274440D01*
X1182968D01*
X1181886Y1273359D01*
Y1267529D01*
X1182973Y1266442D01*
X1188973D01*
X1189012Y1266404D01*
X1189999D01*
X1190471Y1265932D01*
X1191954D01*
Y1260414D01*
G02X1191423Y1260036I-400J0D01*
G03X1190966Y1260113I-458J-1325D01*
G03X1190168Y1259864I0J-1403D01*
G01X1184275D01*
X1183559Y1260580D01*
X1183545Y1260633D01*
G03X1181850Y1261944I-1695J-440D01*
G03X1180851Y1261631I0J-1751D01*
G02X1180572Y1261683I-114J164D01*
G03X1179080Y1262474I-1492J-1012D01*
G03X1177288Y1260858I0J-1802D01*
G01X1177269Y1260678D01*
X1174945D01*
G03X1174057Y1260310I0J-1255D01*
G01X1173610Y1259864D01*
X1169303D01*
G03X1167663I-820J-1136D01*
G01X1162055D01*
G03X1160075I-990J-994D01*
G01X1154723D01*
X1154621Y1259965D01*
G03X1153383Y1260478I-1238J-1237D01*
G01X1152341D01*
G03X1152265Y1260477I-15J-1751D01*
G02X1151912Y1261094I-17J400D01*
G03X1152202Y1262074I-1511J980D01*
G03X1148598I-1802J0D01*
G03X1148682Y1261532I1802J2D01*
G02X1148300Y1261012I-382J-120D01*
G01X1145862D01*
G03X1144974Y1260643I1J-1256D01*
G01X1144194Y1259864D01*
X1139603D01*
G03X1138783Y1260129I-820J-1136D01*
G03X1138011Y1259897I0J-1402D01*
G01X1137961Y1259864D01*
X1137524D01*
Y1260451D01*
X1137525D01*
G03X1136635Y1261348I-890J7D01*
G01X1135582D01*
Y1261112D01*
X1133514D01*
Y1261348D01*
X1132461D01*
G03X1131571Y1260451I0J-890D01*
G01X1131572D01*
Y1260110D01*
X1131325Y1259864D01*
X1125023D01*
X1124921Y1259965D01*
G03X1123683Y1260478I-1238J-1237D01*
G01X1122641D01*
G03X1122227Y1260429I-3J-1751D01*
G02X1122042Y1260768I-47J194D01*
G03X1122602Y1262074I-1243J1306D01*
G03X1120800Y1260272I-1802J0D01*
G03X1121238Y1260326I0J1803D01*
G02X1121426Y1259988I49J-194D01*
G03X1121403Y1259965I1226J-1249D01*
G01X1121301Y1259864D01*
X1111435D01*
X1107996Y1263302D01*
Y1266610D01*
G03X1108384Y1267165I-1256J1292D01*
G02X1109032Y1267284I365J-164D01*
G01X1109873Y1266442D01*
X1116703D01*
X1117790Y1267529D01*
Y1273359D01*
X1115703Y1275446D01*
X1110873D01*
X1108786Y1273359D01*
Y1269364D01*
G02X1108087Y1269098I-400J0D01*
G03X1106740Y1269704I-1348J-1196D01*
G03X1104938Y1267902I0J-1802D01*
G03X1105484Y1266610I1802J0D01*
G01Y1265163D01*
G02X1104801Y1264879I-400J-1D01*
G03X1103530Y1265404I-1271J-1276D01*
G03X1101728Y1263602I0J-1802D01*
G03X1102717Y1261994I1802J0D01*
G01X1102746Y1261979D01*
X1104178Y1260547D01*
G02X1103895Y1259864I-283J-283D01*
G01X1095323D01*
X1095221Y1259965D01*
G03X1093983Y1260478I-1238J-1237D01*
G01X1092941D01*
G03X1092865Y1260477I-15J-1751D01*
G02X1092512Y1261094I-17J400D01*
G03X1092802Y1262074I-1511J980D01*
G03X1091000Y1260272I-1802J0D01*
G03X1091569Y1260364I1J1802D01*
G02X1091766Y1260026I63J-190D01*
G03X1091609Y1259864I1177J-1297D01*
G01X1080203D01*
G03X1079383Y1260129I-820J-1136D01*
G03X1078611Y1259897I0J-1402D01*
G01X1078561Y1259864D01*
X1078139D01*
G03X1074901I-1619J-793D01*
G01X1065623D01*
X1065521Y1259965D01*
G03X1064283Y1260478I-1238J-1237D01*
G01X1063241D01*
X1063190D01*
G02X1062843Y1261095I-11J400D01*
G03X1063132Y1262074I-1514J979D01*
G03X1061330Y1260272I-1802J0D01*
G03X1061857Y1260351I-1J1802D01*
G02X1062052Y1260013I59J-191D01*
G03X1061909Y1259864I1190J-1285D01*
G01X1050503D01*
G03X1049683Y1260129I-820J-1136D01*
G03X1049074Y1259990I0J-1402D01*
G02X1048557Y1260145I-174J360D01*
G03X1047010Y1261024I-1547J-922D01*
G03X1045375Y1259980I0J-1802D01*
G01X1045321Y1259864D01*
X1035923D01*
X1035821Y1259965D01*
G03X1034583Y1260478I-1238J-1237D01*
G01X1033541D01*
G03X1033080Y1260417I-3J-1751D01*
G02X1032585Y1260893I-105J386D01*
G03X1032632Y1261302I-1756J409D01*
G03X1029028I-1802J0D01*
G01Y1261283D01*
G02X1028628Y1260878I-400J-5D01*
G01X1025344D01*
G03X1024456Y1260510I0J-1255D01*
G01X1023809Y1259864D01*
X1010005D01*
X1008738Y1261131D01*
Y1271521D01*
G03X1008994Y1272345I-1201J825D01*
G01Y1276750D01*
X1010412Y1278168D01*
X1022907D01*
G03X1023937Y1278595I0J1456D01*
G01X1028187Y1282845D01*
G03X1028614Y1283875I-1029J1030D01*
G01Y1289712D01*
X1042546Y1303644D01*
X1044610D01*
X1080018Y1339052D01*
G37*
G36*
G01X1031249Y408648D02*
X1031859Y409258D01*
X1043119D01*
X1044089Y408288D01*
Y387451D01*
X1044000Y387362D01*
X1038499D01*
X1037809Y388052D01*
Y392588D01*
X1038959Y393738D01*
Y400878D01*
X1037529Y402308D01*
X1031819D01*
X1031249Y402878D01*
Y408648D01*
G37*
G36*
G01X1030020Y420962D02*
X1041120D01*
X1041820Y420262D01*
Y412362D01*
X1040920Y411462D01*
X1030620D01*
X1029864Y412218D01*
Y415890D01*
X1029720Y416034D01*
Y420662D01*
X1030020Y420962D01*
G37*
G36*
G01X1031420Y429262D02*
X1037620D01*
X1039620Y427262D01*
Y422362D01*
X1039320Y422062D01*
X1030520D01*
X1029920Y422662D01*
Y427762D01*
X1031420Y429262D01*
G37*
G36*
G01X1077343Y204724D02*
G02I-19685J0D01*
G37*
G36*
G01X1074297Y294137D02*
X1108956D01*
X1109030Y294062D01*
X1127480D01*
X1129050Y292492D01*
Y249732D01*
X1143310Y235472D01*
X1187650D01*
X1189600Y233522D01*
Y227767D01*
G02X1189074Y227387I-400J0D01*
G03X1188600Y227464I-475J-1425D01*
G03Y224460I0J-1502D01*
G03X1189074Y224537I-1J1502D01*
G02X1189600Y224157I126J-380D01*
G01Y181862D01*
X1190890Y180572D01*
X1210620D01*
X1214364Y184316D01*
X1214422Y184328D01*
G03X1215677Y185309I-368J1764D01*
G01X1215732Y185422D01*
X1223816D01*
X1223846Y185412D01*
G03X1224235Y185350I390J1195D01*
G01X1244491D01*
X1245440Y184402D01*
Y181342D01*
X1242630Y178532D01*
X1227488D01*
X1227433Y178642D01*
G03X1224753I-1340J-681D01*
G01X1224698Y178532D01*
X1221690D01*
X1208750Y165592D01*
X1170970D01*
X1169180Y167382D01*
Y173422D01*
X1171200Y175442D01*
Y176065D01*
X1171548D01*
X1171591Y175924D01*
G03X1173314Y174650I1723J528D01*
G03Y178254I0J1802D01*
G03X1171911Y177583I0J-1802D01*
G02X1171200Y177834I-311J251D01*
G01Y192961D01*
G02X1171908Y193216I400J0D01*
G03X1173065Y192672I1157J958D01*
G03Y195676I0J1502D01*
G03X1171908Y195132I0J-1502D01*
G02X1171200Y195387I-308J255D01*
G01Y208754D01*
G02X1171866Y209052I400J0D01*
G03X1172865Y208672I999J1123D01*
G03X1171363Y210174I0J1502D01*
G03X1171365Y210093I1502J-3D01*
G02X1170683Y209789I-399J-21D01*
G01X1169890Y210582D01*
X1136750D01*
X1120940Y226392D01*
X1099420D01*
X1080910Y244902D01*
X1078157D01*
X1077908Y245150D01*
G03X1077020Y245518I-888J-887D01*
G01X1068752D01*
X1067891Y246379D01*
Y260716D01*
X1073818Y266643D01*
Y293658D01*
X1074297Y294137D01*
G37*
G36*
G01X1106502Y1597548D02*
Y1565860D01*
X1105142Y1564500D01*
X1085200D01*
X1084200Y1565500D01*
Y1597750D01*
X1084580Y1598130D01*
X1092190D01*
X1092200Y1598120D01*
X1105930D01*
X1106502Y1597548D01*
G37*
G36*
G01X1152358Y1359802D02*
G02X1152680Y1359165I0J-400D01*
G03X1151998Y1357089I2820J-2076D01*
G01Y1357088D01*
G03X1159002I3502J0D01*
G01Y1357089D01*
G03X1158320Y1359165I-3502J0D01*
G02X1158642Y1359802I322J237D01*
G01X1176758D01*
G02X1177080Y1359165I0J-400D01*
G03X1176398Y1357089I2820J-2076D01*
G01Y1357088D01*
G03X1183402I3502J0D01*
G01Y1357089D01*
G03X1182720Y1359165I-3502J0D01*
G02X1183042Y1359802I322J237D01*
G01X1200680D01*
X1201810Y1360932D01*
Y1392102D01*
X1197950Y1395962D01*
Y1399642D01*
X1199970Y1401662D01*
Y1434870D01*
X1202192D01*
G03X1202694Y1435372I0J502D01*
G01Y1440076D01*
X1207000Y1444382D01*
X1245890D01*
X1249240Y1441032D01*
Y1345002D01*
X1247389Y1343151D01*
X1193101D01*
X1192882Y1342932D01*
X1189791D01*
X1189772Y1342951D01*
X1095181D01*
X1093880Y1344252D01*
Y1422172D01*
X1095230Y1423522D01*
X1117100D01*
X1120280Y1426702D01*
X1122790D01*
X1126390Y1423102D01*
Y1398592D01*
X1121881Y1394083D01*
X1116181D01*
X1114660Y1392562D01*
Y1361312D01*
X1116170Y1359802D01*
X1127958D01*
G02X1128280Y1359165I0J-400D01*
G03X1127598Y1357089I2820J-2076D01*
G01Y1357088D01*
G03X1134602I3502J0D01*
G01Y1357089D01*
G03X1133920Y1359165I-3502J0D01*
G02X1134242Y1359802I322J237D01*
G01X1152358D01*
G37*
G36*
G01X1109788Y1272944D02*
X1111288Y1274444D01*
X1115288D01*
X1116788Y1272944D01*
Y1267944D01*
X1116288Y1267444D01*
X1110288D01*
X1109788Y1267944D01*
Y1272944D01*
G37*
G36*
G01X1170021Y1393753D02*
X1181159D01*
X1181862Y1393050D01*
X1197971D01*
X1199682Y1391339D01*
Y1361824D01*
X1198670Y1360812D01*
X1117100D01*
X1116110Y1361802D01*
Y1392562D01*
X1116598Y1393050D01*
X1130278D01*
X1130860Y1393632D01*
X1142400D01*
X1142982Y1393050D01*
X1169318D01*
X1170021Y1393753D01*
G37*
G36*
G01X1195373Y1428095D02*
X1196740Y1429462D01*
Y1443532D01*
X1197470Y1444262D01*
X1207422D01*
X1208372Y1443312D01*
Y1394774D01*
X1207677Y1394079D01*
X1182793D01*
X1181979Y1394893D01*
X1169681D01*
X1168867Y1394079D01*
X1143523D01*
X1142969Y1394633D01*
X1129465D01*
X1128911Y1394079D01*
X1120423D01*
X1120003Y1394499D01*
Y1426649D01*
X1120782Y1427428D01*
X1121581Y1428227D01*
X1128608D01*
X1129909Y1429528D01*
Y1436834D01*
X1130373Y1437298D01*
X1136786D01*
X1136928Y1437239D01*
X1137110Y1437057D01*
G02X1137152Y1436996I-141J-142D01*
G01Y1428493D01*
X1137550Y1428095D01*
X1151466D01*
X1154365D01*
X1155398D01*
X1156322Y1429019D01*
Y1437489D01*
X1154892Y1438919D01*
Y1448589D01*
X1157572Y1451269D01*
X1159652D01*
X1160272Y1450649D01*
Y1449679D01*
X1159604Y1449011D01*
X1159072Y1448479D01*
Y1428943D01*
X1159604Y1428411D01*
X1159922Y1428092D01*
X1160932D01*
X1165545D01*
X1167172Y1429719D01*
Y1436619D01*
X1167849Y1437296D01*
X1174780D01*
X1175332Y1436744D01*
Y1429099D01*
X1176336Y1428095D01*
X1195373D01*
G37*
G36*
G01X1137075Y1447441D02*
X1136592Y1446958D01*
X1135426D01*
X1134403Y1447981D01*
X1128470D01*
X1127411Y1446922D01*
X1125220D01*
X1124743Y1447399D01*
Y1448634D01*
Y1450964D01*
X1125042Y1451263D01*
X1127797D01*
X1136529D01*
X1137504Y1450288D01*
Y1447870D01*
X1137075Y1447441D01*
G37*
G36*
G01X1142627Y1459937D02*
X1141382Y1458692D01*
X1127523D01*
X1126829Y1459386D01*
Y1471632D01*
Y1471998D01*
X1127723Y1472892D01*
X1142083D01*
X1142627Y1472348D01*
Y1459937D01*
G37*
G36*
G01X1150402Y1479032D02*
X1194162D01*
X1195320Y1477874D01*
Y1430192D01*
X1194234Y1429106D01*
X1176545D01*
X1176398Y1429253D01*
Y1437174D01*
X1180234Y1441010D01*
Y1449614D01*
X1177573Y1452275D01*
X1156805D01*
X1153664Y1449134D01*
Y1436839D01*
X1155172Y1435331D01*
Y1430169D01*
X1154109Y1429106D01*
X1138935D01*
X1138102Y1429939D01*
Y1438552D01*
X1142312Y1442762D01*
Y1450762D01*
X1148702Y1457152D01*
Y1477332D01*
X1150402Y1479032D01*
G37*
G36*
G01X1157500Y208462D02*
X1168000D01*
X1169700Y206762D01*
Y180062D01*
X1168800Y179162D01*
X1157300D01*
X1155700Y180762D01*
Y192834D01*
X1158168D01*
G03X1159460Y192288I1292J1256D01*
G03Y195892I0J1802D01*
G03X1158168Y195346I0J-1802D01*
G01X1155700D01*
Y206662D01*
X1157500Y208462D01*
G37*
G36*
G01X1175218Y1447416D02*
X1174735Y1446933D01*
X1173569D01*
X1172546Y1447956D01*
X1169710D01*
X1168306Y1449360D01*
X1163106D01*
X1162886Y1449580D01*
Y1450939D01*
X1163185Y1451238D01*
X1165940D01*
X1174672D01*
X1175647Y1450263D01*
Y1447845D01*
X1175218Y1447416D01*
G37*
G36*
G01X1183383Y1273439D02*
X1193221D01*
X1194033Y1272627D01*
Y1270114D01*
G02X1193625Y1269714I-400J0D01*
G01X1193590D01*
G03X1191788Y1267912I0J-1802D01*
G03X1191851Y1267438I1802J-2D01*
G02X1191466Y1266933I-386J-105D01*
G01X1190886D01*
X1190414Y1267405D01*
X1189427D01*
X1189388Y1267444D01*
X1183388D01*
X1182888Y1267944D01*
Y1272944D01*
X1183383Y1273439D01*
G37*
G36*
G01X1191300Y222462D02*
X1199100D01*
X1199900Y221662D01*
Y213709D01*
G03Y211587I1063J-1061D01*
G01Y207181D01*
G03X1199328Y206002I929J-1179D01*
G03X1199368Y205657I1502J-1D01*
G01X1199374Y205634D01*
Y201612D01*
G03X1199800Y200582I1456J-1D01*
G01X1199900Y200482D01*
Y189120D01*
G03Y186604I819J-1258D01*
G01Y186120D01*
G03X1199218Y184863I820J-1258D01*
G01Y184780D01*
X1197000Y182562D01*
X1192200D01*
X1190700Y184062D01*
Y221862D01*
X1191300Y222462D01*
G37*
G36*
G01X1199030Y1015832D02*
X1244530D01*
X1246000Y1014362D01*
Y989922D01*
X1244900Y988822D01*
X1237373D01*
G03X1235793I-790J-1157D01*
G01X1228673D01*
G03X1227883Y989066I-790J-1157D01*
G03X1227139Y988852I0J-1402D01*
G01X1227091Y988822D01*
X1226818D01*
G02X1226676Y989163I0J200D01*
G01X1228771Y991259D01*
G03X1229140Y992147I-887J889D01*
G01Y993734D01*
X1229158Y993773D01*
G03X1229285Y994357I-1275J583D01*
G03X1226481I-1402J0D01*
G03X1226608Y993773I1402J-1D01*
G01X1226626Y993734D01*
Y992667D01*
X1224058Y990099D01*
X1223978Y990096D01*
G03X1222352Y988949I53J-1801D01*
G01X1222302Y988822D01*
X1208160D01*
X1201007Y995975D01*
Y1003957D01*
X1198174Y1006790D01*
Y1012202D01*
X1198141Y1012235D01*
Y1014944D01*
X1199030Y1015832D01*
G37*
G36*
G01X1211587Y1028018D02*
X1222547D01*
X1225659Y1024907D01*
G03X1226547Y1024538I889J887D01*
G01X1239587D01*
Y1017375D01*
X1239130Y1016918D01*
X1197844D01*
X1197477Y1017285D01*
Y1024662D01*
X1197593Y1024778D01*
X1207827D01*
G03X1208715Y1025147I-1J1256D01*
G01X1211587Y1028018D01*
G37*
G36*
G01X1195146Y1578182D02*
G03I-574J0D01*
G37*
G36*
G01Y1590094D02*
G03I-574J0D01*
G37*
G36*
G01X1200446Y1614292D02*
G03I-574J0D01*
G37*
G36*
G01Y1602380D02*
G03I-574J0D01*
G37*
G36*
G01X1206100Y988062D02*
X1207504D01*
X1207745Y987820D01*
X1222287D01*
X1222334Y987688D01*
G03X1225728I1697J607D01*
G01X1225775Y987820D01*
X1238742D01*
X1239200Y987362D01*
Y980562D01*
X1238582Y979944D01*
X1206141D01*
X1205641Y980444D01*
Y987603D01*
X1206100Y988062D01*
G37*
G36*
G01X1202946Y1578182D02*
G03I-574J0D01*
G37*
G36*
G01X1215006D02*
G03I-574J0D01*
G37*
G36*
G01X1207206D02*
G03I-574J0D01*
G37*
G36*
G01X1202946Y1590094D02*
G03I-574J0D01*
G37*
G36*
G01X1215006D02*
G03I-574J0D01*
G37*
G36*
G01X1207206D02*
G03I-574J0D01*
G37*
G36*
G01X1208246Y1602380D02*
G03I-574J0D01*
G37*
G36*
G01Y1614292D02*
G03I-574J0D01*
G37*
G36*
G01X1212506D02*
G03I-574J0D01*
G37*
G36*
G01Y1602380D02*
G03I-574J0D01*
G37*
G36*
G01X1219266Y1578182D02*
G03I-574J0D01*
G37*
G36*
G01X1227066D02*
G03I-574J0D01*
G37*
G36*
G01X1231326D02*
G03I-574J0D01*
G37*
G36*
G01X1219266Y1590094D02*
G03I-574J0D01*
G37*
G36*
G01X1227066D02*
G03I-574J0D01*
G37*
G36*
G01X1231326D02*
G03I-574J0D01*
G37*
G36*
G01X1220306Y1614292D02*
G03I-574J0D01*
G37*
G36*
G01Y1602380D02*
G03I-574J0D01*
G37*
G36*
G01X1232366Y1614292D02*
G03I-574J0D01*
G37*
G36*
G01Y1602380D02*
G03I-574J0D01*
G37*
G36*
G01X1224566D02*
G03I-574J0D01*
G37*
G36*
G01Y1614292D02*
G03I-574J0D01*
G37*
G36*
G01X1243069Y165362D02*
G03I-549J0D01*
G37*
G36*
G01X1239126Y1578182D02*
G03I-574J0D01*
G37*
G36*
G01X1243386D02*
G03I-574J0D01*
G37*
G36*
G01X1239126Y1590094D02*
G03I-574J0D01*
G37*
G36*
G01X1243386D02*
G03I-574J0D01*
G37*
G36*
G01X1236626Y1602380D02*
G03I-574J0D01*
G37*
G36*
G01Y1614292D02*
G03I-574J0D01*
G37*
G36*
G01X1244426D02*
G03I-574J0D01*
G37*
G36*
G01Y1602380D02*
G03I-574J0D01*
G37*
G36*
G01X1248686D02*
G03I-574J0D01*
G37*
G36*
G01Y1614292D02*
G03I-574J0D01*
G37*
G36*
G01X1265234Y175506D02*
G03I-549J0D01*
G37*
G36*
G01X1256650Y262474D02*
X1283413D01*
X1283635Y262252D01*
Y258841D01*
X1283502Y258708D01*
X1279105D01*
X1278338Y257941D01*
Y256086D01*
X1278709Y255715D01*
Y254625D01*
X1278165Y254081D01*
Y251534D01*
X1280485Y249214D01*
Y247257D01*
X1281363Y246379D01*
Y244777D01*
X1280744Y244158D01*
X1273697D01*
X1269742Y240202D01*
X1269723D01*
X1268333Y238812D01*
Y234762D01*
X1267883Y234312D01*
X1259483D01*
X1257703Y232532D01*
X1255753D01*
X1254786Y233499D01*
G02X1254849Y234116I283J283D01*
G03X1255662Y235622I-988J1506D01*
G03X1254624Y237254I-1802J0D01*
G01X1254509Y237308D01*
Y239497D01*
X1254675Y239526D01*
G03Y243078I-305J1776D01*
G01X1254509Y243107D01*
Y244974D01*
X1254633Y245025D01*
G03Y248359I-682J1667D01*
G01X1254509Y248410D01*
Y249493D01*
X1253627Y250375D01*
Y259765D01*
G03X1256650Y262474I-5989J9724D01*
G37*
G36*
G01X1278594Y278239D02*
X1284262D01*
X1284269Y278232D01*
X1285493D01*
X1285905Y277820D01*
Y275237D01*
X1284437Y273769D01*
Y264735D01*
X1283592Y263890D01*
X1258253D01*
G02X1257894Y264466I0J400D01*
G03X1255719Y277556I-10257J5021D01*
G02X1256002Y278239I283J283D01*
G01X1275006D01*
G02X1275332Y277607I0J-400D01*
G03X1274998Y276562I1468J-1045D01*
G03X1278602I1802J0D01*
G03X1278268Y277607I-1802J0D01*
G02X1278594Y278239I326J232D01*
G37*
G36*
G01X1257437Y749605D02*
G03I-650J0D01*
G37*
G36*
G01X1251186Y1578182D02*
G03I-574J0D01*
G37*
G36*
G01X1263246D02*
G03I-574J0D01*
G37*
G36*
G01X1255446D02*
G03I-574J0D01*
G37*
G36*
G01X1251186Y1590094D02*
G03I-574J0D01*
G37*
G36*
G01X1263246D02*
G03I-574J0D01*
G37*
G36*
G01X1255446D02*
G03I-574J0D01*
G37*
G36*
G01X1256486Y1614292D02*
G03I-574J0D01*
G37*
G36*
G01Y1602380D02*
G03I-574J0D01*
G37*
G36*
G01X1260746D02*
G03I-574J0D01*
G37*
G36*
G01Y1614292D02*
G03I-574J0D01*
G37*
G36*
G01X1275553Y136262D02*
X1276950D01*
X1286230Y126982D01*
Y123468D01*
X1275744Y112982D01*
X1271660Y117067D01*
G03X1270630Y117494I-1030J-1029D01*
G01X1269549D01*
X1268707Y118335D01*
X1268696Y118396D01*
G03X1267265Y119827I-1770J-339D01*
G01X1267204Y119838D01*
X1265750Y121292D01*
Y124910D01*
X1272443Y131602D01*
G03X1272870Y132632I-1029J1030D01*
G01Y133579D01*
X1275553Y136262D01*
G37*
G36*
G01X1280780Y256841D02*
G03I-557J0D01*
G37*
G36*
G01X1280398Y253052D02*
G03I-557J0D01*
G37*
G36*
G01X1293965Y1350310D02*
X1294363Y1349912D01*
X1308279D01*
X1308290Y1349902D01*
X1308297Y1349909D01*
X1308989D01*
X1309440Y1349458D01*
Y1329653D01*
X1311740Y1327353D01*
X1315888D01*
X1316788Y1328253D01*
Y1334017D01*
X1318813Y1336042D01*
X1318842Y1336111D01*
X1319016Y1336285D01*
X1319093Y1336317D01*
X1325727D01*
X1325869Y1336258D01*
X1326052Y1336075D01*
G02X1326093Y1336015I-142J-141D01*
G01Y1327512D01*
X1326491Y1327114D01*
X1340407D01*
X1340418Y1327104D01*
X1340425Y1327111D01*
X1341117D01*
X1341568Y1326660D01*
Y1316453D01*
X1343728Y1314293D01*
X1349878D01*
X1350938Y1315353D01*
Y1322608D01*
X1350997Y1322750D01*
X1351079Y1322832D01*
X1351221Y1322891D01*
X1357855D01*
X1357997Y1322832D01*
X1358180Y1322649D01*
G02X1358221Y1322589I-142J-141D01*
G01Y1314086D01*
X1358619Y1313688D01*
X1381979D01*
X1383066Y1314775D01*
Y1322598D01*
X1383359Y1322891D01*
X1389983D01*
X1390125Y1322832D01*
X1390308Y1322649D01*
G02X1390349Y1322589I-142J-141D01*
G01Y1314086D01*
X1390747Y1313688D01*
X1404663D01*
X1404674Y1313678D01*
X1404681Y1313685D01*
X1414104D01*
X1415194Y1314775D01*
Y1322608D01*
X1415253Y1322750D01*
X1415335Y1322832D01*
X1415477Y1322891D01*
X1422111D01*
X1422253Y1322832D01*
X1422436Y1322649D01*
G02X1422477Y1322589I-142J-141D01*
G01Y1314086D01*
X1422875Y1313688D01*
X1436791D01*
X1436802Y1313678D01*
X1436809Y1313685D01*
X1437952D01*
X1439054Y1312583D01*
X1445130D01*
X1447322Y1314775D01*
Y1322608D01*
X1447381Y1322750D01*
X1447463Y1322832D01*
X1447605Y1322891D01*
X1454239D01*
X1454381Y1322832D01*
X1454564Y1322649D01*
G02X1454605Y1322589I-142J-141D01*
G01Y1314086D01*
X1455003Y1313688D01*
X1468919D01*
X1468930Y1313678D01*
X1468937Y1313685D01*
X1470080D01*
X1471242Y1314847D01*
Y1327207D01*
X1471588Y1327553D01*
X1478802D01*
X1479450Y1328201D01*
Y1336034D01*
X1479509Y1336176D01*
X1479591Y1336258D01*
X1479733Y1336317D01*
X1486367D01*
X1486509Y1336258D01*
X1486692Y1336075D01*
G02X1486733Y1336015I-142J-141D01*
G01Y1327512D01*
X1487131Y1327114D01*
X1502606D01*
X1503372Y1327880D01*
Y1348555D01*
X1503624Y1348807D01*
X1509386D01*
X1511578Y1350999D01*
Y1358832D01*
X1511637Y1358974D01*
X1511719Y1359056D01*
X1511861Y1359115D01*
X1518495D01*
X1518637Y1359056D01*
X1518820Y1358873D01*
G02X1518861Y1358813I-142J-141D01*
G01Y1350310D01*
X1519259Y1349912D01*
X1535594D01*
X1536957Y1351275D01*
Y1377125D01*
X1528110Y1385972D01*
Y1388281D01*
G03Y1402545I-14491J7132D01*
G01Y1407512D01*
X1534230Y1413632D01*
X1538670D01*
X1540397Y1411905D01*
Y1311989D01*
X1535316Y1306908D01*
X1504816D01*
X1502729Y1304821D01*
Y1294841D01*
X1501916Y1294028D01*
X1469440D01*
X1467935Y1292523D01*
Y1280737D01*
X1467717Y1280519D01*
X1349157D01*
X1348022Y1281654D01*
Y1290222D01*
X1344396Y1293848D01*
X1310026D01*
X1309820Y1294054D01*
Y1314459D01*
X1309234Y1315045D01*
X1283456D01*
X1282156Y1313745D01*
X1275867D01*
X1275308Y1314304D01*
Y1348618D01*
X1276743Y1350053D01*
X1283688D01*
X1284788Y1351153D01*
Y1356915D01*
X1286988Y1359115D01*
X1293599D01*
X1293741Y1359056D01*
X1293924Y1358873D01*
G02X1293965Y1358813I-142J-141D01*
G01Y1350310D01*
G37*
G36*
G01X1267506Y1578182D02*
G03I-574J0D01*
G37*
G36*
G01X1275306D02*
G03I-574J0D01*
G37*
G36*
G01X1279566D02*
G03I-574J0D01*
G37*
G36*
G01X1267506Y1590094D02*
G03I-574J0D01*
G37*
G36*
G01X1275306D02*
G03I-574J0D01*
G37*
G36*
G01X1279566D02*
G03I-574J0D01*
G37*
G36*
G01X1268546Y1614292D02*
G03I-574J0D01*
G37*
G36*
G01Y1602380D02*
G03I-574J0D01*
G37*
G36*
G01X1272806D02*
G03I-574J0D01*
G37*
G36*
G01Y1614292D02*
G03I-574J0D01*
G37*
G36*
G01X1280606D02*
G03I-574J0D01*
G37*
G36*
G01Y1602380D02*
G03I-574J0D01*
G37*
G36*
G01X1284963Y262701D02*
X1288804D01*
X1290255Y261250D01*
X1290914D01*
X1311799Y240365D01*
X1322674D01*
X1323313Y239726D01*
Y236660D01*
X1325452Y234521D01*
Y231700D01*
X1325131Y231379D01*
X1295281D01*
X1294010Y232650D01*
Y233217D01*
G03X1293584Y234247I-1456J1D01*
G01X1291941Y235890D01*
Y238279D01*
G02X1292393Y238676I400J0D01*
G03X1292630Y238660I240J1786D01*
G03Y242264I0J1802D01*
G03X1292393Y242248I3J-1802D01*
G02X1291941Y242645I-52J397D01*
G01Y246832D01*
X1291956Y246869D01*
G03X1292095Y247562I-1663J694D01*
G03X1291956Y248255I-1802J-1D01*
G01X1291941Y248292D01*
Y248544D01*
X1286492Y253993D01*
Y254026D01*
X1284211Y256307D01*
Y258001D01*
X1284636Y258426D01*
Y262375D01*
X1284963Y262701D01*
G37*
G36*
G01X1286121Y268459D02*
X1300903D01*
X1318800Y250562D01*
Y246927D01*
X1313240Y241366D01*
X1312214D01*
X1291329Y262252D01*
X1290866D01*
X1289325Y263793D01*
X1285875D01*
X1285480Y264188D01*
Y267818D01*
X1286121Y268459D01*
G37*
G36*
G01X1288053Y279462D02*
X1291706D01*
X1292243Y278925D01*
Y270503D01*
X1291470Y269730D01*
X1286110D01*
X1286047Y269793D01*
Y273247D01*
X1286861Y274061D01*
Y274777D01*
X1286906Y274822D01*
Y278316D01*
X1288053Y279462D01*
G37*
G36*
G01X1293554Y782048D02*
G03I-650J0D01*
G37*
G36*
G01X1293264Y789910D02*
G03I-650J0D01*
G37*
G36*
G01X1390248Y1100924D02*
G03X1391502Y1102221I-44J1297D01*
G03X1390445Y1103496I-1297J0D01*
G01X1390354Y1103513D01*
X1389861Y1104368D01*
Y1106829D01*
G02X1390248Y1107229I400J0D01*
G03Y1110031I-44J1401D01*
G02X1389861Y1110431I13J400D01*
G01Y1112586D01*
G02X1390607Y1112786I400J0D01*
G01X1390859Y1112350D01*
X1390829Y1112263D01*
G03X1390756Y1111834I1224J-429D01*
G03X1393350I1297J0D01*
G03X1392296Y1113109I-1298J0D01*
G01X1392206Y1113126D01*
X1391398Y1114524D01*
X1391429Y1114611D01*
G03X1391502Y1115039I-1225J429D01*
G03X1390248Y1116336I-1298J0D01*
G02X1389861Y1116735I13J400D01*
G01Y1119646D01*
G02X1390248Y1120046I400J0D01*
G03Y1122848I-45J1401D01*
G02X1389861Y1123248I13J400D01*
G01Y1124955D01*
G02X1390253Y1125355I400J0D01*
G03X1392706Y1127856I-48J2501D01*
G01Y1129933D01*
G03X1393356Y1131060I-652J1127D01*
G03X1392534Y1132270I-1302J0D01*
G03X1391578Y1133983I-4180J-1209D01*
G03X1391606Y1134264I-1374J279D01*
G03X1390647Y1135594I-1402J0D01*
G03X1390449Y1136101I-4144J-1326D01*
G03X1390856Y1137469I-2096J1368D01*
G01Y1139847D01*
G03Y1142099I-652J1126D01*
G01Y1142592D01*
G03X1390123Y1144361I-2501J0D01*
G01X1389605Y1144879D01*
G03X1387836Y1145612I-1769J-1768D01*
G01X1386504D01*
X1382323Y1149793D01*
G03X1380554Y1150526I-1769J-1768D01*
G01X1309780D01*
X1287368Y1172938D01*
Y1306949D01*
G03X1286824Y1308506I-2502J-1D01*
G01Y1313032D01*
X1287337Y1313545D01*
X1306656D01*
X1308219Y1311982D01*
Y1293705D01*
X1309116Y1292808D01*
X1343516D01*
X1346646Y1289678D01*
Y1281113D01*
X1348341Y1279418D01*
X1468942D01*
X1469807Y1280283D01*
Y1292425D01*
X1470310Y1292928D01*
X1503247D01*
X1504607Y1294288D01*
Y1304399D01*
X1505316Y1305108D01*
X1534986D01*
X1538596Y1301498D01*
Y1112179D01*
X1523618Y1097202D01*
X1523525Y1097210D01*
G03X1523403Y1097215I-118J-1397D01*
G03X1522001Y1095813I0J-1402D01*
G03X1522006Y1095690I1402J-5D01*
G01X1522015Y1095598D01*
X1521780Y1095363D01*
G02X1521099Y1095683I-283J283D01*
G03X1521105Y1095812I-1396J130D01*
G01Y1095813D01*
G03X1519703Y1094411I-1402J0D01*
G01X1519704D01*
G03X1519833Y1094417I-1J1402D01*
G02X1520153Y1093736I37J-398D01*
G01X1517620Y1091203D01*
X1517196Y1090780D01*
X1514105D01*
G03X1514070Y1090779I23J-1401D01*
G01X1512577D01*
X1512559Y1090782D01*
G03X1512303Y1090806I-258J-1378D01*
G03X1512047Y1090782I2J-1402D01*
G01X1512029Y1090779D01*
X1510536D01*
G03X1510501Y1090780I-58J-1400D01*
G01X1510291D01*
G03X1510256Y1090779I23J-1402D01*
G01X1506952D01*
G03X1506917Y1090780I-58J-1401D01*
G01X1506706D01*
G03X1506671Y1090779I23J-1401D01*
G01X1505178D01*
X1505160Y1090782D01*
G03X1504904Y1090806I-258J-1378D01*
G03X1504648Y1090782I2J-1402D01*
G01X1504630Y1090779D01*
X1503137D01*
G03X1503102Y1090780I-58J-1400D01*
G01X1502891D01*
G03X1502856Y1090779I23J-1402D01*
G01X1499552D01*
G03X1499517Y1090780I-58J-1401D01*
G01X1499305D01*
G03X1499270Y1090779I23J-1401D01*
G01X1497777D01*
X1497759Y1090782D01*
G03X1497503Y1090806I-258J-1378D01*
G03X1497247Y1090782I2J-1402D01*
G01X1497229Y1090779D01*
X1495736D01*
G03X1495701Y1090780I-58J-1400D01*
G01X1495491D01*
G03X1495456Y1090779I23J-1402D01*
G01X1492152D01*
G03X1492117Y1090780I-58J-1401D01*
G01X1491791D01*
G03X1491756Y1090779I23J-1402D01*
G01X1488452D01*
G03X1488417Y1090780I-58J-1401D01*
G01X1488206D01*
G03X1488171Y1090779I23J-1401D01*
G01X1486678D01*
X1486660Y1090782D01*
G03X1486404Y1090806I-258J-1378D01*
G03X1486148Y1090782I2J-1402D01*
G01X1486130Y1090779D01*
X1484637D01*
G03X1484602Y1090780I-58J-1400D01*
G01X1484391D01*
G03X1484356Y1090779I23J-1402D01*
G01X1481052D01*
G03X1481017Y1090780I-58J-1401D01*
G01X1480806D01*
G03X1480771Y1090779I23J-1401D01*
G01X1479278D01*
X1479260Y1090782D01*
G03X1479004Y1090806I-258J-1378D01*
G03X1478748Y1090782I2J-1402D01*
G01X1478730Y1090779D01*
X1477237D01*
G03X1477202Y1090780I-58J-1400D01*
G01X1476991D01*
G03X1476956Y1090779I23J-1402D01*
G01X1473652D01*
G03X1473617Y1090780I-58J-1401D01*
G01X1473405D01*
G03X1473370Y1090779I23J-1401D01*
G01X1471877D01*
X1471859Y1090782D01*
G03X1471603Y1090806I-258J-1378D01*
G03X1471347Y1090782I2J-1402D01*
G01X1471329Y1090779D01*
X1469836D01*
G03X1469801Y1090780I-58J-1400D01*
G01X1469591D01*
G03X1469556Y1090779I23J-1402D01*
G01X1466252D01*
G03X1466217Y1090780I-58J-1401D01*
G01X1465891D01*
G03X1465856Y1090779I23J-1402D01*
G01X1462552D01*
G03X1462517Y1090780I-58J-1401D01*
G01X1462306D01*
G03X1462271Y1090779I23J-1401D01*
G01X1460778D01*
X1460760Y1090782D01*
G03X1460504Y1090806I-258J-1378D01*
G03X1460248Y1090782I2J-1402D01*
G01X1460230Y1090779D01*
X1458737D01*
G03X1458702Y1090780I-58J-1400D01*
G01X1458606D01*
G03X1458571Y1090779I23J-1401D01*
G01X1457078D01*
X1457060Y1090782D01*
G03X1456804Y1090806I-258J-1378D01*
G03X1456548Y1090782I2J-1402D01*
G01X1456530Y1090779D01*
X1455037D01*
G03X1455002Y1090780I-58J-1400D01*
G01X1454906D01*
G03X1454871Y1090779I23J-1401D01*
G01X1453378D01*
X1453360Y1090782D01*
G03X1453104Y1090806I-258J-1378D01*
G03X1452848Y1090782I2J-1402D01*
G01X1452830Y1090779D01*
X1451337D01*
G03X1451302Y1090780I-58J-1400D01*
G01X1451205D01*
G03X1451170Y1090779I23J-1401D01*
G01X1449672D01*
X1449655Y1090782D01*
G03X1449403Y1090805I-253J-1379D01*
G03X1449151Y1090782I1J-1402D01*
G01X1449134Y1090779D01*
X1447636D01*
G03X1447601Y1090780I-58J-1400D01*
G01X1447505D01*
G03X1447470Y1090779I23J-1401D01*
G01X1445977D01*
X1445959Y1090782D01*
G03X1445703Y1090806I-258J-1378D01*
G03X1445447Y1090782I2J-1402D01*
G01X1445429Y1090779D01*
X1443936D01*
G03X1443901Y1090780I-58J-1400D01*
G01X1443805D01*
G03X1443770Y1090779I23J-1401D01*
G01X1442272D01*
X1442255Y1090782D01*
G03X1442003Y1090805I-253J-1379D01*
G03X1441751Y1090782I1J-1402D01*
G01X1441734Y1090779D01*
X1438572D01*
X1438555Y1090782D01*
G03X1438303Y1090805I-253J-1379D01*
G03X1438051Y1090782I1J-1402D01*
G01X1438034Y1090779D01*
X1437221D01*
X1436452Y1090010D01*
G02X1435822Y1090096I-282J283D01*
G03X1434603Y1090805I-1219J-693D01*
G03X1433201Y1089403I0J-1402D01*
G03X1433910Y1088184I1402J0D01*
G02X1433996Y1087554I-197J-348D01*
G01X1433694Y1087252D01*
X1433557Y1087349D01*
G03X1432754Y1087602I-803J-1149D01*
G01X1432753D01*
G03X1431351Y1086200I0J-1402D01*
G01Y1086199D01*
G03X1431604Y1085396I1402J0D01*
G01X1431701Y1085259D01*
X1430839Y1084397D01*
X1430768Y1084391D01*
G03X1429827Y1083895I134J-1396D01*
G01X1428277D01*
G03X1426127I-1075J-900D01*
G01X1424578D01*
G03X1423503Y1084397I-1075J-900D01*
G03X1422101Y1082995I0J-1402D01*
G01Y1082993D01*
G03X1422212Y1082447I1402J1D01*
G01X1422265Y1082323D01*
X1421717Y1081775D01*
Y1062965D01*
X1423959Y1060723D01*
X1423955Y1060634D01*
G03X1423953Y1060565I1400J-75D01*
G03X1424954Y1059222I1401J0D01*
G01X1425097Y1059179D01*
Y1058710D01*
G02X1424432Y1058411I-400J1D01*
G03X1423503Y1058763I-929J-1050D01*
G03Y1055959I0J-1402D01*
G03X1424432Y1056311I0J1402D01*
G02X1425097Y1056012I265J-300D01*
G01Y1055543D01*
X1424954Y1055501D01*
G03Y1052813I399J-1344D01*
G01X1425097Y1052771D01*
Y1052301D01*
G02X1424432Y1052002I-400J1D01*
G03X1423503Y1052354I-929J-1050D01*
G03Y1049550I0J-1402D01*
G03X1424432Y1049902I0J1402D01*
G02X1425097Y1049603I265J-300D01*
G01Y1049135D01*
X1424954Y1049093D01*
G03X1423951Y1047749I399J-1344D01*
G03X1425353Y1046347I1402J0D01*
G03X1426352Y1046765I0J1403D01*
G01Y1046766D01*
X1426494Y1046908D01*
X1426879Y1046523D01*
G02X1426731Y1045864I-283J-283D01*
G03X1425801Y1044544I472J-1320D01*
G03X1428605I1402J0D01*
G03X1428501Y1045074I-1402J0D01*
G02X1428871Y1045625I370J151D01*
G01X1429141D01*
X1429628Y1045138D01*
X1429585Y1045019D01*
G03X1429502Y1044544I1318J-475D01*
G03X1430328Y1043266I1402J0D01*
G01Y1042915D01*
G02X1429733Y1042566I-400J1D01*
G03X1429053Y1042742I-680J-1226D01*
G03Y1039938I0J-1402D01*
G03X1429759Y1040129I0J1402D01*
G02X1430361Y1039784I202J-345D01*
G01Y1039434D01*
X1430254Y1039378D01*
G03Y1036894I650J-1242D01*
G01X1430361Y1036838D01*
Y1024974D01*
X1428724Y1023337D01*
Y1016531D01*
X1430008Y1015247D01*
X1437596D01*
X1437801Y1015042D01*
Y1013987D01*
X1437656Y1013842D01*
X1431284D01*
X1430361Y1012919D01*
Y1011719D01*
X1428926Y1010284D01*
Y1005949D01*
X1429620Y1005255D01*
X1430861D01*
X1431361Y1005755D01*
X1450620D01*
X1450844Y1005531D01*
Y999991D01*
X1450561Y999707D01*
X1450219Y999365D01*
X1444696D01*
X1444319Y999742D01*
Y1000832D01*
X1444194Y1000957D01*
X1443881Y1001269D01*
X1443571Y1001579D01*
X1443566D01*
X1443446Y1001699D01*
X1438446D01*
X1437766Y1001019D01*
Y999699D01*
X1437425Y999358D01*
X1431785D01*
X1428806Y996379D01*
Y991819D01*
X1429282Y991343D01*
X1450572D01*
X1450997Y990918D01*
Y986037D01*
X1449896Y984936D01*
X1444589D01*
X1444168Y985357D01*
Y986377D01*
X1443326Y987219D01*
X1438256D01*
X1437806Y986769D01*
Y985339D01*
X1437325Y984858D01*
X1430827D01*
X1428676Y982707D01*
Y977619D01*
X1429326Y976969D01*
X1444044D01*
X1444178Y976835D01*
Y972991D01*
X1443996Y972809D01*
X1439086D01*
X1438246Y971969D01*
Y970729D01*
X1437869Y970352D01*
X1431079D01*
X1428796Y968069D01*
Y962587D01*
X1429446Y961937D01*
X1431268D01*
X1431493Y962162D01*
X1450833D01*
Y956255D01*
X1450426Y955848D01*
X1444546D01*
X1444298Y956097D01*
Y957177D01*
X1443326Y958149D01*
X1438446D01*
X1437786Y957489D01*
Y956369D01*
X1437290Y955873D01*
X1429830D01*
X1428756Y954799D01*
Y947961D01*
X1429376Y947341D01*
X1431398D01*
X1431876Y947819D01*
X1443820D01*
X1444120Y947519D01*
Y944569D01*
X1443820Y944269D01*
X1437526D01*
X1436836Y943579D01*
Y937841D01*
X1436426Y937431D01*
X1428334D01*
X1425935Y939830D01*
X1424648D01*
G02X1424298Y940423I0J400D01*
G03X1424472Y941099I-1228J677D01*
G01Y941100D01*
G03X1421668I-1402J0D01*
G01Y941099D01*
G03X1421842Y940423I1402J1D01*
G02X1421492Y939830I-350J-193D01*
G01X1405839D01*
X1405832Y939823D01*
X1404206D01*
X1403161Y940868D01*
Y944639D01*
X1405006Y946484D01*
Y950409D01*
X1404296Y951119D01*
X1397261D01*
X1396161Y950019D01*
X1387861D01*
X1387617Y950263D01*
G02X1387759Y950604I142J141D01*
G01X1388047D01*
G03X1388548Y951105I0J501D01*
G01Y955105D01*
G03X1388047Y955606I-501J0D01*
G01X1385824D01*
X1385541Y955889D01*
X1382946D01*
X1382456Y956379D01*
Y962109D01*
X1382866Y962519D01*
X1401620D01*
X1402177Y961962D01*
X1404136D01*
X1404824Y962651D01*
X1404796Y962679D01*
Y967359D01*
X1401726Y970429D01*
X1395866D01*
X1395490Y970805D01*
Y971967D01*
X1394658Y972799D01*
X1389716D01*
X1389636Y972879D01*
Y976791D01*
X1389776Y976931D01*
X1401492D01*
X1402150Y976273D01*
X1404026D01*
X1404716Y976963D01*
Y981327D01*
X1404640Y981403D01*
X1403586Y982458D01*
X1403099Y982945D01*
Y984299D01*
X1402405Y984993D01*
X1395756D01*
X1395583Y985166D01*
Y986562D01*
X1394996Y987149D01*
X1390296D01*
X1389466Y986319D01*
Y985289D01*
X1389170Y984993D01*
X1383052D01*
X1382718Y985327D01*
Y991147D01*
X1382913Y991343D01*
X1401595D01*
X1402209Y990729D01*
X1404136D01*
X1404856Y991449D01*
Y995440D01*
X1403118Y997178D01*
Y998302D01*
X1402005Y999415D01*
X1395916D01*
X1395624Y999707D01*
Y1001081D01*
X1394996Y1001709D01*
X1390326D01*
X1389456Y1000839D01*
Y999539D01*
X1389216Y999299D01*
X1385556D01*
X1385396Y999459D01*
Y1000589D01*
X1385556Y1000749D01*
X1387976D01*
X1388736Y1001509D01*
Y1005529D01*
X1388983Y1005776D01*
X1390376D01*
X1390397Y1005755D01*
X1401784D01*
X1402583Y1004956D01*
X1404046D01*
X1404976Y1005886D01*
Y1010204D01*
X1403261Y1011919D01*
Y1012819D01*
X1402319Y1013761D01*
X1396224D01*
X1395866Y1014119D01*
Y1014822D01*
X1396356Y1015312D01*
X1402080D01*
X1404776Y1018008D01*
Y1023079D01*
X1402961Y1024894D01*
Y1029719D01*
X1402011Y1030669D01*
X1394061D01*
X1393361Y1031369D01*
Y1036719D01*
X1394461Y1037819D01*
X1394612Y1037880D01*
X1396603D01*
G03X1397733Y1038587I0J1257D01*
G01X1397748Y1038617D01*
X1398708Y1039577D01*
G03X1398986Y1040018I-832J832D01*
G03X1399452Y1039938I467J1322D01*
G01X1399454D01*
G03X1400856Y1041340I0J1402D01*
G03X1400457Y1042320I-1403J0D01*
G01X1400344Y1042435D01*
X1400851Y1043210D01*
X1400987Y1043178D01*
G03X1401301Y1043142I316J1366D01*
G01X1401304D01*
G03X1402706Y1044544I0J1402D01*
G03X1402424Y1045387I-1401J0D01*
G01X1402384Y1045440D01*
Y1045717D01*
X1403222Y1046348D01*
X1403278Y1046353D01*
G03X1404555Y1047749I-125J1396D01*
G03X1403153Y1049151I-1402J0D01*
G03X1402866Y1049121I1J-1402D01*
G02X1402384Y1049512I-82J392D01*
G01Y1050058D01*
G03Y1051846I-1080J894D01*
G01Y1052394D01*
G02X1402866Y1052785I400J-1D01*
G03X1403153Y1052755I288J1372D01*
G03X1404542Y1053969I0J1402D01*
G01X1404566Y1054142D01*
X1405204D01*
X1405480Y1053866D01*
X1405494Y1053812D01*
G03X1406853Y1052755I1359J345D01*
G03X1408255Y1054157I0J1402D01*
G03X1407198Y1055516I-1402J0D01*
G01X1407144Y1055530D01*
X1406523Y1056151D01*
G03X1406391Y1056264I-829J-835D01*
G02X1406269Y1056758I239J321D01*
G03X1406405Y1057360I-1266J602D01*
G01Y1057361D01*
G03X1405003Y1058763I-1402J0D01*
G03X1404688Y1058727I1J-1402D01*
G02X1404212Y1059013I-90J390D01*
G03X1404088Y1059305I-1135J-310D01*
G02X1404122Y1059552I172J102D01*
G03X1404555Y1060565I-968J1013D01*
G03X1403153Y1061967I-1402J0D01*
G03X1402602Y1061854I0J-1402D01*
G03X1402410Y1062249I-3150J-1287D01*
G01X1402384Y1062295D01*
Y1062876D01*
G03Y1064664I-1080J894D01*
G01Y1065211D01*
G02X1402866Y1065602I400J-1D01*
G03X1403153Y1065572I288J1372D01*
G03Y1068376I0J1402D01*
G03X1402866Y1068346I1J-1402D01*
G02X1402384Y1068737I-82J392D01*
G01Y1069284D01*
G03Y1071072I-1080J894D01*
G01Y1071653D01*
X1402410Y1071699D01*
G03X1402602Y1072094I-2958J1682D01*
G03X1403153Y1071981I551J1289D01*
G03Y1074785I0J1402D01*
G03X1402602Y1074672I0J-1402D01*
G03X1402410Y1075066I-3148J-1290D01*
G01X1402384Y1075112D01*
Y1075693D01*
G03X1402706Y1076587I-1080J894D01*
G03X1402194Y1077670I-1401J0D01*
G01X1402187Y1077676D01*
X1400709Y1079154D01*
X1400757Y1079276D01*
G03X1400855Y1079791I-1304J515D01*
G03X1399453Y1081193I-1402J0D01*
G03X1398902Y1081080I0J-1402D01*
G03X1398444Y1081873I-3149J-1290D01*
G03X1399006Y1082995I-839J1122D01*
G03X1397604Y1084397I-1402J0D01*
G03X1396549Y1083918I0J-1401D01*
G02X1395965Y1083898I-301J263D01*
G01X1395635Y1084228D01*
G02X1395879Y1084909I283J283D01*
G03X1396792Y1085422I-125J1292D01*
G01X1398414D01*
G03X1399453Y1084902I1039J778D01*
G03Y1087498I0J1298D01*
G03X1398414Y1086978I0J-1298D01*
G01X1396792D01*
G03X1395753Y1087498I-1039J-778D01*
G03X1394462Y1086326I0J-1297D01*
G02X1393781Y1086082I-398J39D01*
G01X1393439Y1086424D01*
X1393427Y1086482D01*
G03X1392336Y1087573I-1373J-282D01*
G01X1392278Y1087585D01*
X1391247Y1088616D01*
X1391324Y1088750D01*
G03X1391502Y1089404I-1119J656D01*
G03X1390248Y1090701I-1298J0D01*
G02X1389861Y1091100I13J400D01*
G01Y1094012D01*
G02X1390248Y1094412I400J0D01*
G03Y1097214I-45J1401D01*
G02X1389861Y1097614I13J400D01*
G01Y1100525D01*
G02X1390248Y1100924I400J-1D01*
G37*
G36*
G01X1527329Y1371413D02*
X1526782Y1371960D01*
G03X1526640Y1372019I-142J-141D01*
G01X1502745D01*
G03X1502603Y1371960I0J-200D01*
G01X1502109Y1371466D01*
G03X1502050Y1371324I141J-142D01*
G01Y1370379D01*
X1502021Y1370328D01*
Y1354874D01*
G03X1501585Y1353316I2566J-1558D01*
G03X1502015Y1351768I3004J1D01*
G01X1502031Y1351740D01*
X1502050Y1351657D01*
Y1333105D01*
X1502048Y1333104D01*
Y1332637D01*
X1502050Y1332635D01*
Y1328501D01*
X1501992Y1328358D01*
X1501759Y1328125D01*
X1487983D01*
X1487836Y1328272D01*
Y1339847D01*
X1487877Y1339968D01*
X1487896Y1339993D01*
G03X1488128Y1340359I-2413J1786D01*
G02X1488241Y1340454I176J-95D01*
G03X1490123Y1341794I-1281J3791D01*
G02X1490282Y1341871I158J-123D01*
G01X1492468D01*
G03X1492610Y1341930I0J200D01*
G01X1495204Y1344524D01*
G03X1495263Y1344666I-141J142D01*
G01Y1350229D01*
G03X1495204Y1350371I-200J0D01*
G01X1494081Y1351494D01*
G03X1493939Y1351553I-142J-141D01*
G01X1474571D01*
G03X1474429Y1351494I0J-200D01*
G01X1469981Y1347046D01*
G03X1469922Y1346904I141J-142D01*
G01Y1346865D01*
X1469893Y1346762D01*
Y1332051D01*
G03X1469457Y1330493I2566J-1558D01*
G03X1469887Y1328945I3004J1D01*
G01X1469903Y1328917D01*
X1469922Y1328834D01*
Y1319679D01*
X1469920Y1319678D01*
Y1319211D01*
X1469922Y1319209D01*
Y1315075D01*
X1469864Y1314932D01*
X1469631Y1314699D01*
X1455855D01*
X1455708Y1314846D01*
Y1326421D01*
X1455749Y1326542D01*
X1455768Y1326567D01*
G03X1456000Y1326933I-2413J1786D01*
G02X1456113Y1327028I176J-95D01*
G03X1457842Y1328182I-1281J3791D01*
G01X1462380D01*
X1463386Y1329188D01*
Y1331433D01*
G03X1463388Y1331462I-198J28D01*
G01Y1336918D01*
G03X1463329Y1337060I-200J0D01*
G01X1463262Y1337127D01*
X1462194Y1338194D01*
G03X1462052Y1338253I-142J-141D01*
G01X1441263D01*
G03X1441121Y1338194I0J-200D01*
G01X1438050Y1335123D01*
Y1321544D01*
G03X1437602Y1318342I2282J-1952D01*
G03X1437329Y1317092I2730J-1251D01*
G01Y1317091D01*
G03X1437933Y1315285I3003J0D01*
G01X1438037Y1315146D01*
X1437590Y1314699D01*
X1423727D01*
X1423580Y1314846D01*
Y1326319D01*
X1424485Y1327224D01*
X1424535Y1327260D01*
X1424548Y1327267D01*
G03X1426264Y1328989I-1843J3553D01*
G01X1426278Y1329017D01*
X1426451Y1329190D01*
X1430968D01*
G03X1431110Y1329249I0J200D01*
G01X1431929Y1330068D01*
G03X1431988Y1330210I-141J142D01*
G01Y1336950D01*
G03X1431929Y1337092I-200J0D01*
G01X1431087Y1337934D01*
G03X1430945Y1337993I-142J-141D01*
G01X1407271D01*
G03X1407129Y1337934I0J-200D01*
G01X1405677Y1336482D01*
G03X1405618Y1336340I141J-142D01*
G01Y1333911D01*
X1405637Y1333892D01*
Y1321150D01*
G03X1405201Y1319592I2566J-1558D01*
G03X1405474Y1318342I3003J1D01*
G03X1405201Y1317092I2729J-1251D01*
G03X1405631Y1315544I3004J1D01*
G01X1405647Y1315516D01*
X1405666Y1315433D01*
Y1315075D01*
X1405608Y1314932D01*
X1405375Y1314699D01*
X1391599D01*
X1391452Y1314846D01*
Y1326174D01*
X1392698Y1327420D01*
X1392714Y1327437D01*
X1392734Y1327449D01*
G03X1393949Y1328664I-2156J3371D01*
G01X1393960Y1328682D01*
X1394331Y1329053D01*
X1399051D01*
G03X1399193Y1329112I0J200D01*
G01X1400175Y1330094D01*
G03X1400234Y1330236I-141J142D01*
G01Y1336973D01*
G03X1400175Y1337115I-200J0D01*
G01X1399733Y1337557D01*
X1399688D01*
X1399251Y1337994D01*
G03X1399109Y1338053I-142J-141D01*
G01X1375971D01*
G03X1375829Y1337994I0J-200D01*
G01X1374024Y1336188D01*
X1373654Y1335818D01*
Y1318867D01*
G03X1373595Y1315400I2421J-1775D01*
G01X1373689Y1315263D01*
X1373564Y1315139D01*
X1373480Y1314932D01*
X1373247Y1314699D01*
X1359471D01*
X1359324Y1314846D01*
Y1326421D01*
X1359365Y1326542D01*
X1359384Y1326567D01*
G03X1359616Y1326933I-2413J1786D01*
G02X1359729Y1327028I176J-95D01*
G03X1362027Y1329026I-1280J3792D01*
G01X1362052Y1329076D01*
X1362231Y1329189D01*
X1367141D01*
G03X1367283Y1329248I0J200D01*
G01X1367835Y1329800D01*
G03X1367894Y1329942I-141J142D01*
G01Y1335370D01*
G03X1367835Y1335512I-200J0D01*
G01X1367100Y1336247D01*
G03X1366958Y1336306I-142J-141D01*
G01X1349828D01*
X1348307Y1337827D01*
G03X1348165Y1337886I-142J-141D01*
G01X1345866D01*
G03X1345724Y1337827I0J-200D01*
G01X1342896Y1334999D01*
X1342804Y1334947D01*
X1342779Y1334941D01*
G03X1341440Y1334444I1754J-6779D01*
G01Y1332272D01*
X1341490Y1332222D01*
Y1328732D01*
X1340883Y1328125D01*
X1327343D01*
X1327196Y1328272D01*
Y1339923D01*
X1327800Y1340527D01*
G03X1329899Y1342452I-1479J3719D01*
G01X1329924Y1342502D01*
X1330103Y1342615D01*
X1334588D01*
G03X1334664Y1342630I0J200D01*
G01X1335100Y1342812D01*
G03X1335165Y1342855I-76J185D01*
G01X1335572Y1343262D01*
G03X1335615Y1343327I-142J141D01*
G01X1335797Y1343763D01*
G03X1335812Y1343839I-185J76D01*
G01Y1349346D01*
G03X1335753Y1349488I-200J0D01*
G01X1334147Y1351094D01*
G03X1334005Y1351153I-142J-141D01*
G01X1316912D01*
X1315792Y1352273D01*
G03X1315650Y1352332I-142J-141D01*
G01X1314066D01*
G03X1313924Y1352273I0J-200D01*
G01X1312804Y1351153D01*
X1295668D01*
X1295068Y1351753D01*
Y1362393D01*
X1296903Y1364228D01*
X1296915Y1364239D01*
X1296917Y1364241D01*
G03X1297358Y1364683I-2604J3039D01*
G01X1298088Y1365413D01*
X1302460D01*
G03X1302527Y1365425I-1J200D01*
G01X1302559Y1365436D01*
X1303288D01*
G03X1303430Y1365495I0J200D01*
G01X1303729Y1365794D01*
G03X1303788Y1365936I-141J142D01*
G01Y1374228D01*
X1303939Y1374422D01*
X1304005Y1374439D01*
G03X1319974Y1391235I-5358J21083D01*
G01X1319988Y1391305D01*
X1320184Y1391466D01*
X1354576D01*
X1373938Y1372104D01*
G03X1374080Y1372045I142J141D01*
G01X1399064D01*
G03X1399206Y1372104I0J200D01*
G01X1400240Y1373138D01*
X1419376D01*
X1421376D01*
X1425476D01*
X1429700Y1377362D01*
Y1383462D01*
X1431500Y1385262D01*
X1459400D01*
X1466200Y1378462D01*
X1532838D01*
X1535286Y1376014D01*
Y1352188D01*
X1534396Y1351298D01*
X1534311D01*
G03X1534131Y1351184I1J-200D01*
G01X1534116Y1351152D01*
X1533887Y1350923D01*
X1520111D01*
X1519964Y1351070D01*
Y1362645D01*
X1520005Y1362766D01*
X1520024Y1362791D01*
G03X1520256Y1363157I-2413J1786D01*
G02X1520369Y1363252I176J-95D01*
G03X1522638Y1365195I-1280J3792D01*
G01X1522664Y1365243D01*
X1522841Y1365353D01*
X1526168D01*
G03X1526310Y1365412I0J200D01*
G01X1527329Y1366431D01*
G03X1527388Y1366573I-141J142D01*
G01Y1371271D01*
G03X1527329Y1371413I-200J0D01*
G37*
G36*
G01X1292307Y1373655D02*
X1301547D01*
X1302544Y1372658D01*
Y1367009D01*
X1302369Y1366834D01*
X1296213D01*
G02X1295814Y1367243I1J400D01*
G01Y1367279D01*
G03X1292810I-1502J0D01*
G01Y1367243D01*
G02X1292411Y1366834I-400J-9D01*
G01X1292311D01*
X1291942Y1367203D01*
Y1373290D01*
X1292307Y1373655D01*
G37*
G36*
G01X1287366Y1578182D02*
G03I-574J0D01*
G37*
G36*
G01X1291626D02*
G03I-574J0D01*
G37*
G36*
G01X1287366Y1590094D02*
G03I-574J0D01*
G37*
G36*
G01X1291626D02*
G03I-574J0D01*
G37*
G36*
G01X1284866Y1602380D02*
G03I-574J0D01*
G37*
G36*
G01Y1614292D02*
G03I-574J0D01*
G37*
G36*
G01X1292666D02*
G03I-574J0D01*
G37*
G36*
G01Y1602380D02*
G03I-574J0D01*
G37*
G36*
G01X1296926D02*
G03I-574J0D01*
G37*
G36*
G01Y1614292D02*
G03I-574J0D01*
G37*
G36*
G01X1301011Y95302D02*
G03I-557J0D01*
G37*
G36*
G01X1311397Y193666D02*
X1314011D01*
X1314197Y193480D01*
Y190527D01*
G02X1313626Y190166I-400J0D01*
G03X1313025Y190301I-600J-1267D01*
G03Y187497I0J-1402D01*
G03X1314027Y187919I-1J1402D01*
G01X1314028Y187920D01*
X1314170Y188062D01*
X1314737Y187495D01*
X1316669D01*
X1317115Y187049D01*
Y186229D01*
X1317113Y186215D01*
G03X1317100Y186024I1389J-190D01*
G03X1317113Y185833I1402J-1D01*
G01X1317115Y185819D01*
Y183079D01*
X1317113Y183065D01*
G03X1317100Y182874I1389J-190D01*
G03X1317113Y182683I1402J-1D01*
G01X1317115Y182669D01*
Y176779D01*
X1317113Y176765D01*
G03X1317100Y176574I1389J-190D01*
G03X1317113Y176383I1402J-1D01*
G01X1317115Y176369D01*
Y175732D01*
X1317766Y175081D01*
X1319995D01*
X1320497Y174579D01*
Y173679D01*
X1319764Y172946D01*
X1317453D01*
G03X1316298Y173650I-1217J-697D01*
G01X1316221Y173653D01*
X1314107Y175766D01*
X1314132D01*
Y178266D01*
X1313974D01*
Y178575D01*
X1310605Y181944D01*
X1310667Y182073D01*
G03X1310851Y182865I-1618J793D01*
G03X1310293Y184169I-1803J0D01*
G01Y185724D01*
X1310409Y185778D01*
G03Y188320I-592J1271D01*
G01X1310293Y188374D01*
Y189424D01*
X1310409Y189478D01*
G03Y192020I-592J1271D01*
G01X1310293Y192074D01*
Y192562D01*
X1311397Y193666D01*
G37*
G36*
G01X1316954Y203002D02*
Y197312D01*
X1316693Y197051D01*
Y195306D01*
X1316149Y194762D01*
X1313544D01*
X1312114Y196192D01*
Y201184D01*
X1313124Y202194D01*
X1314020D01*
X1315042Y203216D01*
X1316740D01*
X1316954Y203002D01*
G37*
G36*
G01X1306368Y228939D02*
X1326305D01*
X1327838Y227406D01*
X1327850Y227345D01*
G03X1328613Y226188I1770J337D01*
G01Y225384D01*
X1328494Y225331D01*
G03Y222767I567J-1282D01*
G01X1328613Y222714D01*
Y221684D01*
X1328494Y221631D01*
G03Y219067I568J-1282D01*
G01X1328613Y219014D01*
Y217984D01*
X1328494Y217931D01*
G03Y215367I568J-1282D01*
G01X1328613Y215314D01*
Y214284D01*
X1328494Y214231D01*
G03Y211667I568J-1282D01*
G01X1328613Y211614D01*
Y210584D01*
X1328494Y210531D01*
G03Y207967I568J-1282D01*
G01X1328613Y207914D01*
Y207523D01*
X1328918Y207218D01*
Y204490D01*
X1328500Y204072D01*
X1321072D01*
X1320182Y203182D01*
Y197845D01*
X1319293Y196956D01*
X1318260D01*
X1317956Y197260D01*
Y203417D01*
X1317914Y203458D01*
Y203672D01*
X1317386Y204200D01*
X1317172D01*
X1317155Y204218D01*
X1314627D01*
X1314610Y204200D01*
X1314342D01*
X1314288Y204312D01*
G03X1313027Y205101I-1261J-613D01*
G03X1312775Y205078I1J-1402D01*
G01X1312672Y205059D01*
X1310905Y206826D01*
X1310890Y206869D01*
G03X1310529Y207479I-1701J-595D01*
G02X1310606Y208080I297J267D01*
G03X1311234Y209249I-774J1169D01*
G03X1309832Y210651I-1402J0D01*
G03X1308491Y209657I0J-1402D01*
G01X1308476Y209609D01*
X1308299Y209432D01*
X1307876Y209855D01*
X1307912Y209970D01*
G03X1307992Y210502I-1722J531D01*
G03X1307054Y212083I-1801J0D01*
G01Y213457D01*
X1307176Y213509D01*
G03X1308029Y214799I-549J1290D01*
G03X1306826Y216187I-1402J0D01*
G01X1306760Y216196D01*
X1306193Y216763D01*
Y217113D01*
X1306407D01*
X1306422Y217111D01*
G03X1306622Y217097I198J1388D01*
G03Y219901I0J1402D01*
G01X1306599D01*
G02X1306193Y220301I-6J400D01*
G01Y220397D01*
G02X1306599Y220797I400J0D01*
G01X1306622D01*
G03Y223601I0J1402D01*
G01X1306599D01*
G02X1306193Y224001I-6J400D01*
G01Y228764D01*
X1306368Y228939D01*
G37*
G36*
G01X1327808Y262170D02*
X1327225Y260763D01*
G02X1326659Y260568I-369J153D01*
G03X1325769Y260803I-890J-1568D01*
G03Y257199I0J-1802D01*
G03X1325996Y257213I3J1802D01*
G01X1326009Y257215D01*
X1326222D01*
Y256830D01*
X1325324Y255932D01*
X1316154D01*
X1312902Y259184D01*
Y278718D01*
X1313191Y279007D01*
X1325956D01*
X1326632Y278727D01*
X1326980Y278379D01*
X1327808Y276379D01*
Y265536D01*
G03Y262988I585J-1274D01*
G01Y262170D01*
G37*
G36*
G01X1303667Y785837D02*
G03I-650J0D01*
G37*
G36*
G01X1324466Y987119D02*
X1360376D01*
X1364459Y983036D01*
X1364445Y982937D01*
G03X1364432Y982756I1275J-183D01*
G03X1365215Y981572I1287J0D01*
G01X1365336Y981520D01*
Y980861D01*
G02X1364684Y980551I-400J0D01*
G03X1363871Y980840I-813J-999D01*
G03Y978264I0J-1288D01*
G03X1364684Y978553I0J1288D01*
G02X1365336Y978243I252J-310D01*
G01Y977583D01*
X1365215Y977531D01*
G03Y975163I507J-1184D01*
G01X1365336Y975111D01*
Y971175D01*
X1365215Y971123D01*
G03Y968755I504J-1184D01*
G01X1365336Y968703D01*
Y968044D01*
G02X1364684Y967734I-400J0D01*
G03X1363871Y968022I-812J-1000D01*
G03Y965448I0J-1287D01*
G03X1364684Y965736I1J1288D01*
G02X1365336Y965426I252J-310D01*
G01Y964766D01*
X1365215Y964714D01*
G03Y962346I504J-1184D01*
G01X1365336Y962294D01*
Y961635D01*
G02X1364684Y961325I-400J0D01*
G03X1363871Y961614I-813J-999D01*
G03Y959038I0J-1288D01*
G03X1364684Y959327I0J1288D01*
G02X1365336Y959017I252J-310D01*
G01Y958358D01*
X1365215Y958306D01*
G03Y955938I504J-1184D01*
G01X1365336Y955886D01*
Y951949D01*
X1365215Y951897D01*
G03Y949529I504J-1184D01*
G01X1365336Y949477D01*
Y948818D01*
G02X1364684Y948508I-400J0D01*
G03X1363871Y948796I-812J-1000D01*
G03Y946222I0J-1287D01*
G03X1364684Y946510I1J1288D01*
G02X1365336Y946200I252J-310D01*
G01Y945540D01*
X1365215Y945488D01*
G03Y943120I504J-1184D01*
G01X1365336Y943068D01*
Y942409D01*
G02X1364684Y942099I-400J0D01*
G03X1363871Y942388I-813J-999D01*
G03X1362584Y941100I0J-1287D01*
G03X1362773Y940428I1287J-1D01*
G02X1362432Y939819I-341J-209D01*
G01X1357910D01*
G02X1357569Y940428I0J400D01*
G03X1357758Y941100I-1098J671D01*
G03X1355184I-1287J0D01*
G03X1355373Y940428I1287J-1D01*
G02X1355032Y939819I-341J-209D01*
G01X1354210D01*
G02X1353869Y940428I0J400D01*
G03X1354058Y941100I-1098J671D01*
G03X1351484I-1287J0D01*
G03X1351673Y940428I1287J-1D01*
G02X1351332Y939819I-341J-209D01*
G01X1346810D01*
G02X1346469Y940428I0J400D01*
G03X1346658Y941100I-1098J671D01*
G03X1344084I-1287J0D01*
G03X1344273Y940428I1287J-1D01*
G02X1343932Y939819I-341J-209D01*
G01X1339410D01*
G02X1339069Y940428I0J400D01*
G03X1339258Y941100I-1098J671D01*
G03X1336684I-1287J0D01*
G03X1336873Y940428I1287J-1D01*
G02X1336532Y939819I-341J-209D01*
G01X1332010D01*
G02X1331669Y940428I0J400D01*
G03X1331858Y941100I-1098J671D01*
G03X1329284I-1287J0D01*
G03X1329473Y940428I1287J-1D01*
G02X1329132Y939819I-341J-209D01*
G01X1328310D01*
G02X1327969Y940428I0J400D01*
G03X1328158Y941100I-1098J671D01*
G03X1325584I-1287J0D01*
G03X1325773Y940428I1287J-1D01*
G02X1325432Y939819I-341J-209D01*
G01X1320666D01*
X1313506Y946979D01*
X1306486D01*
X1303546Y949919D01*
Y969936D01*
X1308609Y974999D01*
X1313276D01*
X1324466Y986189D01*
Y987119D01*
G37*
G36*
G01X1371513Y1138229D02*
X1371895D01*
G02X1372286Y1137744I0J-400D01*
G03X1372256Y1137469I1268J-277D01*
G03X1374852I1298J0D01*
G03X1374841Y1137637I-1298J-1D01*
G01X1374828Y1137735D01*
X1375039Y1137946D01*
X1375366Y1137619D01*
Y1135577D01*
X1375198Y1135550D01*
G03Y1132978I206J-1286D01*
G01X1375366Y1132951D01*
Y1129164D01*
X1375198Y1129137D01*
G03X1374106Y1127856I205J-1281D01*
G03X1374179Y1127428I1298J1D01*
G01X1374210Y1127341D01*
X1373403Y1125943D01*
X1373312Y1125926D01*
G03X1372256Y1124651I242J-1275D01*
G03X1373553Y1123354I1297J0D01*
G03X1373694Y1123361I6J1297D01*
G01X1373705Y1123362D01*
X1373916D01*
Y1123038D01*
X1373858Y1122979D01*
G03X1373412Y1122325I1545J-1533D01*
G02X1372730Y1122241I-366J161D01*
G03X1371944Y1122722I-1026J-794D01*
G01X1371854Y1122739D01*
X1371047Y1124136D01*
X1371078Y1124223D01*
G03X1371150Y1124651I-1225J426D01*
G03X1368556I-1297J0D01*
G03X1369611Y1123376I1298J0D01*
G01X1369701Y1123359D01*
X1370509Y1121960D01*
X1370479Y1121874D01*
G03X1370406Y1121447I1225J-429D01*
G03X1371704Y1120150I1297J0D01*
G03X1372730Y1120653I0J1298D01*
G02X1373412Y1120569I316J-245D01*
G03X1373591Y1120242I1992J878D01*
G02X1373324Y1119626I-333J-222D01*
G03X1372151Y1118243I229J-1383D01*
G03X1373553Y1116841I1402J0D01*
G03X1374315Y1117066I0J1403D01*
G01X1374451Y1117154D01*
X1374822Y1116783D01*
G02X1374743Y1116156I-283J-283D01*
G03X1374106Y1115039I661J-1117D01*
G03X1375404Y1113742I1297J0D01*
G03X1376443Y1114262I0J1298D01*
G01X1378065D01*
G03X1379104Y1113742I1039J778D01*
G03X1380402Y1115039I0J1298D01*
G03X1380400Y1115093I-1297J-21D01*
G02X1380800Y1115509I400J16D01*
G01X1381002D01*
G02X1381402Y1115093I0J-400D01*
G03X1381401Y1115039I1401J-53D01*
G03X1382803Y1113637I1402J0D01*
G03X1383759Y1114013I0J1403D01*
G01X1383900Y1114145D01*
X1384339Y1113706D01*
G02X1384197Y1113049I-283J-283D01*
G03X1383356Y1111834I457J-1215D01*
G03X1384543Y1110541I1298J0D01*
G02X1384726Y1110342I-17J-199D01*
G01Y1107104D01*
X1384503Y1106718D01*
X1384413Y1106701D01*
G03X1383356Y1105426I240J-1275D01*
G03X1384543Y1104133I1298J0D01*
G02X1384726Y1103934I-17J-199D01*
G01Y1100509D01*
G02X1384543Y1100310I-200J0D01*
G03X1383614Y1099794I110J-1293D01*
G01X1381992D01*
G03X1380953Y1100314I-1039J-778D01*
G03Y1097720I0J-1297D01*
G03X1381992Y1098240I0J1298D01*
G01X1383614D01*
G03X1384543Y1097724I1039J777D01*
G02X1384726Y1097525I-17J-199D01*
G01Y1094100D01*
G02X1384543Y1093901I-200J0D01*
G03X1383356Y1092608I111J-1293D01*
G03X1383428Y1092180I1297J-2D01*
G01X1383459Y1092093D01*
X1382652Y1090696D01*
X1382562Y1090679D01*
G03X1381506Y1089404I242J-1275D01*
G03X1382662Y1088114I1298J0D01*
G02X1382901Y1087434I-44J-397D01*
G01X1382508Y1087041D01*
G02X1381925Y1087059I-283J283D01*
G03X1381194Y1087475I-973J-859D01*
G01X1381104Y1087492D01*
X1380297Y1088889D01*
X1380328Y1088976D01*
G03X1380400Y1089404I-1225J426D01*
G03X1377806I-1297J0D01*
G03X1378861Y1088129I1298J0D01*
G01X1378951Y1088112D01*
X1379758Y1086714D01*
X1379728Y1086628D01*
G03X1379697Y1086526I1225J-428D01*
G02X1379481Y1086378I-193J51D01*
G03X1378645Y1086367I-374J-3383D01*
G03X1375861I-1392J-167D01*
G03X1374946I-458J-3372D01*
G03X1372162I-1392J-167D01*
G03X1371315Y1086376I-459J-3372D01*
G02X1371099Y1086524I-23J199D01*
G03X1369853Y1087488I-1246J-323D01*
G03X1368607Y1086525I0J-1288D01*
G02X1368391Y1086376I-194J50D01*
G01X1367615D01*
G02X1367399Y1086524I-23J199D01*
G03X1364907I-1246J-323D01*
G02X1364691Y1086376I-193J51D01*
G03X1364303Y1086398I-386J-3381D01*
G03X1363845Y1086367I0J-3403D01*
G03X1362453Y1087602I-1392J-167D01*
G03X1361061Y1086368I0J-1402D01*
G03X1360215Y1086376I-455J-3373D01*
G02X1359999Y1086524I-23J199D01*
G03X1358753Y1087488I-1246J-323D01*
G03X1357507Y1086525I0J-1288D01*
G02X1357291Y1086376I-194J50D01*
G03X1356445Y1086367I-387J-3381D01*
G03X1355053Y1087602I-1392J-167D01*
G03X1353661Y1086368I0J-1402D01*
G03X1352815Y1086376I-455J-3373D01*
G02X1352599Y1086524I-23J199D01*
G03X1350107I-1246J-323D01*
G02X1349891Y1086376I-193J51D01*
G03X1349046Y1086367I-387J-3381D01*
G03X1346262I-1392J-167D01*
G03X1345415Y1086376I-459J-3372D01*
G02X1345199Y1086524I-23J199D01*
G03X1343953Y1087488I-1246J-323D01*
G03X1342707Y1086525I0J-1288D01*
G02X1342491Y1086376I-194J50D01*
G01X1341715D01*
G02X1341499Y1086524I-23J199D01*
G03X1339007I-1246J-323D01*
G02X1338791Y1086376I-193J51D01*
G03X1338403Y1086398I-386J-3381D01*
G03X1337945Y1086367I0J-3403D01*
G03X1336553Y1087602I-1392J-167D01*
G03X1335161Y1086368I0J-1402D01*
G03X1334315Y1086376I-455J-3373D01*
G02X1334099Y1086524I-23J199D01*
G03X1331607I-1246J-323D01*
G02X1331391Y1086376I-193J51D01*
G03X1331003Y1086398I-386J-3381D01*
G03X1330545Y1086367I0J-3403D01*
G03X1327761I-1392J-167D01*
G03X1327303Y1086398I-458J-3372D01*
G03X1326915Y1086376I-2J-3403D01*
G02X1326699Y1086524I-23J199D01*
G03X1325453Y1087488I-1246J-323D01*
G03X1324207Y1086525I0J-1288D01*
G02X1323991Y1086376I-194J50D01*
G03X1323144Y1086367I-388J-3381D01*
G03X1321752Y1087602I-1392J-167D01*
G03X1320816Y1087244I0J-1403D01*
G02X1320267Y1087259I-267J298D01*
G01X1315246Y1092280D01*
G03X1314414Y1092624I-831J-832D01*
G01X1312941D01*
X1306706Y1098859D01*
Y1133489D01*
X1311446Y1138229D01*
X1319986D01*
G02X1320378Y1137749I0J-400D01*
G03X1320350Y1137469I1374J-279D01*
G03X1323154I1402J0D01*
G03X1323126Y1137749I-1402J1D01*
G02X1323518Y1138229I392J80D01*
G01X1323795D01*
G02X1324186Y1137744I0J-400D01*
G03X1324156Y1137469I1268J-277D01*
G03X1325212Y1136194I1298J0D01*
G01X1325302Y1136177D01*
X1326109Y1134779D01*
X1326078Y1134693D01*
G03X1326006Y1134264I1225J-426D01*
G03X1328600I1297J0D01*
G03X1327545Y1135539I-1298J0D01*
G01X1327455Y1135556D01*
X1326648Y1136954D01*
X1326679Y1137040D01*
G03X1326752Y1137469I-1224J429D01*
G03X1326722Y1137744I-1298J-2D01*
G02X1327113Y1138229I391J85D01*
G01X1327386D01*
G02X1327778Y1137749I0J-400D01*
G03X1327750Y1137469I1374J-279D01*
G03X1330554I1402J0D01*
G03X1330526Y1137749I-1402J1D01*
G02X1330918Y1138229I392J80D01*
G01X1331195D01*
G02X1331586Y1137744I0J-400D01*
G03X1331556Y1137469I1268J-277D01*
G03X1332612Y1136194I1298J0D01*
G01X1332702Y1136177D01*
X1333509Y1134779D01*
X1333478Y1134693D01*
G03X1333406Y1134264I1225J-426D01*
G03X1336000I1297J0D01*
G03X1334945Y1135539I-1298J0D01*
G01X1334855Y1135556D01*
X1334048Y1136954D01*
X1334079Y1137040D01*
G03X1334152Y1137469I-1224J429D01*
G03X1334122Y1137744I-1298J-2D01*
G02X1334513Y1138229I391J85D01*
G01X1334895D01*
G02X1335286Y1137744I0J-400D01*
G03X1335256Y1137469I1268J-277D01*
G03X1337852I1298J0D01*
G03X1337822Y1137744I-1298J-2D01*
G02X1338213Y1138229I391J85D01*
G01X1338595D01*
G02X1338986Y1137744I0J-400D01*
G03X1338956Y1137469I1268J-277D01*
G03X1340012Y1136194I1298J0D01*
G01X1340102Y1136177D01*
X1340910Y1134779D01*
X1340879Y1134692D01*
G03X1340806Y1134264I1225J-429D01*
G03X1343402I1298J0D01*
G03X1342346Y1135539I-1298J0D01*
G01X1342256Y1135556D01*
X1341448Y1136954D01*
X1341479Y1137041D01*
G03X1341552Y1137469I-1225J429D01*
G03X1341522Y1137744I-1298J-2D01*
G02X1341913Y1138229I391J85D01*
G01X1342295D01*
G02X1342686Y1137744I0J-400D01*
G03X1342656Y1137469I1268J-277D01*
G03X1345252I1298J0D01*
G03X1345222Y1137744I-1298J-2D01*
G02X1345613Y1138229I391J85D01*
G01X1345995D01*
G02X1346386Y1137744I0J-400D01*
G03X1346356Y1137469I1268J-277D01*
G03X1347412Y1136194I1298J0D01*
G01X1347502Y1136177D01*
X1348310Y1134779D01*
X1348279Y1134692D01*
G03X1348206Y1134264I1225J-429D01*
G03X1350802I1298J0D01*
G03X1349746Y1135539I-1298J0D01*
G01X1349656Y1135556D01*
X1348848Y1136954D01*
X1348879Y1137041D01*
G03X1348952Y1137469I-1225J429D01*
G03X1348922Y1137744I-1298J-2D01*
G02X1349313Y1138229I391J85D01*
G01X1349695D01*
G02X1350086Y1137744I0J-400D01*
G03X1350056Y1137469I1268J-277D01*
G03X1352652I1298J0D01*
G03X1352622Y1137744I-1298J-2D01*
G02X1353013Y1138229I391J85D01*
G01X1353395D01*
G02X1353786Y1137744I0J-400D01*
G03X1353756Y1137469I1268J-277D01*
G03X1354812Y1136194I1298J0D01*
G01X1354902Y1136177D01*
X1355710Y1134779D01*
X1355679Y1134692D01*
G03X1355606Y1134264I1225J-429D01*
G03X1358202I1298J0D01*
G03X1357146Y1135539I-1298J0D01*
G01X1357056Y1135556D01*
X1356248Y1136954D01*
X1356279Y1137041D01*
G03X1356352Y1137469I-1225J429D01*
G03X1356322Y1137744I-1298J-2D01*
G02X1356713Y1138229I391J85D01*
G01X1357095D01*
G02X1357486Y1137744I0J-400D01*
G03X1357456Y1137469I1268J-277D01*
G03X1360052I1298J0D01*
G03X1360022Y1137744I-1298J-2D01*
G02X1360413Y1138229I391J85D01*
G01X1360795D01*
G02X1361186Y1137744I0J-400D01*
G03X1361156Y1137469I1268J-277D01*
G03X1362212Y1136194I1298J0D01*
G01X1362302Y1136177D01*
X1363110Y1134779D01*
X1363079Y1134692D01*
G03X1363006Y1134264I1225J-429D01*
G03X1365602I1298J0D01*
G03X1364546Y1135539I-1298J0D01*
G01X1364456Y1135556D01*
X1363648Y1136954D01*
X1363679Y1137041D01*
G03X1363752Y1137469I-1225J429D01*
G03X1363722Y1137744I-1298J-2D01*
G02X1364113Y1138229I391J85D01*
G01X1364495D01*
G02X1364886Y1137744I0J-400D01*
G03X1364856Y1137469I1268J-277D01*
G03X1367452I1298J0D01*
G03X1367422Y1137744I-1298J-2D01*
G02X1367813Y1138229I391J85D01*
G01X1368195D01*
G02X1368586Y1137744I0J-400D01*
G03X1368556Y1137469I1268J-277D01*
G03X1369612Y1136194I1298J0D01*
G01X1369702Y1136177D01*
X1370510Y1134779D01*
X1370479Y1134692D01*
G03X1370406Y1134264I1225J-429D01*
G03X1373002I1298J0D01*
G03X1371946Y1135539I-1298J0D01*
G01X1371856Y1135556D01*
X1371048Y1136954D01*
X1371079Y1137041D01*
G03X1371152Y1137469I-1225J429D01*
G03X1371122Y1137744I-1298J-2D01*
G02X1371513Y1138229I391J85D01*
G37*
G36*
G01X1299426Y1578182D02*
G03I-574J0D01*
G37*
G36*
G01X1303686D02*
G03I-574J0D01*
G37*
G36*
G01X1311486D02*
G03I-574J0D01*
G37*
G36*
G01X1299426Y1590094D02*
G03I-574J0D01*
G37*
G36*
G01X1303686D02*
G03I-574J0D01*
G37*
G36*
G01X1311486D02*
G03I-574J0D01*
G37*
G36*
G01X1304726Y1602380D02*
G03I-574J0D01*
G37*
G36*
G01Y1614292D02*
G03I-574J0D01*
G37*
G36*
G01X1308986Y1602380D02*
G03I-574J0D01*
G37*
G36*
G01Y1614292D02*
G03I-574J0D01*
G37*
G36*
G01X1320244Y190962D02*
X1323324D01*
X1323484Y190802D01*
Y186503D01*
X1323474Y186472D01*
G03X1323400Y186024I1328J-449D01*
G03X1323474Y185576I1402J1D01*
G01X1323484Y185545D01*
Y185192D01*
X1323186Y184894D01*
X1320962D01*
X1320200Y184132D01*
Y178102D01*
X1321084Y177218D01*
X1323188D01*
X1323474Y176932D01*
Y175222D01*
X1323118Y174866D01*
Y166650D01*
G02X1322703Y166250I-400J0D01*
G03X1322652Y166251I-53J-1401D01*
G03X1321447Y165566I0J-1402D01*
G01X1319471D01*
X1319431Y165714D01*
G03X1319105Y166500I-3190J-862D01*
G03X1318799Y166942I-2861J-1654D01*
G01Y171182D01*
X1319483Y171866D01*
X1320311D01*
X1321544Y173099D01*
Y175122D01*
X1321083Y175583D01*
X1321024D01*
X1320885Y175722D01*
X1320874D01*
X1320624Y175972D01*
X1320520D01*
X1320410Y176082D01*
X1318181D01*
X1318116Y176147D01*
Y187464D01*
X1317412Y188168D01*
Y189725D01*
X1317877Y190190D01*
X1319472D01*
X1320244Y190962D01*
G37*
G36*
G01X1321184Y202767D02*
X1321207Y202791D01*
X1328195D01*
X1328744Y202242D01*
Y200682D01*
X1328284Y200222D01*
Y200221D01*
G02X1328068Y200021I-200J-1D01*
G03X1327952Y200026I-118J-1397D01*
G03Y197222I0J-1402D01*
G03X1328475Y197323I0J1402D01*
G02X1329024Y196952I149J-371D01*
G01Y195602D01*
X1329947Y194679D01*
X1329957Y194665D01*
G03X1330293Y194329I1145J809D01*
G01X1330307Y194319D01*
X1330365Y194261D01*
X1330397D01*
X1330441Y194237D01*
G03X1331102Y194072I660J1237D01*
G03X1331763Y194237I1J1402D01*
G01X1331807Y194261D01*
X1333547D01*
X1333591Y194237D01*
G03X1334113Y194079I659J1237D01*
G01X1334184Y194072D01*
X1335139Y193117D01*
Y182317D01*
X1334584Y181762D01*
X1332724D01*
Y181152D01*
X1332094Y180522D01*
Y179242D01*
X1331664Y178812D01*
X1330574D01*
X1330040Y179347D01*
Y183747D01*
X1328853Y184933D01*
X1328983Y185074D01*
G03X1329354Y186024I-1031J950D01*
G03X1328633Y187249I-1401J0D01*
G02Y187949I194J350D01*
G03X1329354Y189174I-680J1225D01*
G03X1326550I-1402J0D01*
G03X1327271Y187949I1401J0D01*
G02Y187249I-194J-350D01*
G03X1326550Y186024I680J-1225D01*
G03X1326943Y185050I1402J-1D01*
G02X1326938Y184490I-288J-277D01*
G01X1325956Y183507D01*
Y178014D01*
X1326829Y177140D01*
X1328775D01*
X1329044Y176872D01*
Y176412D01*
X1330928Y174528D01*
X1330903Y174419D01*
G03X1330866Y174099I1365J-320D01*
G03X1332268Y172697I1402J0D01*
G03X1332588Y172734I0J1402D01*
G01X1332697Y172759D01*
X1333474Y171982D01*
Y168722D01*
X1332944Y168192D01*
X1332324D01*
X1332235Y168103D01*
X1332161Y168097D01*
G03X1330866Y166699I107J-1398D01*
G03X1330872Y166572I1402J3D01*
G01X1330880Y166478D01*
X1330153Y165751D01*
X1330011Y165881D01*
G03X1329062Y166251I-949J-1032D01*
G03X1327867Y165582I0J-1402D01*
G01X1324694D01*
X1324120Y166157D01*
Y172447D01*
X1324214Y172542D01*
Y174546D01*
X1324476Y174807D01*
Y177347D01*
X1324214Y177608D01*
Y177752D01*
X1323794Y178172D01*
X1323650D01*
X1323603Y178220D01*
X1321597D01*
X1321284Y178532D01*
Y183800D01*
X1321377Y183892D01*
X1323601D01*
X1324486Y184777D01*
Y191217D01*
X1323964Y191738D01*
Y191782D01*
X1323784Y191962D01*
X1323740D01*
X1323739Y191964D01*
X1319829D01*
X1319218Y191352D01*
X1317403D01*
X1317293Y191462D01*
Y191752D01*
X1317320D01*
Y194516D01*
X1317694Y194891D01*
Y195954D01*
X1319708D01*
X1319865Y196112D01*
X1320643D01*
X1320993Y196462D01*
Y196841D01*
G02X1321450Y197237I400J0D01*
G03X1321652Y197222I205J1387D01*
G03Y200026I0J1402D01*
G03X1321599Y200025I0J-1402D01*
G02X1321184Y200425I-15J400D01*
G01Y202767D01*
G37*
G36*
G01X1327657Y183792D02*
X1328578D01*
X1329038Y183332D01*
Y178276D01*
X1328904Y178142D01*
X1327244D01*
X1326957Y178429D01*
Y183092D01*
X1327657Y183792D01*
G37*
G36*
G01X1330042Y198974D02*
X1335675D01*
Y195363D01*
X1334992Y194680D01*
X1334410Y195262D01*
X1330780D01*
X1330026Y196017D01*
Y197907D01*
X1329659Y198273D01*
Y198592D01*
X1330042Y198974D01*
G37*
G36*
G01X1337564Y200882D02*
X1336514D01*
X1335644Y200012D01*
X1329934D01*
X1329784Y200162D01*
Y201717D01*
X1330800Y202733D01*
X1332200D01*
X1332800Y203333D01*
Y205800D01*
X1333100Y206100D01*
X1335200D01*
X1338149Y203151D01*
Y201467D01*
X1337564Y200882D01*
G37*
G36*
G01X1366623Y853383D02*
X1366762Y853488D01*
X1366927Y853323D01*
G02X1366839Y852691I-283J-283D01*
G03X1366069Y851380I731J-1311D01*
G03X1367571Y849878I1502J0D01*
G03X1368882Y850648I0J1501D01*
G02X1369514Y850736I349J-195D01*
G01X1370944Y849306D01*
Y846235D01*
X1370814Y846186D01*
G03X1369972Y844971I456J-1215D01*
G03X1370083Y844444I1297J-2D01*
G01X1370122Y844356D01*
X1369281Y842761D01*
X1369186Y842743D01*
G03X1368124Y841467I236J-1276D01*
G03X1369421Y840170I1297J0D01*
G03X1370448Y840674I0J1298D01*
G02X1370748Y840694I159J-122D01*
G01X1370944Y840498D01*
Y840324D01*
X1374874Y836394D01*
Y824764D01*
X1375926Y823714D01*
X1387160D01*
X1388182Y824737D01*
Y836242D01*
X1389319Y837379D01*
X1399579D01*
X1399959Y836999D01*
Y783127D01*
X1398427Y781595D01*
X1347187D01*
X1337116Y791666D01*
Y815549D01*
X1328556Y824109D01*
Y845411D01*
G02X1329302Y845611I400J0D01*
G01X1329375Y845486D01*
X1329344Y845400D01*
G03X1329272Y844971I1225J-426D01*
G03X1331866I1297J0D01*
G03X1330811Y846246I-1298J0D01*
G01X1330721Y846263D01*
X1329914Y847661D01*
X1329945Y847747D01*
G03X1330018Y848176I-1224J429D01*
G03X1329120Y849410I-1297J0D01*
G02X1328961Y850074I123J381D01*
G01X1329188Y850301D01*
X1329673D01*
X1329727Y850261D01*
G03X1330571Y849978I845J1119D01*
G03X1331466Y850301I0J1401D01*
G01X1333226D01*
G03X1334271Y849878I1045J1079D01*
G03X1335594Y850669I0J1502D01*
G01X1336648D01*
G03X1337971Y849878I1323J711D01*
G03X1339473Y851380I0J1502D01*
G03X1339268Y852136I-1502J-1D01*
G01X1340478Y853346D01*
G03X1340615Y853429I-657J1239D01*
G01X1342561D01*
G03X1344481I960J1154D01*
G01X1346425D01*
G03X1348015I795J1156D01*
G01X1349961D01*
G03X1351881I960J1154D01*
G01X1353825D01*
G03X1355415I795J1156D01*
G01X1357361D01*
G03X1359281I960J1154D01*
G01X1361225D01*
G03X1362815I795J1156D01*
G01X1364761D01*
G03X1365721Y853082I960J1154D01*
G03X1366623Y853383I0J1502D01*
G37*
G36*
G01X1324700Y1349775D02*
X1333702D01*
X1334672Y1348805D01*
Y1344211D01*
X1334497Y1344036D01*
X1327822D01*
Y1344237D01*
Y1344245D01*
G03X1324818I-1502J0D01*
G01Y1344237D01*
Y1344036D01*
X1324439D01*
X1324070Y1344405D01*
Y1349145D01*
X1324700Y1349775D01*
G37*
G36*
G01X1321865Y1400293D02*
X1319359D01*
X1318197Y1401455D01*
Y1425945D01*
X1319017Y1426765D01*
X1348307D01*
X1354357Y1420715D01*
Y1401465D01*
X1353163Y1400271D01*
X1321886D01*
X1321865Y1400293D01*
G37*
G36*
G01X1315746Y1578182D02*
G03I-574J0D01*
G37*
G36*
G01X1323546D02*
G03I-574J0D01*
G37*
G36*
G01X1327806D02*
G03I-574J0D01*
G37*
G36*
G01X1315746Y1590094D02*
G03I-574J0D01*
G37*
G36*
G01X1323546D02*
G03I-574J0D01*
G37*
G36*
G01X1327806D02*
G03I-574J0D01*
G37*
G36*
G01X1316786Y1614292D02*
G03I-574J0D01*
G37*
G36*
G01Y1602380D02*
G03I-574J0D01*
G37*
G36*
G01X1328846D02*
G03I-574J0D01*
G37*
G36*
G01Y1614292D02*
G03I-574J0D01*
G37*
G36*
G01X1321046Y1602380D02*
G03I-574J0D01*
G37*
G36*
G01Y1614292D02*
G03I-574J0D01*
G37*
G36*
G01X1336358Y192146D02*
X1338308D01*
X1338693Y191762D01*
X1340054D01*
X1341934Y189882D01*
X1343244D01*
X1344073Y189053D01*
Y180184D01*
X1343115Y179226D01*
X1341276D01*
X1340625Y178575D01*
Y175556D01*
X1339512Y174914D01*
X1336962D01*
X1336129Y175747D01*
Y181891D01*
X1336140Y181902D01*
Y191929D01*
X1336358Y192146D01*
G37*
G36*
G01X1342778Y200739D02*
X1345291D01*
G03X1346147Y200447I856J1109D01*
G03X1346915Y200676I0J1402D01*
G01X1347051Y200765D01*
X1347965Y199851D01*
X1347975Y199786D01*
G03X1349149Y198612I1386J212D01*
G01X1349214Y198602D01*
X1349394Y198422D01*
Y197553D01*
X1350809Y196138D01*
Y194057D01*
G02X1350174Y193733I-400J0D01*
G03X1349351Y194000I-823J-1135D01*
G03X1347949Y192598I0J-1402D01*
G03X1348302Y191668I1402J0D01*
G02X1348285Y191120I-300J-265D01*
G01X1346918Y189753D01*
X1345559D01*
X1345029Y190283D01*
Y194146D01*
X1344758Y194417D01*
X1342994D01*
X1342529Y194882D01*
Y199703D01*
X1342534Y199708D01*
Y200495D01*
X1342778Y200739D01*
G37*
G36*
G01X1344551Y205019D02*
X1349286D01*
X1349842Y204463D01*
Y202879D01*
X1349174Y202211D01*
X1347509D01*
X1347460Y202341D01*
G03X1346147Y203251I-1313J-492D01*
G03X1344787Y202189I0J-1402D01*
G01X1344749Y202038D01*
X1342630D01*
X1341907Y201315D01*
Y201284D01*
X1341532Y200910D01*
Y200123D01*
X1341528Y200118D01*
Y194467D01*
X1342579Y193416D01*
X1343420D01*
X1343854Y192982D01*
Y191665D01*
X1343569Y191380D01*
X1342019D01*
X1338907Y194492D01*
G02X1338903Y195055I282J284D01*
G03X1339303Y196035I-1002J981D01*
G03X1337901Y197437I-1402J0D01*
G03X1337259Y197282I-1J-1402D01*
G02X1336676Y197637I-183J356D01*
G01Y199286D01*
X1337272Y199880D01*
X1337979D01*
X1339150Y201052D01*
Y202770D01*
X1340953Y204573D01*
X1344105D01*
X1344551Y205019D01*
G37*
G36*
G01X1335606Y1578182D02*
G03I-574J0D01*
G37*
G36*
G01X1339866D02*
G03I-574J0D01*
G37*
G36*
G01X1335606Y1590094D02*
G03I-574J0D01*
G37*
G36*
G01X1339866D02*
G03I-574J0D01*
G37*
G36*
G01X1340906Y1602380D02*
G03I-574J0D01*
G37*
G36*
G01Y1614292D02*
G03I-574J0D01*
G37*
G36*
G01X1333106Y1602380D02*
G03I-574J0D01*
G37*
G36*
G01Y1614292D02*
G03I-574J0D01*
G37*
G36*
G01X1345166Y1602380D02*
G03I-574J0D01*
G37*
G36*
G01Y1614292D02*
G03I-574J0D01*
G37*
G36*
G01X1372298Y208654D02*
G03X1370345Y207845I0J-2762D01*
G01X1368947Y206446D01*
X1361462D01*
X1361201Y206185D01*
X1358199D01*
X1357658Y206726D01*
Y214824D01*
X1357898Y215064D01*
X1359343D01*
X1361109Y213298D01*
X1388250D01*
X1388759Y212789D01*
Y208959D01*
X1388453Y208654D01*
X1376683D01*
G03X1373917I-1383J-232D01*
G01X1372298D01*
G37*
G36*
G01X1375464Y231552D02*
X1388390D01*
X1389280Y230662D01*
Y228158D01*
X1391826Y225612D01*
Y218296D01*
X1389286Y215755D01*
X1360970D01*
X1360841Y215884D01*
Y217285D01*
X1360971Y217333D01*
G03X1361957Y217967I-967J2587D01*
G01X1366247Y222258D01*
X1369976D01*
X1372391Y224673D01*
Y228402D01*
X1375117Y231127D01*
G03X1375464Y231552I-1955J1950D01*
G37*
G36*
G01X1356198Y1335719D02*
X1356284Y1335804D01*
X1366374D01*
X1366800Y1335379D01*
Y1330785D01*
X1366625Y1330610D01*
X1359950D01*
Y1330811D01*
Y1330819D01*
G03X1356946I-1502J0D01*
G01Y1330811D01*
Y1330610D01*
X1356567D01*
X1356198Y1330979D01*
Y1335719D01*
G37*
G36*
G01X1347666Y1578182D02*
G03I-574J0D01*
G37*
G36*
G01X1351926D02*
G03I-574J0D01*
G37*
G36*
G01X1359726D02*
G03I-574J0D01*
G37*
G36*
G01X1347666Y1590094D02*
G03I-574J0D01*
G37*
G36*
G01X1351926D02*
G03I-574J0D01*
G37*
G36*
G01X1359726D02*
G03I-574J0D01*
G37*
G36*
G01X1352966Y1602380D02*
G03I-574J0D01*
G37*
G36*
G01Y1614292D02*
G03I-574J0D01*
G37*
G36*
G01X1357226Y1602380D02*
G03I-574J0D01*
G37*
G36*
G01Y1614292D02*
G03I-574J0D01*
G37*
G36*
G01X1377430Y209422D02*
Y208162D01*
X1376770Y207502D01*
X1374070D01*
X1372780Y208792D01*
X1371200Y210372D01*
Y212562D01*
X1371560Y212922D01*
X1380530D01*
X1381670Y211782D01*
Y210492D01*
X1381060Y209882D01*
X1377890D01*
X1377430Y209422D01*
G37*
G36*
G01X1373031Y661428D02*
G03I-650J0D01*
G37*
G36*
G01X1372581Y685278D02*
G03I-650J0D01*
G37*
G36*
G01X1372893Y697108D02*
G03I-650J0D01*
G37*
G36*
G01Y709108D02*
G03I-650J0D01*
G37*
G36*
G01Y721108D02*
G03I-650J0D01*
G37*
G36*
G01X1437585Y855739D02*
X1439443D01*
X1440661Y854521D01*
Y852703D01*
X1438471Y850513D01*
X1434589D01*
X1433494Y849418D01*
Y844541D01*
X1440363Y837672D01*
Y824322D01*
X1442058Y822627D01*
X1453318D01*
X1454994Y824303D01*
Y839563D01*
X1453575Y840982D01*
Y841778D01*
X1454745Y842948D01*
X1469526D01*
X1469556Y842919D01*
X1473036D01*
X1474216Y841739D01*
Y783934D01*
X1471977Y781695D01*
X1403157D01*
X1402078Y782774D01*
Y837067D01*
X1400672Y838473D01*
X1388292D01*
X1387181Y837362D01*
Y825152D01*
X1386745Y824716D01*
X1376340D01*
X1375876Y825179D01*
Y836982D01*
X1371632Y841226D01*
Y843718D01*
X1371757Y843769D01*
G03X1372566Y844971I-488J1202D01*
G03X1372465Y845475I-1297J2D01*
G01X1372412Y845599D01*
X1372985Y846172D01*
X1373379D01*
X1373775Y845486D01*
X1373744Y845400D01*
G03X1373672Y844971I1225J-426D01*
G03X1376266I1297J0D01*
G03X1376113Y845583I-1297J1D01*
G02X1376466Y846172I353J189D01*
G01X1377172D01*
G02X1377525Y845583I0J-400D01*
G03X1377372Y844971I1144J-611D01*
G03X1377483Y844444I1297J-2D01*
G01X1377522Y844356D01*
X1376681Y842761D01*
X1376586Y842743D01*
G03X1375524Y841467I236J-1276D01*
G03X1378118I1297J0D01*
G03X1378007Y841994I-1297J2D01*
G01X1377968Y842082D01*
X1378809Y843677D01*
X1378904Y843695D01*
G03X1379966Y844971I-236J1276D01*
G03X1379813Y845583I-1297J1D01*
G02X1380166Y846172I353J189D01*
G01X1380779D01*
X1381175Y845486D01*
X1381144Y845400D01*
G03X1381072Y844971I1225J-426D01*
G03X1383666I1297J0D01*
G03X1383513Y845583I-1297J1D01*
G02X1383866Y846172I353J189D01*
G01X1384572D01*
G02X1384925Y845583I0J-400D01*
G03X1384772Y844971I1144J-611D01*
G03X1384883Y844444I1297J-2D01*
G01X1384922Y844356D01*
X1384081Y842761D01*
X1383986Y842743D01*
G03X1382924Y841467I236J-1276D01*
G03X1385518I1297J0D01*
G03X1385407Y841994I-1297J2D01*
G01X1385368Y842082D01*
X1386209Y843677D01*
X1386304Y843695D01*
G03X1387366Y844971I-236J1276D01*
G03X1387213Y845583I-1297J1D01*
G02X1387566Y846172I353J189D01*
G01X1388179D01*
X1388575Y845486D01*
X1388544Y845400D01*
G03X1388472Y844971I1225J-426D01*
G03X1391066I1297J0D01*
G03X1390913Y845583I-1297J1D01*
G02X1391266Y846172I353J189D01*
G01X1391972D01*
G02X1392325Y845583I0J-400D01*
G03X1392172Y844971I1144J-611D01*
G03X1392283Y844444I1297J-2D01*
G01X1392322Y844356D01*
X1391481Y842761D01*
X1391386Y842743D01*
G03X1390324Y841467I236J-1276D01*
G03X1392918I1297J0D01*
G03X1392807Y841994I-1297J2D01*
G01X1392768Y842082D01*
X1393609Y843677D01*
X1393704Y843695D01*
G03X1394766Y844971I-236J1276D01*
G03X1394613Y845583I-1297J1D01*
G02X1394966Y846172I353J189D01*
G01X1395579D01*
X1395975Y845486D01*
X1395944Y845400D01*
G03X1395872Y844971I1225J-426D01*
G03X1398466I1297J0D01*
G03X1398313Y845583I-1297J1D01*
G02X1398666Y846172I353J189D01*
G01X1399372D01*
G02X1399725Y845583I0J-400D01*
G03X1399572Y844971I1144J-611D01*
G03X1399683Y844444I1297J-2D01*
G01X1399722Y844356D01*
X1398881Y842761D01*
X1398786Y842743D01*
G03X1397724Y841467I236J-1276D01*
G03X1400318I1297J0D01*
G03X1400207Y841994I-1297J2D01*
G01X1400168Y842082D01*
X1401009Y843677D01*
X1401104Y843695D01*
G03X1402166Y844971I-236J1276D01*
G03X1402013Y845583I-1297J1D01*
G02X1402366Y846172I353J189D01*
G01X1402979D01*
X1403375Y845486D01*
X1403344Y845400D01*
G03X1403272Y844971I1225J-426D01*
G03X1405866I1297J0D01*
G03X1405713Y845583I-1297J1D01*
G02X1406066Y846172I353J189D01*
G01X1410472D01*
G02X1410825Y845583I0J-400D01*
G03X1410672Y844971I1144J-611D01*
G03X1413266I1297J0D01*
G03X1413194Y845398I-1297J1D01*
G01X1413164Y845485D01*
X1413561Y846172D01*
X1415627D01*
X1416880Y844919D01*
Y844502D01*
X1413836Y841458D01*
Y824529D01*
X1416197Y822169D01*
X1426105D01*
X1428766Y824830D01*
Y843993D01*
X1427273Y845486D01*
Y850173D01*
X1427380Y850229D01*
G03X1428073Y851380I-609J1151D01*
G03X1427900Y852028I-1302J0D01*
G01X1427824Y852160D01*
X1429010Y853346D01*
X1429052Y853361D01*
G03X1429843Y854152I-432J1223D01*
G01X1429858Y854194D01*
X1431403Y855739D01*
X1434500D01*
G02X1434858Y855161I0J-400D01*
G03X1434722Y854584I1162J-578D01*
G03X1437318I1298J0D01*
G03X1437245Y855011I-1298J-2D01*
G01X1437215Y855098D01*
X1437585Y855739D01*
G37*
G36*
G01X1413398Y863709D02*
X1414243D01*
X1414296Y863590D01*
G03X1415994Y862731I1374J607D01*
G01X1416101Y862755D01*
X1416401Y862455D01*
X1416914D01*
Y862145D01*
X1416822Y862086D01*
G03X1416222Y860993I697J-1094D01*
G03X1417278Y859718I1298J0D01*
G01X1417368Y859701D01*
X1418176Y858302D01*
X1418145Y858215D01*
G03X1418074Y857789I1226J-423D01*
G03X1420668I1297J0D01*
G03X1419610Y859064I-1297J0D01*
G01X1419520Y859081D01*
X1418714Y860478D01*
X1418745Y860564D01*
G03X1418818Y860993I-1224J429D01*
G03X1418764Y861362I-1298J-1D01*
G02X1419147Y861876I383J114D01*
G01X1423294D01*
G02X1423677Y861362I0J-400D01*
G03X1423624Y860993I1244J-367D01*
G03X1424679Y859718I1298J0D01*
G01X1424769Y859701D01*
X1425576Y858303D01*
X1425546Y858216D01*
G03X1425474Y857789I1225J-426D01*
G03X1428068I1297J0D01*
G03X1427011Y859064I-1297J0D01*
G01X1426921Y859081D01*
X1426115Y860478D01*
X1426146Y860564D01*
G03X1426218Y860993I-1225J426D01*
G03X1426165Y861362I-1297J2D01*
G02X1426548Y861876I383J114D01*
G01X1429044D01*
X1429951Y860969D01*
Y859097D01*
X1429841Y859041D01*
G03X1429069Y857789I629J-1252D01*
G03X1429175Y857254I1403J0D01*
G01X1429213Y857163D01*
X1428534Y855987D01*
X1428436Y855974D01*
G03X1427218Y854584I184J-1390D01*
G03X1427241Y854331I1403J0D01*
G01X1427260Y854228D01*
X1426661Y853629D01*
Y852887D01*
X1426497Y852857D01*
G03X1426154Y850011I275J-1477D01*
G01X1426272Y849957D01*
Y845071D01*
X1426661Y844682D01*
Y843673D01*
X1427629Y842705D01*
Y825487D01*
X1426173Y824031D01*
X1416175D01*
X1415168Y825038D01*
Y841338D01*
X1417599Y843769D01*
Y843805D01*
X1417882Y844087D01*
Y845334D01*
X1417599Y845616D01*
Y846666D01*
X1417766Y846694D01*
G03X1419022Y848176I-246J1482D01*
G03X1417520Y849678I-1502J0D01*
G03X1416471Y849251I0J-1502D01*
G02X1415908Y849254I-280J286D01*
G01X1415752Y849410D01*
X1414222D01*
X1414194Y849418D01*
G03X1413820Y849474I-377J-1242D01*
G03X1413446Y849418I3J-1298D01*
G01X1413418Y849410D01*
X1410522D01*
X1410494Y849418D01*
G03X1410120Y849474I-377J-1242D01*
G03X1409746Y849418I3J-1298D01*
G01X1409718Y849410D01*
X1406822D01*
X1406794Y849418D01*
G03X1406420Y849474I-377J-1242D01*
G03X1406046Y849418I3J-1298D01*
G01X1406018Y849410D01*
X1403122D01*
X1403094Y849418D01*
G03X1402720Y849474I-377J-1242D01*
G03X1401422Y848176I0J-1298D01*
G03X1401423Y848157I1295J59D01*
G01X1401424Y848072D01*
X1400781Y847429D01*
X1396648D01*
X1396514Y847661D01*
X1396545Y847747D01*
G03X1396618Y848176I-1224J429D01*
G03X1394022I-1298J0D01*
G03X1394050Y847911I1298J3D01*
G02X1393658Y847429I-392J-82D01*
G01X1389248D01*
X1389114Y847661D01*
X1389145Y847747D01*
G03X1389218Y848176I-1224J429D01*
G03X1386622I-1298J0D01*
G03X1386650Y847911I1298J3D01*
G02X1386258Y847429I-392J-82D01*
G01X1381848D01*
X1381714Y847661D01*
X1381745Y847747D01*
G03X1381818Y848176I-1224J429D01*
G03X1379222I-1298J0D01*
G03X1379250Y847911I1298J3D01*
G02X1378858Y847429I-392J-82D01*
G01X1374953D01*
X1374405Y847977D01*
X1374413Y848069D01*
G03X1374418Y848176I-1293J114D01*
G03X1373727Y849323I-1297J0D01*
G01X1373620Y849379D01*
Y849849D01*
G02X1374231Y850189I400J0D01*
G03X1374971Y849978I740J1192D01*
G03Y852782I0J1402D01*
G03X1374231Y852571I0J-1403D01*
G02X1373620Y852911I-211J340D01*
G01Y853268D01*
X1373733Y853322D01*
G03Y855846I-613J1262D01*
G01X1373620Y855900D01*
Y856383D01*
G02X1374244Y856714I400J0D01*
G03X1374729Y856514I727J1075D01*
G01X1374819Y856497D01*
X1375626Y855099D01*
X1375595Y855013D01*
G03X1375522Y854584I1224J-429D01*
G03X1378118I1298J0D01*
G03X1377062Y855859I-1298J0D01*
G01X1376972Y855876D01*
X1376165Y857274D01*
X1376196Y857360D01*
G03X1376268Y857789I-1225J426D01*
G03X1374971Y859086I-1297J0D01*
G03X1374244Y858864I-1J-1297D01*
G02X1373620Y859195I-224J331D01*
G01Y859562D01*
X1374530Y860472D01*
X1375621D01*
X1375678Y860368D01*
G03X1377962I1142J625D01*
G01X1378019Y860472D01*
X1378630D01*
G02X1378976Y859872I0J-400D01*
G01X1378519Y859081D01*
X1378429Y859064D01*
G03X1377374Y857789I243J-1275D01*
G03X1379968I1297J0D01*
G03X1379896Y858217I-1297J2D01*
G01X1379865Y858304D01*
X1380672Y859701D01*
X1380762Y859718D01*
G03X1381657Y860368I-242J1275D01*
G01X1381714Y860472D01*
X1383021D01*
X1383078Y860368D01*
G03X1385362I1142J625D01*
G01X1385419Y860472D01*
X1386030D01*
G02X1386376Y859872I0J-400D01*
G01X1385919Y859081D01*
X1385829Y859064D01*
G03X1384774Y857789I243J-1275D01*
G03X1387368I1297J0D01*
G03X1387296Y858217I-1297J2D01*
G01X1387265Y858304D01*
X1388072Y859701D01*
X1388162Y859718D01*
G03X1389218Y860993I-242J1275D01*
G03X1389207Y861156I-1298J-6D01*
G01X1389195Y861253D01*
X1391566Y863624D01*
X1392083D01*
G03X1394859I1388J573D01*
G01X1395783D01*
G03X1397171Y862695I1388J572D01*
G03X1398545Y863590I0J1502D01*
G01X1398598Y863709D01*
X1399444D01*
X1399497Y863590D01*
G03X1402245I1374J607D01*
G01X1402298Y863709D01*
X1403144D01*
X1403197Y863590D01*
G03X1405945I1374J607D01*
G01X1405998Y863709D01*
X1406844D01*
X1406897Y863590D01*
G03X1409645I1374J607D01*
G01X1409698Y863709D01*
X1410544D01*
X1410597Y863590D01*
G03X1413345I1374J607D01*
G01X1413398Y863709D01*
G37*
G36*
G01X1398459Y950118D02*
X1403490D01*
X1403827Y949780D01*
Y946774D01*
X1402126Y945073D01*
Y940604D01*
X1402160Y940570D01*
Y940453D01*
X1403791Y938822D01*
X1406247D01*
X1406254Y938828D01*
X1425520D01*
X1427919Y936430D01*
X1436841D01*
X1437838Y937426D01*
Y942896D01*
X1438011Y943069D01*
X1443211D01*
X1443711Y942569D01*
Y941369D01*
X1444713Y940367D01*
X1446114D01*
X1446324Y940157D01*
Y936490D01*
X1445386Y935552D01*
X1438580D01*
X1437118Y934089D01*
Y930379D01*
X1436907Y930168D01*
X1433785D01*
X1433046Y929429D01*
Y926669D01*
G02X1432551Y926281I-400J0D01*
G03X1432125Y926332I-426J-1751D01*
G03X1430496Y925301I0J-1802D01*
G01X1430442Y925186D01*
X1430083D01*
G03X1429619Y924994I0J-657D01*
G01X1428891Y924266D01*
G03X1428839Y924208I462J-466D01*
G02X1428220Y924272I-223J871D01*
G01X1428169Y924301D01*
X1428098Y924342D01*
G03X1428079Y924353I-298J-493D01*
G03X1426729Y924677I-1309J-2478D01*
G02X1426323Y925076I-6J400D01*
G01Y925077D01*
G03X1424921Y926481I-1402J2D01*
G03X1423532Y925271I0J-1402D01*
G02X1422980Y924958I-396J55D01*
G01X1422627Y925108D01*
X1422614Y925225D01*
G03X1421220Y926481I-1394J-146D01*
G03X1419818Y925079I0J-1402D01*
G03X1419915Y924565I1402J-2D01*
G02X1419543Y924019I-372J-146D01*
G01X1415497D01*
G02X1415125Y924565I0J400D01*
G03X1415222Y925079I-1305J512D01*
G03X1413820Y926481I-1402J0D01*
G03X1412426Y925224I0J-1401D01*
G01X1412413Y925107D01*
X1410742Y924397D01*
G03X1410678Y924364I232J-528D01*
G01X1410569Y924301D01*
G02X1409674I-448J778D01*
G01X1409634Y924324D01*
G03X1409621Y924331I-280J-504D01*
G03X1408228Y924677I-1350J-2456D01*
G02X1407822Y925077I-6J400D01*
G03X1406420Y926481I-1402J2D01*
G03X1405019Y925138I0J-1402D01*
G02X1404601Y924756I-399J17D01*
G01X1403730D01*
X1403686Y924895D01*
G03X1403261Y925599I-1715J-555D01*
G01Y925734D01*
X1403702Y926174D01*
Y934840D01*
X1401601Y936940D01*
X1383465D01*
X1382702Y936177D01*
X1381656Y935129D01*
Y931147D01*
X1381937Y930866D01*
Y930101D01*
X1381541Y929705D01*
X1380517D01*
X1380022Y930200D01*
Y934315D01*
X1380028Y934340D01*
G03X1380073Y934691I-1357J352D01*
G03X1380028Y935042I-1402J-1D01*
G01X1380022Y935067D01*
Y936109D01*
X1379036Y937095D01*
Y944629D01*
X1379364Y944958D01*
X1379495D01*
X1380242Y945704D01*
Y948104D01*
X1381165Y949028D01*
X1386025D01*
X1386237Y949240D01*
X1387224D01*
X1387446Y949018D01*
X1396576D01*
X1396798Y949240D01*
X1397582D01*
X1398459Y950118D01*
G37*
G36*
G01X1378437Y977229D02*
X1388150D01*
X1388634Y976744D01*
Y972464D01*
X1388940Y972159D01*
Y970479D01*
X1388440Y969979D01*
X1379780D01*
X1379080Y969279D01*
Y968537D01*
G02X1378678Y968137I-400J0D01*
G01X1378671D01*
G03Y965333I0J-1402D01*
G01X1378678D01*
G02X1379080Y964933I2J-400D01*
G01Y963079D01*
X1381441Y960718D01*
Y955944D01*
X1382466Y954919D01*
X1382500D01*
X1382531Y954888D01*
X1385041D01*
X1385990Y953939D01*
Y950409D01*
X1385610Y950029D01*
X1380750D01*
X1379240Y948519D01*
Y946119D01*
X1379080Y945959D01*
X1376358D01*
G02X1376050Y946614I0J400D01*
G03X1376373Y947509I-1078J895D01*
G03X1373569I-1402J0D01*
G03X1373892Y946614I1401J0D01*
G02X1373584Y945959I-308J-255D01*
G01X1372506D01*
G02X1372213Y946632I0J400D01*
G03X1372558Y947509I-942J877D01*
G03X1369984I-1287J0D01*
G03X1370329Y946632I1287J0D01*
G02X1370036Y945959I-293J-273D01*
G01X1369660D01*
X1368799Y946820D01*
X1368854Y946945D01*
G03X1368973Y947509I-1283J565D01*
G03X1367571Y948911I-1402J0D01*
G01X1367555D01*
G02X1367150Y949311I-5J400D01*
G01Y952115D01*
G02X1367555Y952515I400J0D01*
G01X1367571D01*
G03Y955319I0J1402D01*
G01X1367555D01*
G02X1367150Y955719I-5J400D01*
G01Y958524D01*
G02X1367555Y958924I400J0D01*
G01X1367571D01*
G03Y961728I0J1402D01*
G01X1367555D01*
G02X1367150Y962128I-5J400D01*
G01Y964933D01*
G02X1367555Y965333I400J0D01*
G01X1367571D01*
G03Y968137I0J1402D01*
G01X1367555D01*
G02X1367150Y968537I-5J400D01*
G01Y971341D01*
G02X1367555Y971741I400J0D01*
G01X1367571D01*
G03Y974545I0J1402D01*
G01X1367555D01*
G02X1367150Y974945I-5J400D01*
G01Y976469D01*
X1367910Y977229D01*
X1368298D01*
Y976980D01*
X1368276Y976937D01*
G03X1368132Y976347I1144J-592D01*
G03X1370708I1288J0D01*
G03X1370654Y976715I-1288J-1D01*
G02X1371037Y977229I383J114D01*
G01X1371384D01*
G02X1371769Y976722I0J-400D01*
G03X1371718Y976347I1351J-375D01*
G03X1374522I1402J0D01*
G03X1374471Y976722I-1402J0D01*
G02X1374856Y977229I385J107D01*
G01X1375203D01*
G02X1375586Y976715I0J-400D01*
G03X1375532Y976347I1234J-369D01*
G03X1378108I1288J0D01*
G03X1378054Y976715I-1288J-1D01*
G02X1378437Y977229I383J114D01*
G37*
G36*
G01X1386306Y1037139D02*
X1390256D01*
X1390426Y1036969D01*
Y1030809D01*
X1390198Y1030581D01*
X1386668D01*
X1386276Y1030189D01*
Y1027629D01*
X1386636Y1027269D01*
X1387576D01*
X1387716Y1027129D01*
Y1023576D01*
X1389482Y1021810D01*
X1401902D01*
X1402804Y1022712D01*
X1403373D01*
X1403774Y1022311D01*
Y1018423D01*
X1401665Y1016314D01*
X1395941D01*
X1394864Y1015237D01*
Y1013704D01*
X1395809Y1012760D01*
X1401896D01*
X1402236Y1012419D01*
Y1011560D01*
X1402260Y1011536D01*
Y1011504D01*
X1403806Y1009958D01*
Y1006569D01*
X1403372Y1006135D01*
X1402820D01*
X1402199Y1006756D01*
X1390812D01*
X1390791Y1006778D01*
X1388568D01*
X1388396Y1006605D01*
X1388277D01*
X1387726Y1006054D01*
Y1001915D01*
X1387590Y1001779D01*
X1385116D01*
X1384306Y1000969D01*
Y998829D01*
X1384836Y998299D01*
X1385140D01*
X1385141Y998298D01*
X1389631D01*
X1389632Y998299D01*
X1389656D01*
X1390556Y999199D01*
Y1000429D01*
X1390834Y1000708D01*
X1394118D01*
X1394476Y1000349D01*
Y999079D01*
X1395191Y998364D01*
X1401640D01*
X1402116Y997887D01*
Y996763D01*
X1402186Y996694D01*
Y996659D01*
X1403786Y995059D01*
Y992029D01*
X1403488Y991730D01*
X1402926D01*
X1402308Y992349D01*
X1382596D01*
X1382592Y992344D01*
X1382497D01*
X1381716Y991560D01*
Y984912D01*
X1382637Y983992D01*
X1382680D01*
X1382692Y983979D01*
X1389556D01*
X1389568Y983992D01*
X1389585D01*
X1390468Y984874D01*
Y985904D01*
X1390711Y986148D01*
X1394288D01*
X1394582Y985854D01*
Y984751D01*
X1394596Y984737D01*
Y984689D01*
X1395376Y983909D01*
X1401746D01*
X1401936Y983719D01*
Y982719D01*
X1402098Y982558D01*
Y982530D01*
X1402878Y981750D01*
X1403714Y980912D01*
Y977617D01*
X1403372Y977274D01*
X1402814D01*
X1402135Y977954D01*
X1388841D01*
X1388565Y978230D01*
X1380085D01*
G02X1379750Y978849I0J400D01*
G03X1379958Y979552I-1079J702D01*
G03X1379119Y980759I-1288J0D01*
G01X1379078Y980774D01*
X1378737Y981115D01*
X1376227D01*
X1375667Y981675D01*
Y997635D01*
X1376431Y998399D01*
X1378542D01*
X1378578Y998384D01*
G03X1379104Y998282I525J1300D01*
G03X1380506Y999684I0J1402D01*
G03X1379304Y1001072I-1402J0D01*
G01X1379133Y1001096D01*
Y1004681D01*
X1379304Y1004705D01*
G03X1380506Y1006093I-200J1388D01*
G03X1379503Y1007437I-1402J0D01*
G01X1379454Y1007452D01*
X1379277Y1007629D01*
X1379635Y1007987D01*
X1381805D01*
X1381810Y1007992D01*
X1387283D01*
X1387293Y1007981D01*
X1388244D01*
X1389478Y1009215D01*
Y1013320D01*
X1389484Y1013326D01*
X1389478Y1013332D01*
Y1020215D01*
X1388328Y1021365D01*
X1387361D01*
X1387336Y1021340D01*
X1380746D01*
X1380550Y1021536D01*
Y1027539D01*
X1381603Y1028593D01*
G03X1381914Y1029105I-887J889D01*
G01X1381929Y1029152D01*
X1381973Y1029196D01*
Y1032836D01*
X1384706Y1035569D01*
X1384736D01*
X1386306Y1037139D01*
G37*
G36*
G01X1363986Y1578182D02*
G03I-574J0D01*
G37*
G36*
G01X1371786D02*
G03I-574J0D01*
G37*
G36*
G01X1376046D02*
G03I-574J0D01*
G37*
G36*
G01X1363986Y1590094D02*
G03I-574J0D01*
G37*
G36*
G01X1371786D02*
G03I-574J0D01*
G37*
G36*
G01X1376046D02*
G03I-574J0D01*
G37*
G36*
G01X1365026Y1602380D02*
G03I-574J0D01*
G37*
G36*
G01Y1614292D02*
G03I-574J0D01*
G37*
G36*
G01X1377086Y1602286D02*
G03I-574J0D01*
G37*
G36*
G01Y1614292D02*
G03I-574J0D01*
G37*
G36*
G01X1369286Y1602380D02*
G03I-574J0D01*
G37*
G36*
G01Y1614292D02*
G03I-574J0D01*
G37*
G36*
G01X1390166Y145311D02*
G03I-557J0D01*
G37*
G36*
G01X1390000Y147879D02*
G03I-557J0D01*
G37*
G36*
G01X1392974Y234072D02*
X1394012D01*
X1398408Y229675D01*
Y228575D01*
X1395117Y225284D01*
G03X1394308Y223331I1953J-1953D01*
G01Y222348D01*
X1392828D01*
Y226027D01*
X1392578Y226276D01*
Y226414D01*
X1390800Y228192D01*
Y231784D01*
X1392578Y233562D01*
Y233676D01*
X1392974Y234072D01*
G37*
G36*
G01X1381781Y656378D02*
G03I-650J0D01*
G37*
G36*
G01Y668378D02*
G03I-650J0D01*
G37*
G36*
G01X1396481Y666278D02*
G03I-650J0D01*
G37*
G36*
G01X1387581Y660978D02*
G03I-650J0D01*
G37*
G36*
G01X1387793Y690208D02*
G03I-650J0D01*
G37*
G36*
G01X1381381Y692208D02*
G03I-650J0D01*
G37*
G36*
G01X1396281Y695108D02*
G03I-650J0D01*
G37*
G36*
G01X1381381Y704208D02*
G03I-650J0D01*
G37*
G36*
G01X1387793Y704708D02*
G03I-650J0D01*
G37*
G36*
G01X1381381Y716208D02*
G03I-650J0D01*
G37*
G36*
G01X1396281Y709608D02*
G03I-650J0D01*
G37*
G36*
G01X1387793Y719235D02*
G03I-650J0D01*
G37*
G36*
G01X1396281Y724135D02*
G03I-650J0D01*
G37*
G36*
G01X1383570Y733725D02*
G03I-650J0D01*
G37*
G36*
G01X1392058Y738625D02*
G03I-650J0D01*
G37*
G36*
G01X1389561Y929936D02*
X1394366D01*
X1394864Y929437D01*
Y927945D01*
X1397137Y925672D01*
Y925315D01*
X1396567Y924745D01*
X1395311D01*
X1394336Y925720D01*
X1392379Y927677D01*
X1392013D01*
X1389528D01*
X1389380Y927825D01*
Y929755D01*
X1389561Y929936D01*
G37*
G36*
G01X1388180Y927749D02*
X1388340Y927909D01*
Y929789D01*
X1388090Y930039D01*
X1384136D01*
X1383291D01*
X1381677Y928425D01*
Y927485D01*
X1382067Y927095D01*
X1383582D01*
X1384076Y927589D01*
X1387390D01*
X1388020D01*
X1388180Y927749D01*
G37*
G36*
G01X1398094Y926149D02*
X1402260D01*
X1402700Y926589D01*
Y934169D01*
Y934425D01*
X1401186Y935939D01*
X1383880D01*
X1383410Y935469D01*
X1382657Y934715D01*
Y931562D01*
X1382730Y931489D01*
X1395560D01*
X1395700Y931349D01*
X1396083Y930966D01*
X1396128Y930921D01*
Y928115D01*
X1398094Y926149D01*
G37*
G36*
G01X1389942Y971754D02*
X1389976Y971789D01*
X1394026D01*
X1394376Y971439D01*
Y970451D01*
X1395255Y969572D01*
X1395307D01*
X1395451Y969428D01*
X1401311D01*
X1403794Y966944D01*
Y963198D01*
X1403561Y962964D01*
X1402592D01*
X1402035Y963520D01*
X1382451D01*
X1382426Y963495D01*
X1382279D01*
X1381977Y963193D01*
Y963179D01*
X1381606Y962809D01*
X1380766D01*
X1380116Y963459D01*
Y968869D01*
X1380224Y968978D01*
X1388855D01*
X1389942Y970064D01*
Y971754D01*
G37*
G36*
G01X1387776Y1020364D02*
X1387913D01*
X1388476Y1019800D01*
Y1009630D01*
X1387840Y1008994D01*
X1381346D01*
X1380700Y1009639D01*
Y1019849D01*
X1381190Y1020338D01*
X1387751D01*
X1387776Y1020364D01*
G37*
G36*
G01X1390747Y1029714D02*
X1393600D01*
X1393646Y1029668D01*
X1401152D01*
X1401815Y1029004D01*
Y1023139D01*
X1401487Y1022812D01*
X1389897D01*
X1389150Y1023558D01*
Y1027389D01*
X1388600Y1027939D01*
X1388322D01*
X1387991Y1028270D01*
X1387278D01*
Y1029536D01*
X1387320Y1029580D01*
X1390613D01*
X1390747Y1029714D01*
G37*
G36*
G01X1388956Y1336349D02*
X1397958D01*
X1398928Y1335379D01*
Y1330785D01*
X1398753Y1330610D01*
X1392078D01*
Y1330811D01*
Y1330819D01*
G03X1389074I-1502J0D01*
G01Y1330811D01*
Y1330610D01*
X1388695D01*
X1388326Y1330979D01*
Y1335719D01*
X1388956Y1336349D01*
G37*
G36*
G01X1394885Y1420602D02*
Y1404719D01*
X1395341Y1404263D01*
X1411752D01*
X1412161Y1404672D01*
Y1409547D01*
X1412600Y1409986D01*
X1414183D01*
X1414668Y1410471D01*
Y1412851D01*
X1414319Y1413200D01*
X1412722D01*
X1412161Y1413761D01*
Y1420809D01*
X1411615Y1421355D01*
X1395638D01*
X1394885Y1420602D01*
G37*
G36*
G01X1383846Y1578182D02*
G03I-574J0D01*
G37*
G36*
G01Y1590094D02*
G03I-574J0D01*
G37*
G36*
G01X1381346Y1602380D02*
G03I-574J0D01*
G37*
G36*
G01Y1614292D02*
G03I-574J0D01*
G37*
G36*
G01X1389146D02*
G03I-574J0D01*
G37*
G36*
G01Y1602380D02*
G03I-574J0D01*
G37*
G36*
G01X1396681Y680678D02*
G03I-650J0D01*
G37*
G36*
G01X1438250Y1066442D02*
G02X1437851Y1066871I0J400D01*
G03X1437855Y1066974I-1398J106D01*
G03X1435051I-1402J0D01*
G01Y1066972D01*
G03X1435116Y1066551I1402J1D01*
G01X1435153Y1066435D01*
X1431427Y1062709D01*
X1427934D01*
X1426230Y1064413D01*
G03X1425076Y1066089I-2727J-643D01*
G01Y1067387D01*
X1426597Y1068908D01*
X1426717Y1068863D01*
G03X1427202Y1068776I486J1315D01*
G01X1427204D01*
G03Y1071580I0J1402D01*
G03X1427105Y1071577I-7J-1402D01*
G02X1426677Y1071975I-28J399D01*
G01Y1072921D01*
G03X1426755Y1073382I-1324J461D01*
G01Y1073384D01*
G03X1426677Y1073845I-1402J0D01*
G01Y1074789D01*
G02X1427105Y1075188I400J0D01*
G03X1427203Y1075185I92J1399D01*
G03X1428605Y1076587I0J1402D01*
G03X1427344Y1077982I-1402J0D01*
G02X1427101Y1078662I40J398D01*
G01X1427374Y1078935D01*
G02X1427967Y1078905I283J-283D01*
G03X1429053Y1078389I1086J885D01*
G03X1430398Y1079395I0J1402D01*
G01X1430440Y1079538D01*
X1431367D01*
X1431409Y1079395D01*
G03X1432754Y1078389I1345J396D01*
G03X1433457Y1078578I0J1402D01*
G02X1434007Y1078427I201J-346D01*
G03X1434049Y1078354I2449J1361D01*
G02X1433905Y1077802I-344J-205D01*
G03X1433202Y1076587I698J-1215D01*
G03X1434604Y1075185I1402J0D01*
G03X1435797Y1075851I0J1402D01*
G02X1436109Y1075887I170J-105D01*
G01X1436241Y1075755D01*
G03X1437073Y1075410I832J831D01*
G01X1437539D01*
X1437587Y1075382D01*
G03X1438304Y1075185I717J1206D01*
G03Y1077989I0J1402D01*
G03X1437753Y1077876I0J-1402D01*
G03X1437295Y1078669I-3148J-1289D01*
G03X1437799Y1079395I-841J1122D01*
G01X1437841Y1079538D01*
X1438767D01*
X1438809Y1079395D01*
G03X1440154Y1078389I1345J396D01*
G03X1441556Y1079791I0J1402D01*
G03X1440731Y1081069I-1402J0D01*
G01Y1081419D01*
G02X1441325Y1081769I400J0D01*
G03X1442004Y1081593I680J1226D01*
G03Y1084397I0J1402D01*
G03X1441325Y1084221I1J-1402D01*
G02X1440731Y1084571I-194J350D01*
G01Y1084923D01*
G03Y1087477I-578J1277D01*
G01Y1087826D01*
G02X1441325Y1088176I400J0D01*
G03X1442003Y1088001I678J1226D01*
G03X1443405Y1089383I0J1402D01*
G02X1443805Y1089778I400J-5D01*
G01X1443901D01*
G02X1444301Y1089383I0J-400D01*
G03X1447105I1402J21D01*
G02X1447505Y1089778I400J-5D01*
G01X1447601D01*
G02X1448001Y1089383I0J-400D01*
G03X1450805I1402J20D01*
G02X1451205Y1089778I400J-5D01*
G01X1451302D01*
G02X1451702Y1089383I0J-400D01*
G03X1454506I1402J21D01*
G02X1454906Y1089778I400J-5D01*
G01X1455002D01*
G02X1455402Y1089383I0J-400D01*
G03X1458206I1402J21D01*
G02X1458606Y1089778I400J-5D01*
G01X1458702D01*
G02X1459102Y1089383I0J-400D01*
G03X1461906I1402J21D01*
G02X1462306Y1089778I400J-5D01*
G01X1462517D01*
G02X1462917Y1089384I0J-400D01*
G03X1465491I1287J19D01*
G02X1465891Y1089778I400J-6D01*
G01X1466217D01*
G02X1466617Y1089384I0J-400D01*
G03X1469191I1287J19D01*
G02X1469591Y1089778I400J-6D01*
G01X1469801D01*
G02X1470201Y1089383I0J-400D01*
G03X1473005I1402J21D01*
G02X1473405Y1089778I400J-5D01*
G01X1473617D01*
G02X1474017Y1089384I0J-400D01*
G03X1476591I1287J19D01*
G02X1476991Y1089778I400J-6D01*
G01X1477202D01*
G02X1477602Y1089383I0J-400D01*
G03X1480406I1402J21D01*
G02X1480806Y1089778I400J-5D01*
G01X1481017D01*
G02X1481417Y1089384I0J-400D01*
G03X1483991I1287J19D01*
G02X1484391Y1089778I400J-6D01*
G01X1484602D01*
G02X1485002Y1089383I0J-400D01*
G03X1487806I1402J21D01*
G02X1488206Y1089778I400J-5D01*
G01X1488417D01*
G02X1488817Y1089384I0J-400D01*
G03X1491391I1287J19D01*
G02X1491791Y1089778I400J-6D01*
G01X1492117D01*
G02X1492517Y1089384I0J-400D01*
G03X1495091I1287J19D01*
G02X1495491Y1089778I400J-6D01*
G01X1495701D01*
G02X1496101Y1089383I0J-400D01*
G03X1498905I1402J21D01*
G02X1499305Y1089778I400J-5D01*
G01X1499517D01*
G02X1499917Y1089384I0J-400D01*
G03X1502491I1287J19D01*
G02X1502891Y1089778I400J-6D01*
G01X1503102D01*
G02X1503502Y1089383I0J-400D01*
G03X1506306I1402J21D01*
G02X1506706Y1089778I400J-5D01*
G01X1506917D01*
G02X1507317Y1089384I0J-400D01*
G03X1509891I1287J19D01*
G02X1510291Y1089778I400J-6D01*
G01X1510501D01*
G02X1510901Y1089383I0J-400D01*
G03X1513705I1402J21D01*
G02X1514105Y1089778I400J-5D01*
G01X1517611D01*
X1519753Y1091919D01*
G02X1520372Y1091852I283J-283D01*
G03X1521553Y1091206I1181J757D01*
G03X1522955Y1092608I0J1402D01*
G03X1522309Y1093789I-1403J0D01*
G02X1522242Y1094408I216J336D01*
G01X1522541Y1094707D01*
G03X1523403Y1094411I862J1107D01*
G03X1524805Y1095813I0J1402D01*
G03X1524597Y1096547I-1402J-1D01*
G01X1524515Y1096682D01*
X1539598Y1111764D01*
Y1112740D01*
X1541606Y1114748D01*
Y1413588D01*
X1510836Y1444358D01*
X1451306D01*
X1450276Y1445388D01*
Y1497448D01*
X1455370Y1502542D01*
X1591800D01*
X1598160Y1496182D01*
Y1341208D01*
X1587127Y1330175D01*
G03X1586628Y1328972I1203J-1204D01*
G01Y1078517D01*
X1584565Y1076454D01*
X1578150D01*
G03X1576947Y1075955I1J-1702D01*
G01X1572115Y1071124D01*
X1525420D01*
G03X1524598Y1070912I1J-1702D01*
G03X1523404Y1071580I-1194J-733D01*
G03X1522012Y1070345I0J-1402D01*
G03X1519942Y1069971I-460J-3371D01*
G03X1519904Y1069950I550J-1040D01*
G01X1519851Y1069919D01*
G02X1519704Y1069880I-147J259D01*
G02X1519555Y1069920I0J298D01*
G03X1516242Y1069971I-1702J-2946D01*
G03X1516204Y1069950I550J-1040D01*
G01X1516151Y1069919D01*
G02X1516004Y1069880I-147J259D01*
G02X1515855Y1069920I0J298D01*
G03X1513696Y1070346I-1703J-2946D01*
G03X1512304Y1071580I-1392J-168D01*
G03X1510902Y1070178I0J-1402D01*
G03X1511463Y1069056I1403J0D01*
G03X1511005Y1068263I2690J-2082D01*
G03X1510454Y1068376I-551J-1289D01*
G01X1510453D01*
G03X1509061Y1067142I0J-1402D01*
G03X1508273Y1067156I-454J-3372D01*
G01X1508194Y1067148D01*
X1508001Y1067297D01*
X1507982Y1067358D01*
G03X1505524I-1229J-384D01*
G01X1505505Y1067297D01*
X1505313Y1067149D01*
X1505234Y1067157D01*
G03X1504573Y1067156I-325J-3387D01*
G01X1504494Y1067148D01*
X1504301Y1067297D01*
X1504282Y1067358D01*
G03X1503053Y1068262I-1229J-383D01*
G03X1501824Y1067357I0J-1287D01*
G01X1501805Y1067296D01*
X1501613Y1067148D01*
X1501534Y1067156D01*
G03X1501206Y1067172I-330J-3386D01*
G01X1501203D01*
G03X1500745Y1067141I0J-3402D01*
G03X1499353Y1068376I-1392J-167D01*
G03X1497961Y1067142I0J-1402D01*
G03X1497173Y1067156I-454J-3372D01*
G01X1497094Y1067148D01*
X1496901Y1067297D01*
X1496882Y1067358D01*
G03X1494424I-1229J-384D01*
G01X1494405Y1067297D01*
X1494213Y1067149D01*
X1494134Y1067157D01*
G03X1493345Y1067141I-326J-3387D01*
G03X1491953Y1068376I-1392J-167D01*
G03X1490561Y1067142I0J-1402D01*
G03X1489773Y1067156I-454J-3372D01*
G01X1489694Y1067148D01*
X1489501Y1067297D01*
X1489482Y1067358D01*
G03X1487024I-1229J-384D01*
G01X1487005Y1067297D01*
X1486813Y1067149D01*
X1486734Y1067157D01*
G03X1485945Y1067141I-326J-3387D01*
G03X1484553Y1068376I-1392J-167D01*
G03X1483161Y1067142I0J-1402D01*
G03X1482373Y1067156I-454J-3372D01*
G01X1482294Y1067148D01*
X1482101Y1067297D01*
X1482082Y1067358D01*
G03X1479624I-1229J-384D01*
G01X1479605Y1067297D01*
X1479413Y1067149D01*
X1479334Y1067157D01*
G03X1478673Y1067156I-325J-3387D01*
G01X1478594Y1067148D01*
X1478401Y1067297D01*
X1478382Y1067358D01*
G03X1475924I-1229J-384D01*
G01X1475905Y1067297D01*
X1475713Y1067149D01*
X1475634Y1067157D01*
G03X1474845Y1067141I-326J-3387D01*
G03X1473453Y1068376I-1392J-167D01*
G03X1472061Y1067142I0J-1402D01*
G03X1471273Y1067156I-454J-3372D01*
G01X1471194Y1067148D01*
X1471001Y1067297D01*
X1470982Y1067358D01*
G03X1468524I-1229J-384D01*
G01X1468505Y1067297D01*
X1468313Y1067149D01*
X1468234Y1067157D01*
G03X1467445Y1067141I-326J-3387D01*
G03X1466053Y1068376I-1392J-167D01*
G03X1464661Y1067142I0J-1402D01*
G03X1463873Y1067156I-454J-3372D01*
G01X1463794Y1067148D01*
X1463601Y1067297D01*
X1463582Y1067358D01*
G03X1462353Y1068262I-1229J-383D01*
G03X1461124Y1067357I0J-1287D01*
G01X1461105Y1067296D01*
X1460913Y1067148D01*
X1460834Y1067156D01*
G03X1460046Y1067141I-330J-3386D01*
G03X1458654Y1068376I-1392J-167D01*
G03X1457262Y1067142I0J-1402D01*
G03X1456345Y1067141I-455J-3372D01*
G03X1454953Y1068376I-1392J-167D01*
G03X1453561Y1067142I0J-1402D01*
G03X1452645Y1067141I-454J-3372D01*
G03X1451253Y1068376I-1392J-167D01*
G03X1449861Y1067142I0J-1402D01*
G03X1448945Y1067141I-454J-3372D01*
G03X1447553Y1068376I-1392J-167D01*
G03X1446305Y1067614I0J-1403D01*
G02X1445793Y1067428I-356J182D01*
G01X1445014Y1067759D01*
G03X1443853Y1068376I-1161J-784D01*
G03X1442451Y1066974I0J-1402D01*
G03X1442455Y1066871I1402J3D01*
G02X1442056Y1066442I-399J-29D01*
G01X1441950D01*
G02X1441551Y1066871I0J400D01*
G03X1441555Y1066974I-1398J106D01*
G03X1438751I-1402J0D01*
G03X1438755Y1066871I1402J3D01*
G02X1438356Y1066442I-399J-29D01*
G01X1438250D01*
G37*
G36*
G01X1421084Y1336349D02*
X1430086D01*
X1431056Y1335379D01*
Y1330785D01*
X1430881Y1330610D01*
X1424206D01*
Y1330811D01*
Y1330819D01*
G03X1421202I-1502J0D01*
G01Y1330811D01*
Y1330610D01*
X1420823D01*
X1420454Y1330979D01*
Y1335719D01*
X1421084Y1336349D01*
G37*
G36*
G01X1433707Y862396D02*
G02X1434121Y862796I400J0D01*
G03X1434171Y862795I53J1401D01*
G03X1435562Y864020I0J1402D01*
G01X1435584Y864195D01*
X1436458D01*
X1436480Y864020D01*
G03X1439262I1391J177D01*
G01X1439284Y864195D01*
X1440158D01*
X1440180Y864020D01*
G03X1442962I1391J177D01*
G01X1442984Y864195D01*
X1443858D01*
X1443880Y864020D01*
G03X1446662I1391J177D01*
G01X1446684Y864195D01*
X1447558D01*
X1447580Y864020D01*
G03X1450362I1391J177D01*
G01X1450384Y864195D01*
X1451258D01*
X1451280Y864020D01*
G03X1454062I1391J177D01*
G01X1454084Y864195D01*
X1454958D01*
X1454980Y864020D01*
G03X1457762I1391J177D01*
G01X1457784Y864195D01*
X1458658D01*
X1458680Y864020D01*
G03X1461462I1391J177D01*
G01X1461484Y864195D01*
X1462358D01*
X1462380Y864020D01*
G03X1463771Y862795I1391J177D01*
G03X1464652Y863106I0J1403D01*
G03X1465230Y863016I965J4295D01*
G01X1465303Y863009D01*
X1466582Y861730D01*
X1467525D01*
G03X1468028Y861114I3648J2465D01*
G03X1468022Y860993I1292J-125D01*
G03X1469078Y859718I1298J0D01*
G01X1469168Y859701D01*
X1469976Y858302D01*
X1469945Y858215D01*
G03X1469874Y857789I1226J-423D01*
G03X1472468I1297J0D01*
G03X1471410Y859064I-1297J0D01*
G01X1471320Y859081D01*
X1471244Y859213D01*
G02X1471556Y859811I347J200D01*
G03X1472265Y859932I-384J4386D01*
G03X1473020Y859691I755J1062D01*
G03X1473776Y859933I0J1302D01*
G03X1475971Y859934I1096J4264D01*
G03X1476284Y859771I750J1058D01*
G01X1476326Y859756D01*
X1476551Y859531D01*
Y858903D01*
G02X1475849Y858641I-400J1D01*
G03X1474871Y859086I-978J-852D01*
G03X1473574Y857789I0J-1297D01*
G03X1473646Y857361I1297J-2D01*
G01X1473677Y857274D01*
X1472870Y855876D01*
X1472780Y855859D01*
G03X1471722Y854584I239J-1275D01*
G03X1474318I1298J0D01*
G03X1474245Y855011I-1298J-2D01*
G01X1474215Y855098D01*
X1475023Y856497D01*
X1475113Y856514D01*
G03X1476153Y857591I-242J1275D01*
G01X1476179Y857761D01*
X1476551D01*
Y856685D01*
X1476528Y856641D01*
G03X1476256Y856012I3892J-2056D01*
G03X1475252Y854271I465J-1428D01*
G03X1474407Y852809I3318J-2893D01*
G03Y849951I465J-1429D01*
G03X1475952Y847841I4164J1429D01*
G01X1476030Y847784D01*
X1476035Y847654D01*
Y847641D01*
G03X1476171Y846779I3715J144D01*
G01X1476178Y846752D01*
Y845471D01*
X1475106Y844399D01*
X1454822D01*
X1454372Y843950D01*
X1454330D01*
X1452574Y842193D01*
Y840567D01*
X1453700Y839441D01*
Y825266D01*
X1452953Y824519D01*
X1442855D01*
X1442561Y824813D01*
Y838191D01*
X1440776Y839976D01*
G02X1440762Y840527I283J283D01*
G03X1441123Y841465I-1041J939D01*
G01Y841467D01*
G03X1439721Y842869I-1402J0D01*
G01X1439719D01*
G03X1438781Y842508I1J-1402D01*
G02X1438230Y842522I-268J297D01*
G01X1434861Y845891D01*
Y849019D01*
X1435354Y849512D01*
X1438886D01*
X1439093Y849719D01*
X1440061D01*
X1440581Y850239D01*
X1440718Y850144D01*
G03X1441571Y849878I853J1235D01*
G03X1443073Y851380I0J1502D01*
G03X1441828Y852860I-1502J0D01*
G01X1441662Y852889D01*
Y854936D01*
X1439858Y856740D01*
X1439442D01*
X1439017Y857165D01*
X1439068Y857289D01*
G03X1439168Y857788I-1197J499D01*
G01Y857789D01*
G03X1436574I-1297J0D01*
G03X1436575Y857729I1297J-8D01*
G02X1436176Y857310I-400J-19D01*
G01X1435866D01*
G02X1435467Y857729I1J400D01*
G03X1435468Y857789I-1296J52D01*
G03X1434410Y859064I-1297J0D01*
G01X1434320Y859081D01*
X1433707Y860144D01*
Y862396D01*
G37*
G36*
G01X1448816Y924929D02*
X1448126Y924239D01*
X1434416D01*
X1434106Y924549D01*
Y928889D01*
X1434346Y929129D01*
X1437326D01*
X1438266Y930069D01*
Y933719D01*
X1438891Y934344D01*
X1446431D01*
X1446656Y934119D01*
Y931009D01*
X1448816Y928849D01*
Y924929D01*
G37*
G36*
G01X1439362Y957148D02*
X1442908D01*
X1443236Y956819D01*
Y955579D01*
X1444286Y954528D01*
Y949435D01*
X1443672Y948820D01*
X1431461D01*
X1431210Y948569D01*
X1431206D01*
X1430980Y948342D01*
X1429882D01*
X1429758Y948467D01*
Y954384D01*
X1430245Y954872D01*
X1437705D01*
X1438204Y955371D01*
X1438230Y955385D01*
G03X1438967Y956619I-665J1234D01*
G03X1438963Y956719I-1402J-6D01*
G02X1439362Y957148I399J29D01*
G37*
G36*
G01X1439604Y971808D02*
X1443258D01*
X1443466Y971599D01*
Y970099D01*
X1444246Y969319D01*
X1452976D01*
X1453395Y968899D01*
Y964367D01*
G03Y962693I1126J-837D01*
G01Y959655D01*
X1452845Y959105D01*
X1451995D01*
X1451834Y959265D01*
Y964140D01*
G03X1451493Y964281I-200J0D01*
G01X1450555Y963343D01*
X1431325D01*
X1431145Y963164D01*
X1431078D01*
X1430853Y962938D01*
X1430114D01*
X1429798Y963255D01*
Y967450D01*
X1431696Y969349D01*
X1438266D01*
X1438268Y969350D01*
X1438284D01*
X1439248Y970314D01*
Y971451D01*
X1439604Y971808D01*
G37*
G36*
G01X1451886Y1023309D02*
X1452986D01*
X1453236Y1023059D01*
Y983320D01*
X1453221Y983284D01*
G03X1453118Y982756I1299J-527D01*
G03X1453221Y982228I1402J-1D01*
G01X1453236Y982192D01*
Y977300D01*
X1452855Y976919D01*
X1451923D01*
X1450902Y977940D01*
X1444489D01*
X1444459Y977970D01*
X1429914D01*
X1429678Y978207D01*
Y982160D01*
X1431356Y983839D01*
X1437606D01*
X1437624Y983856D01*
X1437740D01*
X1438225Y984342D01*
X1438249Y984355D01*
G03X1438967Y985579I-684J1224D01*
G03X1438936Y985871I-1402J-1D01*
G01X1438914Y985978D01*
X1439153Y986218D01*
X1442911D01*
X1443166Y985962D01*
Y984942D01*
X1444174Y983934D01*
X1450311D01*
X1451998Y985622D01*
Y991333D01*
X1450987Y992344D01*
X1429940D01*
X1429808Y992477D01*
Y995964D01*
X1432192Y998349D01*
X1437616D01*
X1437624Y998356D01*
X1437840D01*
X1438768Y999284D01*
Y999356D01*
X1438792Y999401D01*
G03X1438967Y1000079I-1226J678D01*
G03X1438935Y1000378I-1402J1D01*
G01X1438912Y1000485D01*
X1439124Y1000698D01*
X1442998D01*
X1443318Y1000378D01*
Y999327D01*
X1444281Y998364D01*
X1450634D01*
X1450639Y998369D01*
X1450648D01*
X1451659Y999380D01*
Y999390D01*
X1451846Y999577D01*
Y1005946D01*
X1451035Y1006756D01*
X1430946D01*
X1430446Y1006256D01*
X1430048D01*
X1429928Y1006377D01*
Y1009780D01*
X1431716Y1011569D01*
Y1012818D01*
X1431738Y1012840D01*
X1438071D01*
X1438802Y1013572D01*
Y1014195D01*
X1438807Y1014215D01*
G03X1438838Y1014509I-1371J293D01*
G03X1438807Y1014803I-1402J1D01*
G01X1438802Y1014823D01*
Y1015457D01*
X1438644Y1015615D01*
Y1015761D01*
X1438118Y1016287D01*
X1430384D01*
X1429751Y1016920D01*
Y1022684D01*
X1430054Y1022987D01*
X1430611D01*
X1431638Y1021960D01*
X1450537D01*
X1451886Y1023309D01*
G37*
G36*
G01X1442461Y1037428D02*
X1445080D01*
X1445195Y1037313D01*
G03X1446027Y1036968I832J831D01*
G01X1449240D01*
X1450180Y1036028D01*
Y1035045D01*
G03X1450411Y1034346I1177J1D01*
G01Y1032194D01*
X1450051Y1031834D01*
X1447911D01*
X1446596Y1030519D01*
X1442696D01*
X1442461Y1030753D01*
Y1037428D01*
G37*
G36*
G01X1432171Y1029444D02*
X1443711D01*
X1444506Y1028649D01*
Y1023349D01*
X1444119Y1022962D01*
X1432173D01*
X1431666Y1023469D01*
Y1028939D01*
X1432171Y1029444D01*
G37*
G36*
G01X1433714Y1037428D02*
X1440386D01*
Y1030789D01*
X1440066Y1030469D01*
X1433016D01*
X1432316Y1031169D01*
Y1036960D01*
X1432758D01*
G03X1433590Y1037304I1J1176D01*
G01X1433714Y1037428D01*
G37*
G36*
G01X1456980Y209382D02*
G03I-557J0D01*
G37*
G36*
G01X1454380Y206002D02*
G03I-557J0D01*
G37*
G36*
G01X1455539Y658712D02*
G03I-650J0D01*
G37*
G36*
G01X1455089Y670262D02*
G03I-650J0D01*
G37*
G36*
G01Y682562D02*
G03I-650J0D01*
G37*
G36*
G01X1455401Y694392D02*
G03I-650J0D01*
G37*
G36*
G01Y706392D02*
G03I-650J0D01*
G37*
G36*
G01X1448062Y935814D02*
X1452744D01*
X1453345Y935213D01*
Y932250D01*
G03Y930726I1178J-762D01*
G01Y929308D01*
X1453076Y929039D01*
X1450589D01*
X1447658Y931970D01*
Y934534D01*
X1447606Y934585D01*
Y935358D01*
X1448062Y935814D01*
G37*
G36*
G01X1446097Y948639D02*
X1452170D01*
X1453466Y947343D01*
Y945068D01*
G03X1453260Y944632I1054J-765D01*
G01X1453246Y944579D01*
X1452826Y944159D01*
X1446023D01*
X1445520Y944662D01*
Y948062D01*
X1446097Y948639D01*
G37*
G36*
G01X1453265Y958109D02*
X1455616D01*
X1456836Y956889D01*
X1456849Y956831D01*
G03X1457569Y955880I1372J290D01*
G01X1457676Y955824D01*
Y952010D01*
X1457569Y951954D01*
G03Y949472I652J-1241D01*
G01X1457676Y949416D01*
Y946549D01*
X1457186Y946059D01*
X1456166D01*
X1452556Y949669D01*
X1445913D01*
X1445520Y950062D01*
Y954662D01*
X1445704Y954846D01*
X1450841D01*
X1450872Y954878D01*
X1451504D01*
X1452481Y955854D01*
Y957534D01*
X1453050Y958104D01*
X1453260D01*
X1453265Y958109D01*
G37*
G36*
G01X1444916Y943099D02*
X1451796D01*
X1452176Y942719D01*
Y937189D01*
X1451886Y936899D01*
X1448106D01*
X1447826Y937179D01*
Y939919D01*
X1447326Y940420D01*
Y940572D01*
X1446529Y941368D01*
X1445128D01*
X1444712Y941784D01*
Y942896D01*
X1444916Y943099D01*
G37*
G36*
G01X1445625Y976938D02*
X1450487D01*
X1451508Y975918D01*
X1452388D01*
X1453566Y974739D01*
Y970965D01*
G03X1453215Y970448I955J-1026D01*
G01X1453165Y970320D01*
X1444661D01*
X1444468Y970514D01*
Y971864D01*
X1445180Y972576D01*
Y972992D01*
X1445206Y973019D01*
Y976519D01*
X1445625Y976938D01*
G37*
G36*
G01X1451806Y1032739D02*
X1451999D01*
X1453436Y1031302D01*
Y1030779D01*
G03X1453706Y1030030I1177J1D01*
G01Y1029165D01*
X1453687Y1029125D01*
G03X1453551Y1028523I1266J-602D01*
G03X1453687Y1027921I1402J0D01*
G01X1453706Y1027881D01*
Y1024799D01*
X1453441Y1024534D01*
X1451611D01*
X1450226Y1023149D01*
X1446046D01*
X1445806Y1023389D01*
Y1029319D01*
X1446004Y1029518D01*
X1447011D01*
X1448282Y1030789D01*
X1450456D01*
X1451606Y1031939D01*
Y1032539D01*
X1451806Y1032739D01*
G37*
G36*
G01X1452277Y1336904D02*
X1461279D01*
X1462249Y1335934D01*
Y1331340D01*
X1462074Y1331165D01*
X1456301D01*
X1456255Y1331301D01*
G03X1453409I-1423J-483D01*
G01X1453363Y1331165D01*
X1452016D01*
X1451647Y1331534D01*
Y1336274D01*
X1452277Y1336904D01*
G37*
G36*
G01X1504661Y1443328D02*
X1509084D01*
X1533997Y1418415D01*
Y1418322D01*
X1539090Y1413229D01*
Y1381292D01*
X1537460Y1379662D01*
X1475300D01*
X1474800Y1380162D01*
Y1415230D01*
X1475920Y1416350D01*
G02X1476061Y1416408I141J-142D01*
G01X1484216D01*
Y1416418D01*
X1486783D01*
G03X1486925Y1416477I0J200D01*
G01X1487877Y1417429D01*
G03X1487936Y1417571I-141J142D01*
G01Y1425855D01*
G03X1487877Y1425997I-200J0D01*
G01X1484745Y1429129D01*
G03X1484603Y1429188I-142J-141D01*
G01X1452094D01*
X1450387Y1430895D01*
Y1442185D01*
X1451530Y1443328D01*
X1501251D01*
G02X1501448Y1442581I-1J-400D01*
G03X1499553Y1439530I1509J-3051D01*
G03X1506359I3403J0D01*
G03X1504464Y1442581I-3404J0D01*
G02X1504661Y1443328I198J347D01*
G37*
G36*
G01X1460669Y1578182D02*
G03I-574J0D01*
G37*
G36*
G01Y1590094D02*
G03I-574J0D01*
G37*
G36*
G01X1465736Y213082D02*
G03I-557J0D01*
G37*
G36*
G01X1465700Y319962D02*
X1481700D01*
X1482376Y319286D01*
Y281438D01*
X1481500Y280562D01*
X1478280D01*
X1477850Y280992D01*
G03X1476820Y281418I-1029J-1030D01*
G01X1466823D01*
X1465158Y283084D01*
Y319420D01*
X1465700Y319962D01*
G37*
G36*
G01X1464289Y653662D02*
G03I-650J0D01*
G37*
G36*
G01X1470301Y655992D02*
G03I-650J0D01*
G37*
G36*
G01X1462660Y645842D02*
G03I-650J0D01*
G37*
G36*
G01X1464289Y665662D02*
G03I-650J0D01*
G37*
G36*
G01X1470089Y670262D02*
G03I-650J0D01*
G37*
G36*
G01X1464289Y677562D02*
G03I-650J0D01*
G37*
G36*
G01X1463889Y689492D02*
G03I-650J0D01*
G37*
G36*
G01X1470301Y684992D02*
G03I-650J0D01*
G37*
G36*
G01X1463889Y701492D02*
G03I-650J0D01*
G37*
G36*
G01X1470127Y699475D02*
G03I-650J0D01*
G37*
G36*
G01X1472729Y1578182D02*
G03I-574J0D01*
G37*
G36*
G01X1468469D02*
G03I-574J0D01*
G37*
G36*
G01X1472729Y1590094D02*
G03I-574J0D01*
G37*
G36*
G01X1468469D02*
G03I-574J0D01*
G37*
G36*
G01X1473769Y1614292D02*
G03I-574J0D01*
G37*
G36*
G01Y1602380D02*
G03I-574J0D01*
G37*
G36*
G01X1465969D02*
G03I-574J0D01*
G37*
G36*
G01Y1614292D02*
G03I-574J0D01*
G37*
G36*
G01X1478257Y236502D02*
G03I-557J0D01*
G37*
G36*
G01X1478789Y660892D02*
G03I-650J0D01*
G37*
G36*
G01X1479189Y675462D02*
G03I-650J0D01*
G37*
G36*
G01X1478789Y689892D02*
G03I-650J0D01*
G37*
G36*
G01Y704392D02*
G03I-650J0D01*
G37*
G36*
G01X1484227Y1350564D02*
X1493229D01*
X1494199Y1349594D01*
Y1345000D01*
X1494024Y1344825D01*
X1488351D01*
X1488295Y1344933D01*
G03X1485625I-1335J-688D01*
G01X1485569Y1344825D01*
X1483966D01*
X1483597Y1345194D01*
Y1349934D01*
X1484227Y1350564D01*
G37*
G36*
G01X1492589Y1578182D02*
G03I-574J0D01*
G37*
G36*
G01X1484789D02*
G03I-574J0D01*
G37*
G36*
G01X1480529D02*
G03I-574J0D01*
G37*
G36*
G01X1492589Y1590094D02*
G03I-574J0D01*
G37*
G36*
G01X1484789D02*
G03I-574J0D01*
G37*
G36*
G01X1480529D02*
G03I-574J0D01*
G37*
G36*
G01X1478029Y1602380D02*
G03I-574J0D01*
G37*
G36*
G01Y1614292D02*
G03I-574J0D01*
G37*
G36*
G01X1490089D02*
G03I-574J0D01*
G37*
G36*
G01Y1602380D02*
G03I-574J0D01*
G37*
G36*
G01X1485829D02*
G03I-574J0D01*
G37*
G36*
G01Y1614292D02*
G03I-574J0D01*
G37*
G36*
G01X1506378Y215822D02*
G03I-557J0D01*
G37*
G36*
G01X1505935Y225482D02*
G03I-557J0D01*
G37*
G36*
G01X1510128Y239033D02*
G03I-557J0D01*
G37*
G36*
G01X1508417Y249772D02*
G03I-557J0D01*
G37*
G36*
G01X1484300Y319962D02*
X1491100D01*
X1497266Y313796D01*
X1508952D01*
Y313236D01*
G03X1508982Y313008I890J1D01*
G03X1509407Y312040I1455J62D01*
G01X1510955Y310492D01*
G03X1511855Y310071I1030J1030D01*
G03X1512242Y310020I388J1451D01*
G01X1512244D01*
G03X1513522Y310732I0J1503D01*
G01X1513534Y310752D01*
X1514024Y311242D01*
X1514119Y311232D01*
G03X1514213Y311226I104J884D01*
G01X1515266D01*
Y311354D01*
X1515377Y311410D01*
G03X1515473Y311462I-645J1306D01*
G01X1516310D01*
Y313796D01*
X1536960D01*
X1538479Y312277D01*
Y281214D01*
X1536389Y279124D01*
X1517905D01*
G03X1515461I-1222J-687D01*
G01X1509875D01*
G02X1509491Y279636I0J400D01*
G03X1509551Y280056I-1442J420D01*
G03X1506547I-1502J0D01*
G03X1506607Y279636I1502J0D01*
G02X1506223Y279124I-384J-112D01*
G01X1496562D01*
X1496500Y279062D01*
X1495105D01*
G02X1494723Y279581I0J400D01*
G03X1494791Y280027I-1434J447D01*
G03X1493289Y281529I-1502J0D01*
G03X1491831Y280388I0J-1502D01*
G02X1491241Y280139I-388J97D01*
G01X1491158Y280056D01*
X1484504D01*
X1483804Y280756D01*
Y319466D01*
X1484300Y319962D01*
G37*
G36*
G01X1508909Y1578182D02*
G03I-574J0D01*
G37*
G36*
G01X1496849D02*
G03I-574J0D01*
G37*
G36*
G01X1504649D02*
G03I-574J0D01*
G37*
G36*
G01X1508909Y1590094D02*
G03I-574J0D01*
G37*
G36*
G01X1496849D02*
G03I-574J0D01*
G37*
G36*
G01X1504649D02*
G03I-574J0D01*
G37*
G36*
G01X1502149Y1614292D02*
G03I-574J0D01*
G37*
G36*
G01Y1602380D02*
G03I-574J0D01*
G37*
G36*
G01X1509949D02*
G03I-574J0D01*
G37*
G36*
G01Y1614292D02*
G03I-574J0D01*
G37*
G36*
G01X1497889Y1602380D02*
G03I-574J0D01*
G37*
G36*
G01Y1614292D02*
G03I-574J0D01*
G37*
G36*
G01X1525327Y195812D02*
G03I-557J0D01*
G37*
G36*
G01X1521758Y215571D02*
G03I-557J0D01*
G37*
G36*
G01X1513667Y247392D02*
G03I-557J0D01*
G37*
G36*
G01X1521348Y1366684D02*
X1525707D01*
X1526027Y1367004D01*
Y1370764D01*
X1525747Y1371044D01*
X1516807D01*
X1516387Y1370624D01*
Y1369314D01*
X1516797Y1368904D01*
X1518827D01*
X1518847Y1368885D01*
X1520407D01*
X1520997Y1368295D01*
Y1367035D01*
X1521348Y1366684D01*
G37*
G36*
G01X1520969Y1578182D02*
G03I-574J0D01*
G37*
G36*
G01X1516709D02*
G03I-574J0D01*
G37*
G36*
G01X1520969Y1590094D02*
G03I-574J0D01*
G37*
G36*
G01X1516709D02*
G03I-574J0D01*
G37*
G36*
G01X1526269Y1614292D02*
G03I-574J0D01*
G37*
G36*
G01Y1602380D02*
G03I-574J0D01*
G37*
G36*
G01X1522009D02*
G03I-574J0D01*
G37*
G36*
G01Y1614292D02*
G03I-574J0D01*
G37*
G36*
G01X1514209D02*
G03I-574J0D01*
G37*
G36*
G01Y1602380D02*
G03I-574J0D01*
G37*
G36*
G01X1532307Y199782D02*
G03I-557J0D01*
G37*
G36*
G01X1530167Y211634D02*
G03I-557J0D01*
G37*
G36*
G01X1533147Y225452D02*
G03I-557J0D01*
G37*
G36*
G01X1549449Y300477D02*
X1548569Y299597D01*
X1541009D01*
X1539989Y300617D01*
Y311387D01*
X1540819Y312217D01*
X1544500D01*
X1549449Y307268D01*
Y300477D01*
G37*
G36*
G01X1540829Y1578182D02*
G03I-574J0D01*
G37*
G36*
G01X1533029D02*
G03I-574J0D01*
G37*
G36*
G01X1528769D02*
G03I-574J0D01*
G37*
G36*
G01X1540829Y1590094D02*
G03I-574J0D01*
G37*
G36*
G01X1533029D02*
G03I-574J0D01*
G37*
G36*
G01X1528769D02*
G03I-574J0D01*
G37*
G36*
G01X1538329Y1614292D02*
G03I-574J0D01*
G37*
G36*
G01Y1602380D02*
G03I-574J0D01*
G37*
G36*
G01X1534069D02*
G03I-574J0D01*
G37*
G36*
G01Y1614292D02*
G03I-574J0D01*
G37*
G36*
G01X1548151Y37106D02*
G03I-722J0D01*
G37*
G36*
G01X1555237D02*
G03I-722J0D01*
G37*
G36*
G01Y40020D02*
G03I-722J0D01*
G37*
G36*
G01X1548151D02*
G03I-722J0D01*
G37*
G36*
G01X1551067Y677045D02*
G03I-650J0D01*
G37*
G36*
G01X1550707Y693485D02*
G03I-650J0D01*
G37*
G36*
G01X1549129Y706088D02*
G03I-650J0D01*
G37*
G36*
G01X1557149Y1578182D02*
G03I-574J0D01*
G37*
G36*
G01X1545089D02*
G03I-574J0D01*
G37*
G36*
G01X1552889D02*
G03I-574J0D01*
G37*
G36*
G01X1557149Y1590094D02*
G03I-574J0D01*
G37*
G36*
G01X1545089D02*
G03I-574J0D01*
G37*
G36*
G01X1552889D02*
G03I-574J0D01*
G37*
G36*
G01X1550389Y1614292D02*
G03I-574J0D01*
G37*
G36*
G01Y1602380D02*
G03I-574J0D01*
G37*
G36*
G01X1558189D02*
G03I-574J0D01*
G37*
G36*
G01Y1614292D02*
G03I-574J0D01*
G37*
G36*
G01X1546129Y1602380D02*
G03I-574J0D01*
G37*
G36*
G01Y1614292D02*
G03I-574J0D01*
G37*
G36*
G01X1562324Y37106D02*
G03I-722J0D01*
G37*
G36*
G01X1569410D02*
G03I-722J0D01*
G37*
G36*
G01Y40020D02*
G03I-722J0D01*
G37*
G36*
G01X1562324D02*
G03I-722J0D01*
G37*
G36*
G01X1580509Y620860D02*
X1610138D01*
G02X1610279Y620802I0J-200D01*
G01X1610818Y620262D01*
Y580380D01*
X1610200Y579762D01*
X1572000D01*
X1570648Y581114D01*
Y618760D01*
X1572748Y620860D01*
X1573491D01*
X1573550Y620803D01*
G03X1573900Y620660I351J359D01*
G01X1580100D01*
G03X1580450Y620803I-1J502D01*
G01X1580509Y620860D01*
G37*
G36*
G01X1566021Y654592D02*
X1604876D01*
X1604935Y654533D01*
X1605395Y654073D01*
G02X1605454Y653931I-141J-142D01*
G01Y622576D01*
X1605450Y622491D01*
X1605395Y622436D01*
X1604880Y621921D01*
X1604821Y621862D01*
X1580502D01*
Y627362D01*
G03X1580100Y627764I-402J0D01*
G01X1573900D01*
G03X1573498Y627362I0J-402D01*
G01Y621862D01*
X1568538D01*
X1568479Y621921D01*
X1565207Y625193D01*
X1565148Y625252D01*
Y653719D01*
X1565207Y653778D01*
X1566021Y654592D01*
G37*
G36*
G01X1574770Y728472D02*
X1602913D01*
X1604764Y726621D01*
X1604907Y726561D01*
X1605454Y726014D01*
Y656495D01*
X1604821Y655862D01*
X1573030D01*
X1570350Y658542D01*
Y724052D01*
X1574770Y728472D01*
G37*
G36*
G01X1569209Y1578182D02*
G03I-574J0D01*
G37*
G36*
G01X1564949D02*
G03I-574J0D01*
G37*
G36*
G01X1569209Y1590094D02*
G03I-574J0D01*
G37*
G36*
G01X1564949D02*
G03I-574J0D01*
G37*
G36*
G01X1574509Y1614292D02*
G03I-574J0D01*
G37*
G36*
G01Y1602380D02*
G03I-574J0D01*
G37*
G36*
G01X1570249Y1614292D02*
G03I-574J0D01*
G37*
G36*
G01Y1602380D02*
G03I-574J0D01*
G37*
G36*
G01X1562449Y1614292D02*
G03I-574J0D01*
G37*
G36*
G01Y1602380D02*
G03I-574J0D01*
G37*
G36*
G01X1576497Y37106D02*
G03I-722J0D01*
G37*
G36*
G01X1583584D02*
G03I-722J0D01*
G37*
G36*
G01X1590670D02*
G03I-722J0D01*
G37*
G36*
G01Y40020D02*
G03I-722J0D01*
G37*
G36*
G01X1583584D02*
G03I-722J0D01*
G37*
G36*
G01X1576497D02*
G03I-722J0D01*
G37*
G36*
G01X1589069Y1578182D02*
G03I-574J0D01*
G37*
G36*
G01X1581269D02*
G03I-574J0D01*
G37*
G36*
G01X1577009D02*
G03I-574J0D01*
G37*
G36*
G01X1589069Y1590094D02*
G03I-574J0D01*
G37*
G36*
G01X1581269D02*
G03I-574J0D01*
G37*
G36*
G01X1577009D02*
G03I-574J0D01*
G37*
G36*
G01X1586569Y1614292D02*
G03I-574J0D01*
G37*
G36*
G01Y1602380D02*
G03I-574J0D01*
G37*
G36*
G01X1582309D02*
G03I-574J0D01*
G37*
G36*
G01Y1614292D02*
G03I-574J0D01*
G37*
G36*
G01X1597757Y37106D02*
G03I-722J0D01*
G37*
G36*
G01X1604844D02*
G03I-722J0D01*
G37*
G36*
G01Y40020D02*
G03I-722J0D01*
G37*
G36*
G01X1597757D02*
G03I-722J0D01*
G37*
G36*
G01X1604597Y219712D02*
G03I-557J0D01*
G37*
G36*
G01X1604847Y242492D02*
G03I-557J0D01*
G37*
G36*
G01X1607300Y731662D02*
X1635900D01*
X1636514Y731048D01*
Y722072D01*
G02X1636573Y721930I-141J-142D01*
G01Y714344D01*
G03X1636632Y714202I200J0D01*
G01X1637118Y713716D01*
G03X1637260Y713657I142J141D01*
G01X1646594D01*
G02X1646736Y713598I0J-200D01*
G01X1646763Y713571D01*
G02X1646822Y713429I-141J-142D01*
G01Y706697D01*
G02X1646763Y706555I-200J0D01*
G01X1646671Y706463D01*
G02X1646529Y706404I-142J141D01*
G01X1638604D01*
G03X1638462Y706345I0J-200D01*
G01X1637476Y705359D01*
G03X1637417Y705217I141J-142D01*
G01Y696800D01*
G03X1637476Y696658I200J0D01*
G01X1637630Y696504D01*
G02X1637689Y696362I-141J-142D01*
G01Y689212D01*
G02X1637630Y689070I-200J0D01*
G01X1636632Y688072D01*
G03X1636573Y687930I141J-142D01*
G01Y680344D01*
G03X1636632Y680202I200J0D01*
G01X1637118Y679716D01*
G03X1637260Y679657I142J141D01*
G01X1646594D01*
G02X1646736Y679598I0J-200D01*
G01X1646763Y679571D01*
G02X1646822Y679429I-141J-142D01*
G01Y672697D01*
G02X1646763Y672555I-200J0D01*
G01X1646671Y672463D01*
G02X1646529Y672404I-142J141D01*
G01X1638604D01*
G03X1638462Y672345I0J-200D01*
G01X1637476Y671359D01*
G03X1637417Y671217I141J-142D01*
G01Y662800D01*
G03X1637476Y662658I200J0D01*
G01X1637630Y662504D01*
G02X1637689Y662362I-141J-142D01*
G01Y657230D01*
G02X1637630Y657088I-200J0D01*
G01X1636632Y656090D01*
G03X1636573Y655948I141J-142D01*
G01Y646344D01*
G03X1636632Y646202I200J0D01*
G01X1637118Y645716D01*
G03X1637260Y645657I142J141D01*
G01X1646594D01*
G02X1646736Y645598I0J-200D01*
G01X1646763Y645571D01*
G02X1646822Y645429I-141J-142D01*
G01Y638697D01*
G02X1646763Y638555I-200J0D01*
G01X1646671Y638463D01*
G02X1646529Y638404I-142J141D01*
G01X1638604D01*
G03X1638462Y638345I0J-200D01*
G01X1637476Y637359D01*
G03X1637417Y637217I141J-142D01*
G01Y621529D01*
X1637350Y621462D01*
X1638520Y620292D01*
X1646360D01*
X1648130Y618522D01*
Y610482D01*
X1648910Y609702D01*
X1653620D01*
X1655250Y608072D01*
Y601722D01*
X1654470Y600942D01*
X1647340D01*
X1646530Y600132D01*
Y586792D01*
X1648540Y584782D01*
X1681460D01*
X1682640Y583602D01*
Y577262D01*
X1679280Y573902D01*
X1614440D01*
X1611820Y576522D01*
Y621422D01*
X1610980Y622262D01*
X1606715D01*
X1606455Y622522D01*
Y622543D01*
G03X1606456Y622576I-1201J53D01*
G01Y653933D01*
G03X1606455Y653963I-1201J-25D01*
G01Y656080D01*
X1606456Y656081D01*
Y725858D01*
X1606480Y725882D01*
Y730842D01*
X1607300Y731662D01*
G37*
G36*
G01X1596200Y986262D02*
X1628900D01*
X1629414Y985748D01*
Y975554D01*
X1627514Y973654D01*
X1611085D01*
X1608525Y976213D01*
G03X1607637Y976582I-889J-887D01*
G01X1597287D01*
X1595614Y978255D01*
Y985676D01*
X1596200Y986262D01*
G37*
G36*
G01X1595816Y1015744D02*
X1619514D01*
X1620114Y1015144D01*
Y1012125D01*
X1621245Y1010993D01*
X1629669D01*
X1630700Y1009962D01*
Y989562D01*
X1629998Y988860D01*
X1622615D01*
G03X1621883Y989066I-732J-1196D01*
G03X1621151Y988860I0J-1402D01*
G01X1613915D01*
G03X1613183Y989066I-732J-1196D01*
G03X1612451Y988860I0J-1402D01*
G01X1595298D01*
X1594814Y989344D01*
Y1014742D01*
X1595816Y1015744D01*
G37*
G36*
G01X1591987Y1032245D02*
X1627377D01*
X1628214Y1031408D01*
Y1012844D01*
X1627365Y1011994D01*
X1621663D01*
X1621116Y1012542D01*
Y1015559D01*
X1620914Y1015760D01*
Y1016244D01*
X1620214Y1016944D01*
X1592178D01*
X1590867Y1018255D01*
Y1031125D01*
X1591987Y1032245D01*
G37*
G36*
G01X1598797Y1331055D02*
X1738887D01*
X1755707Y1314235D01*
X1759997D01*
X1762317Y1316555D01*
X1795547D01*
X1820154Y1291948D01*
G02X1819865Y1291265I-283J-283D01*
G03X1819812Y1291266I-94J-3600D01*
G01X1814912D01*
G03Y1284062I0J-3602D01*
G01X1819812D01*
G03X1822334Y1285093I-1J3602D01*
G02X1823014Y1284807I280J-286D01*
G01Y1261544D01*
X1821714Y1260244D01*
X1805816D01*
G03X1804948Y1260478I-875J-1517D01*
G02X1804613Y1261096I1J400D01*
G03X1804902Y1262074I-1513J979D01*
G03X1801298I-1802J0D01*
G03X1801730Y1260904I1802J1D01*
G02X1801426Y1260244I-304J-260D01*
G01X1792066D01*
X1789616Y1262693D01*
Y1263228D01*
X1789671Y1263286D01*
G03X1790162Y1264522I-1310J1236D01*
G03X1786558I-1802J0D01*
G03X1787104Y1263230I1802J0D01*
G01Y1262173D01*
G03X1787472Y1261285I1255J0D01*
G01X1787638Y1261118D01*
X1787472Y1260952D01*
X1787441Y1260938D01*
G03X1786677Y1260244I779J-1625D01*
G01X1776116D01*
G03X1775243Y1260478I-875J-1517D01*
G01X1775239D01*
G02X1774903Y1261096I0J400D01*
G03X1775192Y1262074I-1513J979D01*
G03X1771588I-1802J0D01*
G03X1772020Y1260904I1802J1D01*
G02X1771716Y1260244I-304J-260D01*
G01X1759361D01*
G03X1757017I-1172J-1370D01*
G01X1746416D01*
G03X1745556Y1260478I-875J-1517D01*
G02X1745223Y1261096I3J400D01*
G03X1745512Y1262074I-1513J979D01*
G03X1741908I-1802J0D01*
G03X1742340Y1260904I1802J1D01*
G02X1742036Y1260244I-304J-260D01*
G01X1729825D01*
G03X1727553I-1136J-1400D01*
G01X1717359D01*
X1717345Y1260246D01*
G03X1717098Y1260264I-251J-1734D01*
G01X1715621D01*
G02X1715314Y1260920I0J400D01*
G03X1715732Y1262074I-1384J1154D01*
G03X1712128I-1802J0D01*
G03X1712546Y1260920I1802J0D01*
G02X1712239Y1260264I-307J-256D01*
G01X1710561D01*
G03X1710314Y1260246I4J-1752D01*
G01X1710300Y1260244D01*
X1702793D01*
X1700351Y1262686D01*
G03X1700832Y1263912I-1322J1226D01*
G03X1697228I-1802J0D01*
G03X1697719Y1262676I1801J0D01*
G01X1697774Y1262618D01*
Y1262230D01*
G03X1698142Y1261342I1255J0D01*
G01X1698388Y1261095D01*
G02X1698284Y1260454I-283J-283D01*
G03X1697957Y1260244I805J-1612D01*
G01X1687016D01*
G03X1686141Y1260478I-875J-1517D01*
G03X1685266Y1260244I0J-1751D01*
G01X1684152D01*
G03X1681732I-1210J-1334D01*
G01X1671150D01*
G03X1667828I-1661J-699D01*
G01X1659183D01*
X1657942Y1261484D01*
G03X1656810Y1261954I-1133J-1131D01*
G01X1656767D01*
G02X1656374Y1262424I0J400D01*
G03X1656402Y1262742I-1774J316D01*
G03X1652798I-1802J0D01*
G03X1652862Y1262264I1802J-2D01*
G02X1652477Y1261758I-386J-106D01*
G01X1651177D01*
G03X1650289Y1261390I0J-1255D01*
G01X1649142Y1260244D01*
X1641251D01*
G03X1638127I-1562J-899D01*
G01X1627616D01*
G03X1626741Y1260478I-875J-1517D01*
G03X1625909Y1260268I-1J-1751D01*
G01X1625864Y1260244D01*
X1625562D01*
Y1260547D01*
X1625646Y1260607D01*
G03X1626402Y1262074I-1045J1467D01*
G03X1622798I-1802J0D01*
G03X1623230Y1260904I1802J1D01*
G02X1622926Y1260244I-304J-260D01*
G01X1612440D01*
G03X1610510I-965J-1017D01*
G01X1609953D01*
G02X1609598Y1260829I0J400D01*
G03X1609802Y1261662I-1599J833D01*
G03X1606198I-1802J0D01*
G03X1606362Y1260912I1802J1D01*
G02X1606088Y1260356I-364J-166D01*
G03X1605794Y1260260I395J-1706D01*
G01X1605756Y1260244D01*
X1595514D01*
X1594314Y1261444D01*
Y1326572D01*
X1598797Y1331055D01*
G37*
G36*
G01X1605389Y1578182D02*
G03I-574J0D01*
G37*
G36*
G01X1593329D02*
G03I-574J0D01*
G37*
G36*
G01X1601129D02*
G03I-574J0D01*
G37*
G36*
G01X1605389Y1590094D02*
G03I-574J0D01*
G37*
G36*
G01X1593329D02*
G03I-574J0D01*
G37*
G36*
G01X1601129D02*
G03I-574J0D01*
G37*
G36*
G01X1598629Y1614292D02*
G03I-574J0D01*
G37*
G36*
G01Y1602380D02*
G03I-574J0D01*
G37*
G36*
G01X1606429Y1614292D02*
G03I-574J0D01*
G37*
G36*
G01Y1602380D02*
G03I-574J0D01*
G37*
G36*
G01X1594369Y1614292D02*
G03I-574J0D01*
G37*
G36*
G01Y1602380D02*
G03I-574J0D01*
G37*
G36*
G01X1700040Y1450115D02*
X1715297D01*
X1715320Y1450092D01*
X1725827D01*
X1725901Y1450062D01*
X1725929Y1450033D01*
X1728831Y1447131D01*
G02X1728890Y1446989I-141J-142D01*
G01Y1342535D01*
X1728860Y1342461D01*
X1728831Y1342433D01*
X1726700Y1340302D01*
G02X1726558Y1340243I-142J141D01*
G01X1621072D01*
X1620998Y1340273D01*
X1620970Y1340302D01*
X1612309Y1348963D01*
G02X1612250Y1349105I141J142D01*
G01Y1402369D01*
X1612280Y1402443D01*
X1612309Y1402471D01*
X1618381Y1408543D01*
G03X1618440Y1408685I-141J142D01*
G01Y1423729D01*
X1618470Y1423803D01*
X1618499Y1423831D01*
X1620141Y1425473D01*
G02X1620283Y1425532I142J-141D01*
G01X1623924D01*
X1623958Y1425519D01*
X1629999D01*
G03X1630141Y1425578I0J200D01*
G01X1631324Y1426761D01*
G03X1631383Y1426903I-141J142D01*
G01Y1434043D01*
G02X1631442Y1434185I200J0D01*
G01X1631788Y1434531D01*
G02X1631930Y1434590I142J-141D01*
G01X1638261D01*
X1638368Y1434545D01*
G02X1638431Y1434502I-79J-184D01*
G01X1638567Y1434366D01*
G02X1638626Y1434224I-141J-142D01*
G01Y1425868D01*
G03X1638685Y1425726I200J0D01*
G01X1638965Y1425446D01*
G03X1639107Y1425387I142J141D01*
G01X1656789D01*
G03X1656931Y1425446I0J200D01*
G01X1657737Y1426252D01*
G03X1657796Y1426394I-141J142D01*
G01Y1434698D01*
G03X1657737Y1434840I-200J0D01*
G01X1656425Y1436152D01*
X1656396Y1436180D01*
X1656366Y1436254D01*
Y1445798D01*
G02X1656425Y1445940I200J0D01*
G01X1658987Y1448502D01*
G02X1659129Y1448561I142J-141D01*
G01X1661043D01*
G02X1661185Y1448502I0J-200D01*
G01X1661687Y1448000D01*
G02X1661746Y1447858I-141J-142D01*
G01Y1447054D01*
G02X1661687Y1446912I-200J0D01*
G01X1660605Y1445830D01*
G03X1660546Y1445688I141J-142D01*
G01Y1426318D01*
G03X1660605Y1426176I200J0D01*
G01X1661078Y1425703D01*
X1661337Y1425443D01*
G03X1661479Y1425384I142J141D01*
G01X1666936D01*
G03X1667078Y1425443I0J200D01*
G01X1668587Y1426952D01*
G03X1668646Y1427094I-141J142D01*
G01Y1433828D01*
G02X1668705Y1433970I200J0D01*
G01X1669264Y1434529D01*
G02X1669406Y1434588I142J-141D01*
G01X1676171D01*
G02X1676313Y1434529I0J-200D01*
G01X1676747Y1434095D01*
G02X1676806Y1433953I-141J-142D01*
G01Y1426474D01*
G03X1676865Y1426332I200J0D01*
G01X1677751Y1425446D01*
G03X1677893Y1425387I142J141D01*
G01X1697016D01*
G03X1697158Y1425446I0J200D01*
G01X1698478Y1426766D01*
G03X1698537Y1426908I-141J142D01*
G01Y1448612D01*
G02X1698596Y1448754I200J0D01*
G01X1699898Y1450056D01*
G02X1700040Y1450115I142J-141D01*
G37*
G36*
G01X1644127Y1457085D02*
X1643027Y1455984D01*
X1628996D01*
X1614188D01*
X1612305Y1457867D01*
Y1490377D01*
X1616440Y1494512D01*
X1642260D01*
X1644127Y1492645D01*
Y1469613D01*
Y1457085D01*
G37*
G36*
G01X1617449Y1578182D02*
G03I-574J0D01*
G37*
G36*
G01X1613189D02*
G03I-574J0D01*
G37*
G36*
G01X1617449Y1590094D02*
G03I-574J0D01*
G37*
G36*
G01X1613189D02*
G03I-574J0D01*
G37*
G36*
G01X1622749Y1614292D02*
G03I-574J0D01*
G37*
G36*
G01Y1602380D02*
G03I-574J0D01*
G37*
G36*
G01X1618489Y1614292D02*
G03I-574J0D01*
G37*
G36*
G01Y1602380D02*
G03I-574J0D01*
G37*
G36*
G01X1610689Y1614292D02*
G03I-574J0D01*
G37*
G36*
G01Y1602380D02*
G03I-574J0D01*
G37*
G36*
G01X1626536Y37106D02*
G03I-722J0D01*
G37*
G36*
G01X1633623D02*
G03I-722J0D01*
G37*
G36*
G01X1640710D02*
G03I-722J0D01*
G37*
G36*
G01X1626536Y40020D02*
G03I-722J0D01*
G37*
G36*
G01X1633623D02*
G03I-722J0D01*
G37*
G36*
G01X1640710D02*
G03I-722J0D01*
G37*
G36*
G01X1693604Y437126D02*
G03X1692716Y436758I0J-1255D01*
G01X1691372Y435414D01*
G03X1691330Y435371I877J-899D01*
G02X1691060Y435347I-148J135D01*
G03X1690140Y435662I-920J-1186D01*
G03X1688638Y434160I0J-1502D01*
G03X1689301Y432914I1502J0D01*
G02X1689447Y432429I-223J-332D01*
G03X1689302Y431843I1112J-586D01*
G01Y431292D01*
G03X1689074Y430699I662J-595D01*
G01Y429646D01*
X1689310D01*
Y427578D01*
X1689074D01*
Y426525D01*
G03X1689220Y426038I890J2D01*
G01X1689253Y425928D01*
X1689204Y425797D01*
G03X1688894Y424971I947J-827D01*
G01Y423668D01*
G03X1688944Y423320I1257J3D01*
G01X1688952Y423293D01*
Y423149D01*
X1688897Y423091D01*
G03X1688406Y421855I1310J-1236D01*
G03X1692010I1802J0D01*
G03X1691519Y423091I-1801J0D01*
G01X1691464Y423149D01*
Y423612D01*
G03X1691415Y423959I-1256J0D01*
G01X1691408Y423986D01*
Y424452D01*
G03X1691816Y425378I-849J927D01*
G01Y425930D01*
G03X1692046Y426525I-660J597D01*
G01Y427578D01*
X1691810D01*
Y429646D01*
X1692046D01*
Y430699D01*
G03X1691902Y431184I-890J-1D01*
G01X1691818Y431312D01*
Y431324D01*
X1693148Y432655D01*
G03X1693516Y433543I-887J888D01*
G01Y434006D01*
X1694124Y434614D01*
X1715378D01*
X1720420Y429572D01*
Y382392D01*
X1719350Y381322D01*
G02X1718679Y381510I-283J283D01*
G03X1717220Y382654I-1459J-358D01*
G03X1715718Y381152I0J-1502D01*
G03X1716862Y379693I1502J0D01*
G02X1717050Y379022I-95J-388D01*
G01X1714990Y376962D01*
X1658256D01*
X1651976Y383241D01*
Y399394D01*
X1656180Y403597D01*
G03X1656606Y404625I-1030J1029D01*
G01Y433139D01*
G03X1656180Y434167I-1456J-1D01*
G01X1655891Y434455D01*
X1655880Y434516D01*
G03X1654110Y435979I-1770J-339D01*
G03X1652308Y434177I0J-1802D01*
G03X1653555Y432463I1801J0D01*
G01X1653694Y432418D01*
Y405230D01*
X1649490Y401027D01*
G03X1649064Y399999I1030J-1029D01*
G01Y382636D01*
G03X1649490Y381608I1456J1D01*
G01X1653453Y377645D01*
G02X1653171Y376962I-282J-283D01*
G01X1646090D01*
X1632020Y391032D01*
Y438392D01*
X1635410Y441782D01*
X1708210D01*
X1712183Y437809D01*
G02X1711900Y437126I-283J-283D01*
G01X1693604D01*
G37*
G36*
G01X1639421Y705111D02*
X1649855D01*
X1653180Y701786D01*
Y697837D01*
G03X1653239Y697695I200J0D01*
G01X1654058Y696876D01*
G03X1654200Y696817I142J141D01*
G01X1682802D01*
X1689600Y690019D01*
Y687162D01*
Y637202D01*
X1694100Y632702D01*
X1698250Y628552D01*
Y590012D01*
X1695894Y587656D01*
X1649086D01*
X1648430Y588312D01*
Y599152D01*
X1649190Y599912D01*
X1670627D01*
G03X1670769Y599971I0J200D01*
G01X1672991Y602193D01*
G03X1673050Y602335I-141J142D01*
G01Y619482D01*
X1670050Y622482D01*
X1639457D01*
X1639377Y622562D01*
X1639294D01*
X1638689Y623167D01*
Y636379D01*
X1639421Y637111D01*
X1649855D01*
X1653180Y633786D01*
Y629837D01*
G03X1653239Y629695I200J0D01*
G01X1654058Y628876D01*
G03X1654200Y628817I142J141D01*
G01X1659722D01*
G03X1659864Y628876I0J200D01*
G01X1662831Y631843D01*
G03X1662890Y631985I-141J142D01*
G01Y652429D01*
G03X1662831Y652571I-200J0D01*
G01X1659599Y655803D01*
G03X1659457Y655862I-142J-141D01*
G01X1655581D01*
X1654588Y656855D01*
X1639001D01*
X1638689Y657167D01*
Y670379D01*
X1639421Y671111D01*
X1649855D01*
X1653180Y667786D01*
Y663837D01*
G03X1653239Y663695I200J0D01*
G01X1654058Y662876D01*
G03X1654200Y662817I142J141D01*
G01X1660992D01*
G03X1661134Y662876I0J200D01*
G01X1662831Y664573D01*
G03X1662890Y664715I-141J142D01*
G01Y685759D01*
G03X1662831Y685901I-200J0D01*
G01X1658929Y689803D01*
G03X1658787Y689862I-142J-141D01*
G01X1653866D01*
X1653293Y690435D01*
X1652702Y691026D01*
X1639714D01*
X1638689Y692051D01*
Y704379D01*
X1639421Y705111D01*
G37*
G36*
G01X1638549Y1444733D02*
X1638066Y1444250D01*
X1636900D01*
X1635877Y1445273D01*
X1626870D01*
X1626217Y1445926D01*
Y1448256D01*
X1626516Y1448555D01*
X1629271D01*
X1638003D01*
X1638978Y1447580D01*
Y1445162D01*
X1638549Y1444733D01*
G37*
G36*
G01X1637309Y1578088D02*
G03I-574J0D01*
G37*
G36*
G01X1629509Y1578182D02*
G03I-574J0D01*
G37*
G36*
G01X1625249D02*
G03I-574J0D01*
G37*
G36*
G01X1637309Y1590094D02*
G03I-574J0D01*
G37*
G36*
G01X1629509D02*
G03I-574J0D01*
G37*
G36*
G01X1625249D02*
G03I-574J0D01*
G37*
G36*
G01X1634809Y1614292D02*
G03I-574J0D01*
G37*
G36*
G01Y1602380D02*
G03I-574J0D01*
G37*
G36*
G01X1630549Y1614292D02*
G03I-574J0D01*
G37*
G36*
G01Y1602380D02*
G03I-574J0D01*
G37*
G36*
G01X1654883Y37106D02*
G03I-722J0D01*
G37*
G36*
G01X1647796D02*
G03I-722J0D01*
G37*
G36*
G01Y40020D02*
G03I-722J0D01*
G37*
G36*
G01X1654883D02*
G03I-722J0D01*
G37*
G36*
G01X1654969Y640451D02*
X1659809D01*
X1660439Y639821D01*
Y630719D01*
X1659469Y629749D01*
X1654775D01*
X1654600Y629924D01*
Y636399D01*
G02X1654801Y636599I200J0D01*
G01X1654809D01*
G03Y639603I0J1502D01*
G01X1654801D01*
G02X1654600Y639803I-1J200D01*
G01Y640082D01*
X1654969Y640451D01*
G37*
G36*
G01Y674451D02*
X1659809D01*
X1660439Y673821D01*
Y664719D01*
X1659469Y663749D01*
X1654775D01*
X1654600Y663924D01*
Y670399D01*
G02X1654801Y670599I200J0D01*
G01X1654809D01*
G03Y673603I0J1502D01*
G01X1654801D01*
G02X1654600Y673803I-1J200D01*
G01Y674082D01*
X1654969Y674451D01*
G37*
G36*
G01Y708451D02*
X1659809D01*
X1660439Y707821D01*
Y698719D01*
X1659469Y697749D01*
X1654775D01*
X1654600Y697924D01*
Y704399D01*
G02X1654801Y704599I200J0D01*
G01X1654809D01*
G03Y707603I0J1502D01*
G01X1654801D01*
G02X1654600Y707803I-1J200D01*
G01Y708082D01*
X1654969Y708451D01*
G37*
G36*
G01X1652577Y1477115D02*
X1688897D01*
X1696827Y1469185D01*
Y1427108D01*
X1696117Y1426398D01*
X1678019D01*
X1677872Y1426545D01*
Y1434466D01*
X1681708Y1438302D01*
Y1446906D01*
X1679047Y1449567D01*
X1658279D01*
X1655138Y1446426D01*
Y1434131D01*
X1656646Y1432623D01*
Y1427461D01*
X1655583Y1426398D01*
X1640409D01*
X1639576Y1427231D01*
Y1435694D01*
X1643807Y1439925D01*
Y1447465D01*
X1650167Y1453825D01*
Y1474705D01*
X1652577Y1477115D01*
G37*
G36*
G01X1641569Y1578182D02*
G03I-574J0D01*
G37*
G36*
G01X1649369D02*
G03I-574J0D01*
G37*
G36*
G01X1641569Y1590094D02*
G03I-574J0D01*
G37*
G36*
G01X1649369D02*
G03I-574J0D01*
G37*
G36*
G01X1646869Y1614292D02*
G03I-574J0D01*
G37*
G36*
G01Y1602380D02*
G03I-574J0D01*
G37*
G36*
G01X1654669Y1614292D02*
G03I-574J0D01*
G37*
G36*
G01Y1602380D02*
G03I-574J0D01*
G37*
G36*
G01X1642609Y1614292D02*
G03I-574J0D01*
G37*
G36*
G01Y1602380D02*
G03I-574J0D01*
G37*
G36*
G01X1670670Y37106D02*
G03I-722J0D01*
G37*
G36*
G01Y40020D02*
G03I-722J0D01*
G37*
G36*
G01X1668904Y544365D02*
X1683104D01*
X1683304Y544165D01*
Y525965D01*
X1683104Y525765D01*
X1668904D01*
X1668704Y525965D01*
Y544165D01*
X1668904Y544365D01*
G37*
G36*
G01X1676692Y1444708D02*
X1676209Y1444225D01*
X1675043D01*
X1674020Y1445248D01*
X1669870D01*
X1668818Y1446300D01*
X1665010D01*
X1664360Y1446950D01*
Y1448231D01*
X1664659Y1448530D01*
X1667414D01*
X1676146D01*
X1677121Y1447555D01*
Y1445137D01*
X1676692Y1444708D01*
G37*
G36*
G01X1677757Y37106D02*
G03I-722J0D01*
G37*
G36*
G01X1684844D02*
G03I-722J0D01*
G37*
G36*
G01X1677757Y40020D02*
G03I-722J0D01*
G37*
G36*
G01X1684844D02*
G03I-722J0D01*
G37*
G36*
G01X1679200Y732362D02*
X1701200D01*
X1702200Y731362D01*
Y717162D01*
X1696374Y711336D01*
X1696298Y711332D01*
G03X1694603Y709637I104J-1799D01*
G01X1694599Y709561D01*
X1693300Y708262D01*
X1679200D01*
X1678400Y709062D01*
Y731562D01*
X1679200Y732362D01*
G37*
G36*
G01X1691930Y37106D02*
G03I-722J0D01*
G37*
G36*
G01X1698546Y39974D02*
G03I-722J0D01*
G37*
G36*
G01X1691930Y40020D02*
G03I-722J0D01*
G37*
G36*
G01X1701496Y455894D02*
G03I-650J0D01*
G37*
G36*
G01X1693698Y492329D02*
X1697573D01*
X1698520Y491382D01*
X1709944D01*
X1709967Y491359D01*
X1712703D01*
X1713090Y490972D01*
Y484452D01*
X1710058Y481420D01*
Y477074D01*
X1710059Y477073D01*
Y474854D01*
X1709417Y474212D01*
X1696076D01*
X1695605Y474683D01*
Y477142D01*
X1695566Y477182D01*
Y480172D01*
X1695970D01*
Y482672D01*
X1695566D01*
Y488162D01*
X1693320Y490408D01*
Y491951D01*
X1693698Y492329D01*
G37*
G36*
G01X1694504Y515607D02*
G03I-803J0D01*
G37*
G36*
G01X1697654D02*
G03I-803J0D01*
G37*
G36*
G01X1706437Y657221D02*
Y638941D01*
X1705858Y638361D01*
X1700220D01*
X1697510D01*
X1697018Y638853D01*
Y657823D01*
X1697430Y658235D01*
X1698615Y659420D01*
X1705350D01*
X1706437Y658333D01*
Y657221D01*
G37*
G36*
G01X1712540Y1559099D02*
X1831896D01*
X1831955Y1559040D01*
X1838771Y1552223D01*
Y1449833D01*
X1836400Y1447462D01*
X1747200D01*
X1746200Y1448462D01*
Y1462228D01*
G03Y1464296I-1088J1034D01*
G01Y1468210D01*
X1739450Y1474960D01*
X1712980D01*
X1712920Y1474900D01*
X1705340D01*
X1703357Y1476883D01*
Y1492402D01*
X1703327Y1492476D01*
Y1499242D01*
G02X1703936Y1499582I400J-1D01*
G03X1704723Y1499360I786J1280D01*
G03Y1502364I0J1502D01*
G03X1703936Y1502142I-1J-1502D01*
G02X1703327Y1502482I-209J341D01*
G01Y1518742D01*
G02X1703936Y1519082I400J-1D01*
G03X1704723Y1518860I786J1280D01*
G03Y1521864I0J1502D01*
G03X1703936Y1521642I-1J-1502D01*
G02X1703327Y1521982I-209J341D01*
G01Y1539742D01*
G02X1703936Y1540082I400J-1D01*
G03X1704723Y1539860I786J1280D01*
G03Y1542864I0J1502D01*
G03X1703936Y1542642I-1J-1502D01*
G02X1703327Y1542982I-209J341D01*
G01Y1549886D01*
X1703386Y1549945D01*
X1712540Y1559099D01*
G37*
G36*
G01X1715920Y38662D02*
X1715220Y39362D01*
Y53632D01*
X1727620Y66032D01*
Y68862D01*
X1722320Y74162D01*
Y84162D01*
X1723020Y84862D01*
X1731420D01*
X1733120Y83162D01*
Y57602D01*
X1731700Y56182D01*
X1725070D01*
X1720040Y51152D01*
Y39302D01*
X1719400Y38662D01*
X1715920D01*
G37*
G36*
G01X1707920Y53062D02*
X1708620Y53762D01*
X1713320D01*
X1713920Y53162D01*
Y39062D01*
X1713520Y38662D01*
X1709420D01*
X1707920Y40162D01*
Y53062D01*
G37*
G36*
G01X1755691Y102102D02*
X1758490D01*
X1765278Y95314D01*
G02X1765265Y94736I-283J-283D01*
G03X1764776Y93627I1013J-1109D01*
G03X1765530Y92325I1501J0D01*
G01Y91284D01*
X1761770D01*
G03X1760478Y91829I-1291J-1257D01*
G03X1758676Y90027I0J-1802D01*
G03X1758880Y89193I1802J-1D01*
G02X1758536Y88609I-354J-185D01*
G03X1757071Y87107I37J-1502D01*
G03X1760075I1502J0D01*
G03X1759962Y87678I-1502J-1D01*
G02X1760359Y88229I370J152D01*
G03X1760478Y88225I120J1798D01*
G03X1761770Y88770I1J1802D01*
G01X1765530D01*
Y84355D01*
X1765514Y84317D01*
G03X1765368Y83607I1656J-711D01*
G03X1765514Y82897I1802J1D01*
G01X1765530Y82859D01*
Y82298D01*
G02X1765117Y81898I-400J0D01*
G03X1765068Y81899I-55J-1501D01*
G03Y78895I0J-1502D01*
G03X1765117Y78896I-6J1502D01*
G02X1765530Y78496I13J-400D01*
G01Y68652D01*
X1766550Y67632D01*
X1774890D01*
X1777700Y70442D01*
Y74082D01*
X1779310Y75692D01*
X1781690D01*
X1782790Y74592D01*
Y70522D01*
X1789280Y64032D01*
Y56152D01*
X1788220Y55092D01*
X1783137D01*
G03X1780411I-1363J-629D01*
G01X1779293D01*
G03X1776710Y56564I-2583J-1530D01*
G03X1774777Y55859I0J-3002D01*
G02X1774223Y55897I-257J306D01*
G03X1771774Y56984I-2449J-2215D01*
G03X1768788Y55092I0J-3302D01*
G01X1762790D01*
X1762431Y54733D01*
X1762377Y54720D01*
G03X1761280Y53623I361J-1458D01*
G01X1761267Y53569D01*
X1761020Y53322D01*
X1753320D01*
X1752200Y52202D01*
Y49626D01*
G03Y47814I1198J-906D01*
G01Y45542D01*
X1745110Y38452D01*
X1741346D01*
X1741302Y38475D01*
G03X1740719Y38618I-582J-1113D01*
G01X1723524D01*
X1721420Y40722D01*
Y50572D01*
X1725020Y54172D01*
X1732320D01*
X1734110Y55962D01*
Y57176D01*
X1734122Y57187D01*
Y83577D01*
X1734110Y83588D01*
Y92632D01*
X1743580Y102102D01*
X1753105D01*
G02X1753377Y101409I0J-400D01*
G03X1752896Y100307I1022J-1102D01*
G03X1755900I1502J0D01*
G03X1755419Y101409I-1503J0D01*
G02X1755691Y102102I272J293D01*
G37*
G36*
G01X1736900Y199262D02*
X1815700D01*
X1817900Y197062D01*
Y187862D01*
X1816100Y186062D01*
X1745147D01*
X1735700Y195509D01*
Y198062D01*
X1736900Y199262D01*
G37*
G36*
G01X1739683Y200362D02*
X1735400Y204645D01*
Y227462D01*
X1736800Y228862D01*
X1816400D01*
X1818586Y226676D01*
Y201648D01*
X1817300Y200362D01*
X1739683D01*
G37*
G36*
G01X1776098Y297692D02*
X1775273Y296867D01*
Y294127D01*
X1776050Y293350D01*
X1778670D01*
X1780950Y295630D01*
Y303212D01*
X1795400Y317662D01*
X1837700D01*
X1851360Y304002D01*
Y239260D01*
X1850390Y238290D01*
X1821920D01*
X1820500Y236870D01*
Y231362D01*
X1819356Y230218D01*
X1736644D01*
X1735500Y231362D01*
Y297462D01*
X1736800Y298762D01*
X1744131D01*
G03X1745000Y298460I869J1099D01*
G03X1745819Y298724I0J1402D01*
G01X1745872Y298762D01*
X1746283D01*
X1746447Y298598D01*
X1766107D01*
X1768354Y300845D01*
X1775655D01*
X1776330Y300170D01*
Y300034D01*
G03X1776098Y299307I1024J-727D01*
G01Y297692D01*
G37*
G36*
G01X1730100Y1450662D02*
X1728500Y1452262D01*
Y1465762D01*
X1730200Y1467462D01*
X1740700D01*
X1741900Y1466262D01*
Y1452162D01*
X1740400Y1450662D01*
X1730100D01*
G37*
G36*
G01X1758400Y691282D02*
X1740339D01*
X1738956Y692665D01*
Y723992D01*
X1739015Y724051D01*
X1742112Y727148D01*
X1758112D01*
X1758171Y727089D01*
X1759053Y726207D01*
X1759112Y726148D01*
Y691994D01*
X1758400Y691282D01*
G37*
G36*
G01X1761612Y727148D02*
X1772522D01*
X1774122Y725548D01*
Y694250D01*
X1771194Y691322D01*
X1760980D01*
X1760114Y692188D01*
Y725650D01*
X1761612Y727148D01*
G37*
G36*
G01X1756147Y1355565D02*
X1787827D01*
X1789467Y1353925D01*
Y1324715D01*
X1787372Y1322620D01*
X1761442D01*
X1759837Y1324225D01*
X1755987D01*
X1754937Y1325275D01*
Y1354355D01*
X1756147Y1355565D01*
G37*
G36*
G01X1776779Y1714960D02*
G02I-9850J0D01*
G37*
G36*
G01X1789398Y109967D02*
X1812078D01*
Y97053D01*
G03X1809819Y87795I17843J-9258D01*
G03X1812078Y78537I20102J0D01*
G01Y54711D01*
X1798498D01*
X1795804Y52017D01*
X1790864D01*
X1790365Y52516D01*
Y75243D01*
X1789235Y76373D01*
G02X1789249Y76951I283J282D01*
G03X1789740Y78062I-1011J1111D01*
G03X1788238Y79564I-1502J0D01*
G03X1786737Y78119I0J-1502D01*
G01X1786730Y77927D01*
X1775178D01*
X1774178Y78927D01*
Y86577D01*
X1774301Y86628D01*
G03Y89958I-691J1665D01*
G01X1774178Y90009D01*
Y92552D01*
X1774201Y92595D01*
G03X1774346Y93182I-1111J586D01*
G01Y94916D01*
X1776664Y97233D01*
G02X1777289Y97155I282J-283D01*
G03X1778578Y96425I1289J773D01*
G03X1780080Y97927I0J1502D01*
G03X1779350Y99216I-1503J0D01*
G02X1779272Y99841I205J343D01*
G01X1789398Y109967D01*
G37*
G36*
G01X1822412Y222764D02*
Y234764D01*
X1822612Y234964D01*
X1841887D01*
X1847698D01*
X1848700Y233962D01*
Y220462D01*
X1847700Y219462D01*
X1823000D01*
X1822412Y220050D01*
Y222764D01*
G37*
%LPC*%
G75*
G36*
G01X191070Y1283712D02*
X186170D01*
G02Y1291616I0J3952D01*
G01X191070D01*
G02Y1283712I0J-3952D01*
G37*
G36*
G01X131670D02*
X126770D01*
G02Y1291616I0J3952D01*
G01X131670D01*
G02Y1283712I0J-3952D01*
G37*
G36*
G01X72270D02*
X67370D01*
G02Y1291616I0J3952D01*
G01X72270D01*
G02Y1283712I0J-3952D01*
G37*
G36*
G01X161370D02*
X156470D01*
G02Y1291616I0J3952D01*
G01X161370D01*
G02Y1283712I0J-3952D01*
G37*
G36*
G01X101970D02*
X97070D01*
G02Y1291616I0J3952D01*
G01X101970D01*
G02Y1283712I0J-3952D01*
G37*
G36*
G01X42570D02*
X37670D01*
G02Y1291616I0J3952D01*
G01X42570D01*
G02Y1283712I0J-3952D01*
G37*
G36*
G01X245570Y1291266D02*
X250470D01*
G02Y1284062I0J-3602D01*
G01X245570D01*
G02Y1291266I0J3602D01*
G37*
G36*
G01X215870D02*
X220770D01*
G02Y1284062I0J-3602D01*
G01X215870D01*
G02Y1291266I0J3602D01*
G37*
G36*
G01X260448Y1267549D02*
X259361Y1266462D01*
X252531D01*
X251444Y1267549D01*
Y1273379D01*
X253531Y1275466D01*
X258361D01*
X260448Y1273379D01*
Y1267549D01*
G37*
G36*
G01X230748D02*
X229661Y1266462D01*
X222831D01*
X221744Y1267549D01*
Y1273379D01*
X223831Y1275466D01*
X228661D01*
X230748Y1273379D01*
Y1267549D01*
G37*
G36*
G01X204236Y1267927D02*
Y1274236D01*
X205466Y1275466D01*
X212661D01*
X214748Y1273379D01*
Y1267549D01*
X213661Y1266462D01*
X205701D01*
X204236Y1267927D01*
G37*
G36*
G01X190316Y1267501D02*
Y1274085D01*
X191696Y1275466D01*
X198961D01*
X201048Y1273379D01*
Y1267549D01*
X199961Y1266462D01*
X191354D01*
X190316Y1267501D01*
G37*
G36*
G01X185048Y1267549D02*
X183961Y1266462D01*
X177131D01*
X176044Y1267549D01*
Y1273379D01*
X178131Y1275466D01*
X182961D01*
X185048Y1273379D01*
Y1267549D01*
G37*
G36*
G01X171348D02*
X170261Y1266462D01*
X163431D01*
X162344Y1267549D01*
Y1273379D01*
X164431Y1275466D01*
X169261D01*
X171348Y1273379D01*
Y1267549D01*
G37*
G36*
G01X155348D02*
X154261Y1266462D01*
X147431D01*
X146344Y1267549D01*
Y1273379D01*
X148431Y1275466D01*
X153261D01*
X155348Y1273379D01*
Y1267549D01*
G37*
G36*
G01X141648D02*
X140561Y1266462D01*
X133731D01*
X132644Y1267549D01*
Y1273379D01*
X134731Y1275466D01*
X139561D01*
X141648Y1273379D01*
Y1267549D01*
G37*
G36*
G01X125648D02*
X124561Y1266462D01*
X117731D01*
X116644Y1267549D01*
Y1273379D01*
X118731Y1275466D01*
X123561D01*
X125648Y1273379D01*
Y1267549D01*
G37*
G36*
G01X111948D02*
X110861Y1266462D01*
X104031D01*
X102944Y1267549D01*
Y1273379D01*
X105031Y1275466D01*
X109861D01*
X111948Y1273379D01*
Y1267549D01*
G37*
G36*
G01X95948D02*
X94861Y1266462D01*
X88031D01*
X86944Y1267549D01*
Y1273379D01*
X89031Y1275466D01*
X93861D01*
X95948Y1273379D01*
Y1267549D01*
G37*
G36*
G01X82248D02*
X81161Y1266462D01*
X74331D01*
X73244Y1267549D01*
Y1273379D01*
X75331Y1275466D01*
X80161D01*
X82248Y1273379D01*
Y1267549D01*
G37*
G36*
G01X66248D02*
X65161Y1266462D01*
X58331D01*
X57244Y1267549D01*
Y1273379D01*
X59331Y1275466D01*
X64161D01*
X66248Y1273379D01*
Y1267549D01*
G37*
G36*
G01X52548D02*
X51461Y1266462D01*
X44631D01*
X43544Y1267549D01*
Y1273379D01*
X45631Y1275466D01*
X50461D01*
X52548Y1273379D01*
Y1267549D01*
G37*
G36*
G01X36548D02*
X35461Y1266462D01*
X28631D01*
X27544Y1267549D01*
Y1273379D01*
X29631Y1275466D01*
X34461D01*
X36548Y1273379D01*
Y1267549D01*
G37*
G36*
G01X239824Y1275466D02*
X242361D01*
X244448Y1273379D01*
Y1267549D01*
X243361Y1266462D01*
X236531D01*
X235444Y1267549D01*
Y1273379D01*
X237531Y1275466D01*
X238118D01*
G02X239824I853J-1114D01*
G37*
G36*
G01X180346Y1325552D02*
Y1331752D01*
G02X180747Y1332154I401J1D01*
G01X186947D01*
G02X187348Y1331752I-1J-402D01*
G01Y1325552D01*
G02X186947Y1325150I-401J-1D01*
G01X180747D01*
G02X180346Y1325552I1J402D01*
G37*
G36*
G01X155972Y1325527D02*
Y1331727D01*
G02X156374Y1332128I402J-1D01*
G01X162574D01*
G02X162976Y1331727I1J-401D01*
G01Y1325527D01*
G02X162574Y1325126I-402J1D01*
G01X156374D01*
G02X155972Y1325527I-1J401D01*
G37*
G36*
G01X204746Y1325552D02*
Y1331752D01*
G02X205147Y1332154I401J1D01*
G01X211347D01*
G02X211748Y1331752I-1J-402D01*
G01Y1325552D01*
G02X211347Y1325150I-401J-1D01*
G01X205147D01*
G02X204746Y1325552I1J402D01*
G37*
G36*
G01X171205Y637765D02*
X171214Y637835D01*
G02X178156I3471J-468D01*
G01X178165Y637765D01*
G02X178188Y637367I-3479J-401D01*
G02X171182I-3503J0D01*
G02X171205Y637765I3502J-3D01*
G37*
G36*
G01X202800Y1432622D02*
Y1432624D01*
G02X205159Y1433537I2359J-2591D01*
G02Y1426531I0J-3503D01*
G02X202800Y1427444I0J3504D01*
G01Y1427446D01*
G02Y1432622I2358J2588D01*
G37*
G36*
G01X245570Y1004454D02*
X250470D01*
G02Y997252I0J-3601D01*
G01X245570D01*
G02Y1004454I0J3601D01*
G37*
G36*
G01X271788Y580476D02*
Y586676D01*
G02X272189Y587078I401J1D01*
G01X278389D01*
G02X278790Y586676I-1J-402D01*
G01Y580476D01*
G02X278389Y580074I-401J-1D01*
G01X272189D01*
G02X271788Y580476I1J402D01*
G37*
G36*
G01Y604635D02*
Y610835D01*
G02X272189Y611236I401J0D01*
G01X278389D01*
G02X278790Y610835I0J-401D01*
G01Y604635D01*
G02X278389Y604234I-401J0D01*
G01X272189D01*
G02X271788Y604635I0J401D01*
G37*
G36*
G01Y628789D02*
Y634989D01*
G02X272189Y635390I401J0D01*
G01X278389D01*
G02X278790Y634989I0J-401D01*
G01Y628789D01*
G02X278389Y628388I-401J0D01*
G01X272189D01*
G02X271788Y628789I0J401D01*
G37*
G36*
G01Y652943D02*
Y659143D01*
G02X272189Y659544I401J0D01*
G01X278389D01*
G02X278790Y659143I0J-401D01*
G01Y652943D01*
G02X278389Y652542I-401J0D01*
G01X272189D01*
G02X271788Y652943I0J401D01*
G37*
G36*
G01X433118Y1239685D02*
Y1245885D01*
G02X433519Y1246286I401J0D01*
G01X439719D01*
G02X440120Y1245885I0J-401D01*
G01Y1239685D01*
G02X439719Y1239284I-401J0D01*
G01X433519D01*
G02X433118Y1239685I0J401D01*
G37*
G36*
G01X457518D02*
Y1245885D01*
G02X457919Y1246286I401J0D01*
G01X464119D01*
G02X464520Y1245885I0J-401D01*
G01Y1239685D01*
G02X464119Y1239284I-401J0D01*
G01X457919D01*
G02X457518Y1239685I0J401D01*
G37*
G36*
G01X481918D02*
Y1245885D01*
G02X482319Y1246286I401J0D01*
G01X488519D01*
G02X488920Y1245885I0J-401D01*
G01Y1239685D01*
G02X488519Y1239284I-401J0D01*
G01X482319D01*
G02X481918Y1239685I0J401D01*
G37*
G36*
G01X408796D02*
Y1245885D01*
G02X409197Y1246286I401J0D01*
G01X415397D01*
G02X415798Y1245885I0J-401D01*
G01Y1239685D01*
G02X415397Y1239284I-401J0D01*
G01X409197D01*
G02X408796Y1239685I0J401D01*
G37*
G36*
G01X384396D02*
Y1245885D01*
G02X384797Y1246286I401J0D01*
G01X390997D01*
G02X391398Y1245885I0J-401D01*
G01Y1239685D01*
G02X390997Y1239284I-401J0D01*
G01X384797D01*
G02X384396Y1239685I0J401D01*
G37*
G36*
G01X485360Y1152256D02*
X484234Y1151130D01*
X480424D01*
X479228Y1152326D01*
Y1171575D01*
X480395Y1172742D01*
X484223D01*
X485360Y1171605D01*
Y1152256D01*
G37*
G36*
G01X454228Y1170593D02*
X455885Y1172250D01*
X463744D01*
X465380Y1170614D01*
Y1152487D01*
X463814Y1150920D01*
X455644D01*
X454228Y1152337D01*
Y1170593D01*
G37*
G36*
G01X430794Y1172192D02*
X438664D01*
X440328Y1170527D01*
Y1152407D01*
X438782Y1150862D01*
X430769D01*
X429188Y1152443D01*
Y1170585D01*
X430794Y1172192D01*
G37*
G36*
G01X415382Y1170553D02*
Y1152233D01*
X414009Y1150862D01*
X405997D01*
X404240Y1152618D01*
Y1170448D01*
X405984Y1172192D01*
X413744D01*
X415382Y1170553D01*
G37*
G36*
G01X429414Y1079791D02*
G02X432008I1297J0D01*
G02X430953Y1078516I-1298J0D01*
G01X430863Y1078499D01*
X430056Y1077101D01*
X430086Y1077015D01*
G02X430158Y1076587I-1225J-426D01*
G02X427564I-1297J0D01*
G02X428620Y1077862I1298J0D01*
G01X428710Y1077879D01*
X429517Y1079276D01*
X429486Y1079363D01*
G02X429414Y1079791I1225J426D01*
G37*
G36*
G01X425714Y1086200D02*
G02X428310I1298J0D01*
G02X427254Y1084925I-1298J0D01*
G01X427164Y1084908D01*
X426356Y1083510D01*
X426387Y1083423D01*
G02X426460Y1082995I-1225J-429D01*
G02X423864I-1298J0D01*
G02X424920Y1084270I1298J0D01*
G01X425010Y1084287D01*
X425818Y1085685D01*
X425787Y1085772D01*
G02X425714Y1086200I1225J429D01*
G37*
G36*
G01X427564Y1089404D02*
G02X430158I1297J0D01*
G02X430086Y1088976I-1297J-2D01*
G01X430055Y1088889D01*
X430862Y1087492D01*
X430952Y1087475D01*
G02X432008Y1086200I-242J-1275D01*
G02X429412I-1298J0D01*
G02X429485Y1086629I1297J0D01*
G01X429516Y1086715D01*
X428709Y1088112D01*
X428619Y1088129D01*
G02X427564Y1089404I243J1275D01*
G37*
G36*
G01X418314Y1092608D02*
G02X420908I1297J0D01*
G02X420836Y1092180I-1297J-2D01*
G01X420805Y1092093D01*
X421612Y1090696D01*
X421702Y1090679D01*
G02X422760Y1089404I-239J-1275D01*
G02X420164I-1298J0D01*
G02X420237Y1089831I1298J-2D01*
G01X420267Y1089917D01*
X419459Y1091316D01*
X419369Y1091333D01*
G02X418314Y1092608I243J1275D01*
G37*
G36*
G01X427011Y1093906D02*
G02X428050Y1093386I0J-1298D01*
G01X429672D01*
G02X430711Y1093906I1039J-778D01*
G02Y1091310I0J-1298D01*
G02X429672Y1091830I0J1298D01*
G01X428050D01*
G02X427011Y1091310I-1039J778D01*
G02Y1093906I0J1298D01*
G37*
G36*
G01X423864Y1095813D02*
G02X426460I1298J0D01*
G02X425404Y1094538I-1298J0D01*
G01X425314Y1094521D01*
X424506Y1093122D01*
X424536Y1093035D01*
G02X424608Y1092610I-1225J-426D01*
G01Y1092608D01*
G02X422014I-1297J0D01*
G02X423070Y1093883I1298J0D01*
G01X423161Y1093900D01*
X423968Y1095298D01*
X423937Y1095385D01*
G02X423864Y1095813I1225J429D01*
G37*
G36*
G01X415911Y1106724D02*
G02X416950Y1106204I0J-1298D01*
G01X418572D01*
G02X419611Y1106724I1039J-778D01*
G02Y1104128I0J-1298D01*
G02X418572Y1104648I0J1298D01*
G01X416950D01*
G02X415911Y1104128I-1039J778D01*
G02Y1106724I0J1298D01*
G37*
G36*
G01X418314Y1111834D02*
G02X420908I1297J0D01*
G02X419853Y1110559I-1298J0D01*
G01X419763Y1110542D01*
X418956Y1109145D01*
X418987Y1109059D01*
G02X419060Y1108630I-1224J-429D01*
G02X416464I-1298J0D01*
G02X417520Y1109905I1298J0D01*
G01X417610Y1109922D01*
X418417Y1111319D01*
X418386Y1111406D01*
G02X418314Y1111834I1225J426D01*
G37*
G36*
G01X470114Y1124651D02*
G02X472708I1297J0D01*
G02X471653Y1123376I-1298J0D01*
G01X471563Y1123359D01*
X470756Y1121962D01*
X470787Y1121875D01*
G02X470860Y1121447I-1225J-429D01*
G02X468264I-1298J0D01*
G02X469320Y1122722I1298J0D01*
G01X469410Y1122739D01*
X470217Y1124136D01*
X470186Y1124223D01*
G02X470114Y1124651I1225J426D01*
G37*
G36*
G01X477514D02*
G02X480108I1297J0D01*
G02X479053Y1123376I-1298J0D01*
G01X478963Y1123359D01*
X478156Y1121962D01*
X478187Y1121875D01*
G02X478260Y1121447I-1225J-429D01*
G02X475664I-1298J0D01*
G02X476720Y1122722I1298J0D01*
G01X476810Y1122739D01*
X477617Y1124136D01*
X477586Y1124223D01*
G02X477514Y1124651I1225J426D01*
G37*
G36*
G01X484914D02*
G02X487508I1297J0D01*
G02X486453Y1123376I-1298J0D01*
G01X486363Y1123359D01*
X485556Y1121962D01*
X485587Y1121875D01*
G02X485660Y1121447I-1225J-429D01*
G02X483064I-1298J0D01*
G02X484120Y1122722I1298J0D01*
G01X484210Y1122739D01*
X485017Y1124136D01*
X484986Y1124223D01*
G02X484914Y1124651I1225J426D01*
G37*
G36*
G01X492314D02*
G02X494908I1297J0D01*
G02X493853Y1123376I-1298J0D01*
G01X493763Y1123359D01*
X492956Y1121962D01*
X492987Y1121875D01*
G02X493060Y1121447I-1225J-429D01*
G02X490464I-1298J0D01*
G02X491520Y1122722I1298J0D01*
G01X491610Y1122739D01*
X492417Y1124136D01*
X492386Y1124223D01*
G02X492314Y1124651I1225J426D01*
G37*
G36*
G01X499714D02*
G02X502308I1297J0D01*
G02X501253Y1123376I-1298J0D01*
G01X501163Y1123359D01*
X500356Y1121962D01*
X500387Y1121875D01*
G02X500460Y1121447I-1225J-429D01*
G02X497864I-1298J0D01*
G02X498920Y1122722I1298J0D01*
G01X499010Y1122739D01*
X499817Y1124136D01*
X499786Y1124223D01*
G02X499714Y1124651I1225J426D01*
G37*
G36*
G01X507114D02*
G02X509708I1297J0D01*
G02X508653Y1123376I-1298J0D01*
G01X508563Y1123359D01*
X507756Y1121962D01*
X507787Y1121875D01*
G02X507860Y1121447I-1225J-429D01*
G02X505264I-1298J0D01*
G02X506320Y1122722I1298J0D01*
G01X506410Y1122739D01*
X507217Y1124136D01*
X507186Y1124223D01*
G02X507114Y1124651I1225J426D01*
G37*
G36*
G01X514514D02*
G02X517108I1297J0D01*
G02X516053Y1123376I-1298J0D01*
G01X515963Y1123359D01*
X515156Y1121962D01*
X515187Y1121875D01*
G02X515260Y1121447I-1225J-429D01*
G02X512664I-1298J0D01*
G02X513720Y1122722I1298J0D01*
G01X513810Y1122739D01*
X514617Y1124136D01*
X514586Y1124223D01*
G02X514514Y1124651I1225J426D01*
G37*
G36*
G01X521914D02*
G02X524508I1297J0D01*
G02X523453Y1123376I-1298J0D01*
G01X523363Y1123359D01*
X522556Y1121962D01*
X522587Y1121875D01*
G02X522660Y1121447I-1225J-429D01*
G02X520064I-1298J0D01*
G02X521120Y1122722I1298J0D01*
G01X521210Y1122739D01*
X522017Y1124136D01*
X521986Y1124223D01*
G02X521914Y1124651I1225J426D01*
G37*
G36*
G01X471964Y1127856D02*
G02X474560I1298J0D01*
G02X474487Y1127427I-1297J0D01*
G01X474456Y1127341D01*
X475263Y1125943D01*
X475353Y1125926D01*
G02X476408Y1124651I-243J-1275D01*
G02X473814I-1297J0D01*
G02X473886Y1125080I1297J3D01*
G01X473917Y1125166D01*
X473110Y1126564D01*
X473020Y1126581D01*
G02X471964Y1127856I242J1275D01*
G37*
G36*
G01X479364D02*
G02X481960I1298J0D01*
G02X481887Y1127427I-1297J0D01*
G01X481856Y1127341D01*
X482663Y1125943D01*
X482753Y1125926D01*
G02X483808Y1124651I-243J-1275D01*
G02X481214I-1297J0D01*
G02X481286Y1125080I1297J3D01*
G01X481317Y1125166D01*
X480510Y1126564D01*
X480420Y1126581D01*
G02X479364Y1127856I242J1275D01*
G37*
G36*
G01X486764D02*
G02X489360I1298J0D01*
G02X489287Y1127427I-1297J0D01*
G01X489256Y1127341D01*
X490063Y1125943D01*
X490153Y1125926D01*
G02X491208Y1124651I-243J-1275D01*
G02X488614I-1297J0D01*
G02X488686Y1125080I1297J3D01*
G01X488717Y1125166D01*
X487910Y1126564D01*
X487820Y1126581D01*
G02X486764Y1127856I242J1275D01*
G37*
G36*
G01X494164D02*
G02X496760I1298J0D01*
G02X496687Y1127427I-1297J0D01*
G01X496656Y1127341D01*
X497463Y1125943D01*
X497553Y1125926D01*
G02X498608Y1124651I-243J-1275D01*
G02X496014I-1297J0D01*
G02X496086Y1125080I1297J3D01*
G01X496117Y1125166D01*
X495310Y1126564D01*
X495220Y1126581D01*
G02X494164Y1127856I242J1275D01*
G37*
G36*
G01X501564D02*
G02X504160I1298J0D01*
G02X504087Y1127427I-1297J0D01*
G01X504056Y1127341D01*
X504863Y1125943D01*
X504953Y1125926D01*
G02X506008Y1124651I-243J-1275D01*
G02X503414I-1297J0D01*
G02X503486Y1125080I1297J3D01*
G01X503517Y1125166D01*
X502710Y1126564D01*
X502620Y1126581D01*
G02X501564Y1127856I242J1275D01*
G37*
G36*
G01X508964D02*
G02X511560I1298J0D01*
G02X511487Y1127427I-1297J0D01*
G01X511456Y1127341D01*
X512263Y1125943D01*
X512353Y1125926D01*
G02X513408Y1124651I-243J-1275D01*
G02X510814I-1297J0D01*
G02X510886Y1125080I1297J3D01*
G01X510917Y1125166D01*
X510110Y1126564D01*
X510020Y1126581D01*
G02X508964Y1127856I242J1275D01*
G37*
G36*
G01X516364D02*
G02X518960I1298J0D01*
G02X518887Y1127427I-1297J0D01*
G01X518856Y1127341D01*
X519663Y1125943D01*
X519753Y1125926D01*
G02X520808Y1124651I-243J-1275D01*
G02X518214I-1297J0D01*
G02X518286Y1125080I1297J3D01*
G01X518317Y1125166D01*
X517510Y1126564D01*
X517420Y1126581D01*
G02X516364Y1127856I242J1275D01*
G37*
G36*
G01X523764D02*
G02X526360I1298J0D01*
G02X526287Y1127427I-1297J0D01*
G01X526256Y1127341D01*
X527063Y1125943D01*
X527153Y1125926D01*
G02X528208Y1124651I-243J-1275D01*
G02X525614I-1297J0D01*
G02X525686Y1125080I1297J3D01*
G01X525717Y1125166D01*
X524910Y1126564D01*
X524820Y1126581D01*
G02X523764Y1127856I242J1275D01*
G37*
G36*
G01X477514Y1137469D02*
G02X480110I1298J0D01*
G02X479054Y1136194I-1298J0D01*
G01X478964Y1136177D01*
X478156Y1134779D01*
X478187Y1134692D01*
G02X478260Y1134264I-1225J-429D01*
G02X475664I-1298J0D01*
G02X476720Y1135539I1298J0D01*
G01X476810Y1135556D01*
X477618Y1136954D01*
X477587Y1137041D01*
G02X477514Y1137469I1225J429D01*
G37*
G36*
G01X484914D02*
G02X487510I1298J0D01*
G02X486454Y1136194I-1298J0D01*
G01X486364Y1136177D01*
X485557Y1134779D01*
X485587Y1134692D01*
G02X485660Y1134264I-1225J-429D01*
G02X483064I-1298J0D01*
G02X484121Y1135539I1297J0D01*
G01X484211Y1135556D01*
X485018Y1136954D01*
X484987Y1137041D01*
G02X484914Y1137469I1225J429D01*
G37*
G36*
G01X492314D02*
G02X494910I1298J0D01*
G02X493854Y1136194I-1298J0D01*
G01X493764Y1136177D01*
X492957Y1134779D01*
X492987Y1134692D01*
G02X493060Y1134264I-1225J-429D01*
G02X490464I-1298J0D01*
G02X491521Y1135539I1297J0D01*
G01X491611Y1135556D01*
X492418Y1136954D01*
X492387Y1137041D01*
G02X492314Y1137469I1225J429D01*
G37*
G36*
G01X499714D02*
G02X502310I1298J0D01*
G02X501254Y1136194I-1298J0D01*
G01X501164Y1136177D01*
X500357Y1134779D01*
X500387Y1134692D01*
G02X500460Y1134264I-1225J-429D01*
G02X497864I-1298J0D01*
G02X498921Y1135539I1297J0D01*
G01X499011Y1135556D01*
X499818Y1136954D01*
X499787Y1137041D01*
G02X499714Y1137469I1225J429D01*
G37*
G36*
G01X507114D02*
G02X509710I1298J0D01*
G02X508654Y1136194I-1298J0D01*
G01X508564Y1136177D01*
X507757Y1134779D01*
X507787Y1134692D01*
G02X507860Y1134264I-1225J-429D01*
G02X505264I-1298J0D01*
G02X506321Y1135539I1297J0D01*
G01X506411Y1135556D01*
X507218Y1136954D01*
X507187Y1137041D01*
G02X507114Y1137469I1225J429D01*
G37*
G36*
G01X514514D02*
G02X517110I1298J0D01*
G02X516054Y1136194I-1298J0D01*
G01X515964Y1136177D01*
X515157Y1134779D01*
X515187Y1134692D01*
G02X515260Y1134264I-1225J-429D01*
G02X512664I-1298J0D01*
G02X513721Y1135539I1297J0D01*
G01X513811Y1135556D01*
X514618Y1136954D01*
X514587Y1137041D01*
G02X514514Y1137469I1225J429D01*
G37*
G36*
G01X521914D02*
G02X524510I1298J0D01*
G02X523454Y1136194I-1298J0D01*
G01X523364Y1136177D01*
X522557Y1134779D01*
X522587Y1134692D01*
G02X522660Y1134264I-1225J-429D01*
G02X520064I-1298J0D01*
G02X521121Y1135539I1297J0D01*
G01X521211Y1135556D01*
X522018Y1136954D01*
X521987Y1137041D01*
G02X521914Y1137469I1225J429D01*
G37*
G36*
G01X533014D02*
G02X535610I1298J0D01*
G02X534554Y1136194I-1298J0D01*
G01X534464Y1136177D01*
X533656Y1134779D01*
X533687Y1134692D01*
G02X533760Y1134264I-1225J-429D01*
G02X531164I-1298J0D01*
G02X532220Y1135539I1298J0D01*
G01X532310Y1135556D01*
X533118Y1136954D01*
X533087Y1137041D01*
G02X533014Y1137469I1225J429D01*
G37*
G36*
G01X471964Y1140973D02*
G02X474558I1297J0D01*
G02X474447Y1140448I-1297J0D01*
G01X474408Y1140359D01*
X475252Y1138763D01*
X475347Y1138745D01*
G02X476410Y1137469I-234J-1276D01*
G02X473814I-1298J0D01*
G02X473926Y1137994I1297J-2D01*
G01X473965Y1138083D01*
X473121Y1139679D01*
X473026Y1139697D01*
G02X471964Y1140973I236J1276D01*
G37*
G36*
G01X479364D02*
G02X481958I1297J0D01*
G02X481847Y1140448I-1297J0D01*
G01X481808Y1140359D01*
X482652Y1138763D01*
X482747Y1138745D01*
G02X483810Y1137469I-234J-1276D01*
G02X481214I-1298J0D01*
G02X481326Y1137994I1297J-2D01*
G01X481365Y1138083D01*
X480521Y1139679D01*
X480426Y1139697D01*
G02X479364Y1140973I236J1276D01*
G37*
G36*
G01X486764D02*
G02X489358I1297J0D01*
G02X489247Y1140448I-1297J0D01*
G01X489208Y1140359D01*
X490052Y1138763D01*
X490147Y1138745D01*
G02X491210Y1137469I-234J-1276D01*
G02X488614I-1298J0D01*
G02X488726Y1137994I1297J-2D01*
G01X488765Y1138083D01*
X487921Y1139679D01*
X487826Y1139697D01*
G02X486764Y1140973I236J1276D01*
G37*
G36*
G01X494164D02*
G02X496758I1297J0D01*
G02X496647Y1140448I-1297J0D01*
G01X496608Y1140359D01*
X497452Y1138763D01*
X497547Y1138745D01*
G02X498610Y1137469I-234J-1276D01*
G02X496014I-1298J0D01*
G02X496126Y1137994I1297J-2D01*
G01X496165Y1138083D01*
X495321Y1139679D01*
X495226Y1139697D01*
G02X494164Y1140973I236J1276D01*
G37*
G36*
G01X501564D02*
G02X504158I1297J0D01*
G02X504047Y1140448I-1297J0D01*
G01X504008Y1140359D01*
X504852Y1138763D01*
X504947Y1138745D01*
G02X506010Y1137469I-234J-1276D01*
G02X503414I-1298J0D01*
G02X503526Y1137994I1297J-2D01*
G01X503565Y1138083D01*
X502721Y1139679D01*
X502626Y1139697D01*
G02X501564Y1140973I236J1276D01*
G37*
G36*
G01X508964D02*
G02X511558I1297J0D01*
G02X511447Y1140448I-1297J0D01*
G01X511408Y1140359D01*
X512252Y1138763D01*
X512347Y1138745D01*
G02X513410Y1137469I-234J-1276D01*
G02X510814I-1298J0D01*
G02X510926Y1137994I1297J-2D01*
G01X510965Y1138083D01*
X510121Y1139679D01*
X510026Y1139697D01*
G02X508964Y1140973I236J1276D01*
G37*
G36*
G01X516364D02*
G02X518958I1297J0D01*
G02X518847Y1140448I-1297J0D01*
G01X518808Y1140359D01*
X519652Y1138763D01*
X519747Y1138745D01*
G02X520810Y1137469I-234J-1276D01*
G02X518214I-1298J0D01*
G02X518326Y1137994I1297J-2D01*
G01X518365Y1138083D01*
X517521Y1139679D01*
X517426Y1139697D01*
G02X516364Y1140973I236J1276D01*
G37*
G36*
G01X523764D02*
G02X526358I1297J0D01*
G02X526247Y1140448I-1297J0D01*
G01X526208Y1140359D01*
X527052Y1138763D01*
X527147Y1138745D01*
G02X528210Y1137469I-234J-1276D01*
G02X525614I-1298J0D01*
G02X525726Y1137994I1297J-2D01*
G01X525765Y1138083D01*
X524921Y1139679D01*
X524826Y1139697D01*
G02X523764Y1140973I236J1276D01*
G37*
G36*
G01X469298Y1356962D02*
G02X469700Y1357364I402J0D01*
G01X475700D01*
G02X476102Y1356962I0J-402D01*
G01Y1350962D01*
G02X475700Y1350560I-402J0D01*
G01X469700D01*
G02X469298Y1350962I0J402D01*
G01Y1356962D01*
G37*
G36*
G01X482543Y1350460D02*
G02Y1357464I0J3502D01*
G01X482544D01*
G02X482953Y1357440I0J-3502D01*
G03X482979Y1357438I44J397D01*
G02Y1350486I-436J-3476D01*
G03X482953Y1350484I18J-399D01*
G02X482544Y1350460I-409J3478D01*
G01X482543D01*
G37*
G36*
G01X379822Y1357446D02*
G02X380224Y1357848I402J0D01*
G01X386224D01*
G02X386626Y1357446I0J-402D01*
G01Y1351446D01*
G02X386224Y1351044I-402J0D01*
G01X380224D01*
G02X379822Y1351446I0J402D01*
G01Y1357446D01*
G37*
G36*
G01X409588D02*
G02X409990Y1357848I402J0D01*
G01X415990D01*
G02X416392Y1357446I0J-402D01*
G01Y1351446D01*
G02X415990Y1351044I-402J0D01*
G01X409990D01*
G02X409588Y1351446I0J402D01*
G01Y1357446D01*
G37*
G36*
G01X439924D02*
G02X440326Y1357848I402J0D01*
G01X446326D01*
G02X446728Y1357446I0J-402D01*
G01Y1351446D01*
G02X446326Y1351044I-402J0D01*
G01X440326D01*
G02X439924Y1351446I0J402D01*
G01Y1357446D01*
G37*
G36*
G01X455198Y1382662D02*
G02X455600Y1383064I402J0D01*
G01X461600D01*
G02X462002Y1382662I0J-402D01*
G01Y1376662D01*
G02X461600Y1376260I-402J0D01*
G01X455600D01*
G02X455198Y1376662I0J402D01*
G01Y1382662D01*
G37*
G36*
G01X468443Y1376160D02*
G02Y1383164I0J3502D01*
G02X471097Y1381947I0J-3502D01*
G03X471114Y1381929I299J265D01*
G02X471946Y1379662I-2671J-2267D01*
G02X471115Y1377397I-3502J0D01*
G03X471097Y1377377I288J-277D01*
G02X468443Y1376160I-2654J2285D01*
G37*
G36*
G01X350350Y1112612D02*
X351974D01*
G02X353012Y1113132I1038J-776D01*
G02Y1110536I0J-1298D01*
G02X351974Y1111056I0J1296D01*
G01X350350D01*
G02X349312Y1110536I-1038J776D01*
G02Y1113132I0J1298D01*
G02X350350Y1112612I0J-1296D01*
G37*
G36*
G01X337399Y1122224D02*
X339023D01*
G02X340061Y1122744I1038J-776D01*
G02Y1120150I0J-1297D01*
G02X339023Y1120670I0J1296D01*
G01X337399D01*
G02X336361Y1120150I-1038J776D01*
G02Y1122744I0J1297D01*
G02X337399Y1122224I0J-1296D01*
G37*
G36*
G01X359217Y1112348D02*
X358409Y1113747D01*
X358319Y1113764D01*
G02X357264Y1115039I243J1275D01*
G02X359858I1297J0D01*
G01Y1115037D01*
G02X359786Y1114610I-1298J-1D01*
G01X359756Y1114524D01*
X360563Y1113126D01*
X360653Y1113109D01*
G02X361710Y1111834I-240J-1275D01*
G02X359114I-1298J0D01*
G02X359187Y1112262I1299J-1D01*
G01X359217Y1112348D01*
G37*
G36*
G01X346266Y1121961D02*
X345459Y1123359D01*
X345369Y1123376D01*
G02X344314Y1124651I243J1275D01*
G02X346908I1297J0D01*
G02X346836Y1124223I-1298J-2D01*
G01X346806Y1124137D01*
X347613Y1122739D01*
X347703Y1122722D01*
G02X348758Y1121447I-243J-1275D01*
G02X346164I-1297J0D01*
G02X346236Y1121875I1298J2D01*
G01X346266Y1121961D01*
G37*
G36*
G01X363959Y1106718D02*
X364766Y1108116D01*
X364736Y1108202D01*
G02X364664Y1108630I1226J426D01*
G02X367258I1297J0D01*
G02X366203Y1107355I-1298J0D01*
G01X366113Y1107338D01*
X365306Y1105941D01*
X365336Y1105855D01*
G02X365409Y1105426I-1224J-429D01*
G02X364112Y1104128I-1297J-1D01*
G02X362814Y1105426I0J1298D01*
G02X363869Y1106701I1298J0D01*
G01X363959Y1106718D01*
G37*
G36*
G01X342949Y1106204D02*
X344573D01*
G02X345611Y1106724I1038J-776D01*
G02Y1104128I0J-1298D01*
G02X344573Y1104648I0J1296D01*
G01X342949D01*
G02X341911Y1104128I-1038J776D01*
G02Y1106724I0J1298D01*
G02X342949Y1106204I0J-1296D01*
G37*
G36*
G01X342567Y1109144D02*
X341760Y1110542D01*
X341670Y1110559D01*
G02X340614Y1111834I242J1275D01*
G02X343210I1298J0D01*
G02X343137Y1111406I-1299J1D01*
G01X343107Y1111320D01*
X343914Y1109922D01*
X344004Y1109905D01*
G02X345060Y1108630I-242J-1275D01*
G02X342464I-1298J0D01*
G02X342537Y1109058I1299J-1D01*
G01X342567Y1109144D01*
G37*
G36*
G01X344799Y1128634D02*
X346423D01*
G02X347461Y1129154I1038J-776D01*
G02Y1126558I0J-1298D01*
G02X346423Y1127078I0J1296D01*
G01X344799D01*
G02X343761Y1126558I-1038J776D01*
G02Y1129154I0J1298D01*
G02X344799Y1128634I0J-1296D01*
G37*
G36*
G01X351817Y1105941D02*
X351010Y1107338D01*
X350920Y1107355D01*
G02X349864Y1108630I242J1275D01*
G02X352460I1298J0D01*
G01Y1108628D01*
G02X352387Y1108201I-1298J2D01*
G01X352357Y1108115D01*
X353164Y1106718D01*
X353254Y1106701D01*
G02X354308Y1105426I-244J-1275D01*
G02X353011Y1104128I-1297J-1D01*
G02X351714Y1105426I1J1298D01*
G02X351787Y1105855I1297J0D01*
G01X351817Y1105941D01*
G37*
G36*
G01X352200Y1101444D02*
G02X351161Y1100924I-1039J778D01*
G02Y1103518I0J1297D01*
G02X352200Y1102998I0J-1298D01*
G01X353822D01*
G02X354861Y1103518I1039J-778D01*
G02Y1100924I0J-1297D01*
G02X353822Y1101444I0J1298D01*
G01X352200D01*
G37*
G36*
G01X400961Y1100309D02*
X401768Y1101706D01*
X401737Y1101793D01*
G02X401664Y1102221I1225J429D01*
G02X404260I1298J0D01*
G02X403204Y1100946I-1298J0D01*
G01X403114Y1100929D01*
X402306Y1099530D01*
X402336Y1099444D01*
G02X402408Y1099017I-1225J-426D01*
G02X399814I-1297J0D01*
G02X400871Y1100292I1297J0D01*
G01X400961Y1100309D01*
G37*
G36*
G01X376250Y1104648D02*
G02X375211Y1104128I-1039J778D01*
G02Y1106724I0J1298D01*
G02X376250Y1106204I0J-1298D01*
G01X377873D01*
G02X378912Y1106724I1039J-778D01*
G02Y1104128I0J-1298D01*
G02X377873Y1104648I0J1298D01*
G01X376250D01*
G37*
G36*
G01X380609Y1103513D02*
X381417Y1104911D01*
X381386Y1104998D01*
G02X381314Y1105426I1225J426D01*
G02X383908I1297J0D01*
G02X382853Y1104151I-1298J0D01*
G01X382763Y1104134D01*
X381956Y1102737D01*
X381986Y1102650D01*
G02X382060Y1102221I-1223J-432D01*
G02X379464I-1298J0D01*
G02X380519Y1103496I1298J0D01*
G01X380609Y1103513D01*
G37*
G36*
G01X359600Y1107852D02*
G02X358561Y1107332I-1039J778D01*
G02Y1109928I0J1298D01*
G02X359600Y1109408I0J-1298D01*
G01X361222D01*
G02X362261Y1109928I1039J-778D01*
G02Y1107332I0J-1298D01*
G02X361222Y1107852I0J1298D01*
G01X359600D01*
G37*
G36*
G01X385117Y1105941D02*
X384310Y1107338D01*
X384220Y1107355D01*
G02X383164Y1108630I242J1275D01*
G02X385760I1298J0D01*
G02X385687Y1108202I-1298J1D01*
G01X385656Y1108115D01*
X386463Y1106718D01*
X386553Y1106701D01*
G02X387608Y1105426I-243J-1275D01*
G02X385014I-1297J0D01*
G02X385086Y1105855I1297J3D01*
G01X385117Y1105941D01*
G37*
G36*
G01X392901Y1107852D02*
G02X391862Y1107332I-1039J778D01*
G02Y1109928I0J1298D01*
G02X392901Y1109408I0J-1298D01*
G01X394523D01*
G02X395562Y1109928I1039J-778D01*
G02Y1107332I0J-1298D01*
G02X394523Y1107852I0J1298D01*
G01X392901D01*
G37*
G36*
G01X397261Y1106718D02*
X398068Y1108115D01*
X398037Y1108202D01*
G02X397964Y1108630I1225J429D01*
G02X400560I1298J0D01*
G02X399504Y1107355I-1298J0D01*
G01X399414Y1107338D01*
X398606Y1105939D01*
X398636Y1105853D01*
G02X398708Y1105426I-1225J-426D01*
G02X396114I-1297J0D01*
G02X397171Y1106701I1297J0D01*
G01X397261Y1106718D01*
G37*
G36*
G01X368467Y1109145D02*
X367660Y1110542D01*
X367570Y1110559D01*
G02X366514Y1111834I242J1275D01*
G02X369110I1298J0D01*
G02X369037Y1111406I-1298J1D01*
G01X369006Y1111319D01*
X369813Y1109922D01*
X369903Y1109905D01*
G02X370958Y1108630I-243J-1275D01*
G02X368364I-1297J0D01*
G02X368436Y1109059I1297J3D01*
G01X368467Y1109145D01*
G37*
G36*
G01X375867Y1109143D02*
X375059Y1110542D01*
X374969Y1110559D01*
G02X373914Y1111834I243J1275D01*
G02X376508I1297J0D01*
G02X376436Y1111406I-1297J-2D01*
G01X376405Y1111319D01*
X377212Y1109922D01*
X377302Y1109905D01*
G02X378360Y1108630I-239J-1275D01*
G02X375764I-1298J0D01*
G02X375837Y1109057I1298J-2D01*
G01X375867Y1109143D01*
G37*
G36*
G01X383650Y1111056D02*
G02X382611Y1110536I-1039J778D01*
G02Y1113132I0J1298D01*
G02X383650Y1112612I0J-1298D01*
G01X385272D01*
G02X386311Y1113132I1039J-778D01*
G02Y1110536I0J-1298D01*
G02X385272Y1111056I0J1298D01*
G01X383650D01*
G37*
G36*
G01X345459Y1113126D02*
X346267Y1114524D01*
X346236Y1114611D01*
G02X346164Y1115039I1225J426D01*
G02X348758I1297J0D01*
G02X347703Y1113764I-1298J0D01*
G01X347613Y1113747D01*
X346805Y1112349D01*
X346836Y1112262D01*
G02X346908Y1111834I-1225J-426D01*
G02X344314I-1297J0D01*
G02X345369Y1113109I1298J0D01*
G01X345459Y1113126D01*
G37*
G36*
G01X367000Y1114262D02*
G02X365961Y1113742I-1039J778D01*
G02Y1116336I0J1297D01*
G02X367000Y1115816I0J-1298D01*
G01X368622D01*
G02X369661Y1116336I1039J-778D01*
G02Y1113742I0J-1297D01*
G02X368622Y1114262I0J1298D01*
G01X367000D01*
G37*
G36*
G01X378761Y1113126D02*
X379568Y1114524D01*
X379537Y1114611D01*
G02X379464Y1115039I1225J429D01*
G02X382060I1298J0D01*
G02X381004Y1113764I-1298J0D01*
G01X380914Y1113747D01*
X380106Y1112348D01*
X380136Y1112261D01*
G02X380208Y1111834I-1225J-426D01*
G02X377614I-1297J0D01*
G02X378670Y1113109I1298J0D01*
G01X378761Y1113126D01*
G37*
G36*
G01X392517Y1112350D02*
X391710Y1113747D01*
X391620Y1113764D01*
G02X390564Y1115039I242J1275D01*
G02X393160I1298J0D01*
G02X393087Y1114611I-1298J1D01*
G01X393056Y1114524D01*
X393864Y1113126D01*
X393954Y1113109D01*
G02X395008Y1111834I-244J-1275D01*
G02X392414I-1297J0D01*
G02X392487Y1112263I1297J0D01*
G01X392517Y1112350D01*
G37*
G36*
G01X341760Y1119535D02*
X342567Y1120932D01*
X342536Y1121019D01*
G02X342464Y1121447I1225J426D01*
G02X345058I1297J0D01*
G02X344003Y1120172I-1298J0D01*
G01X343913Y1120155D01*
X343106Y1118758D01*
X343137Y1118671D01*
G02X343210Y1118243I-1225J-429D01*
G02X340614I-1298J0D01*
G02X341670Y1119518I1298J0D01*
G01X341760Y1119535D01*
G37*
G36*
G01X357367Y1121962D02*
X356560Y1123359D01*
X356470Y1123376D01*
G02X355414Y1124651I242J1275D01*
G02X358010I1298J0D01*
G02X357937Y1124223I-1298J1D01*
G01X357906Y1124136D01*
X358713Y1122739D01*
X358803Y1122722D01*
G02X359858Y1121447I-243J-1275D01*
G02X357264I-1297J0D01*
G02X357336Y1121876I1297J3D01*
G01X357367Y1121962D01*
G37*
G36*
G01X364767Y1121960D02*
X363959Y1123359D01*
X363869Y1123376D01*
G02X362814Y1124651I243J1275D01*
G02X365408I1297J0D01*
G02X365336Y1124223I-1297J-2D01*
G01X365305Y1124136D01*
X366112Y1122739D01*
X366202Y1122722D01*
G02X367260Y1121447I-239J-1275D01*
G02X364664I-1298J0D01*
G02X364737Y1121874I1298J-2D01*
G01X364767Y1121960D01*
G37*
G36*
G01X372167D02*
X371359Y1123359D01*
X371269Y1123376D01*
G02X370214Y1124651I243J1275D01*
G02X372808I1297J0D01*
G02X372736Y1124223I-1297J-2D01*
G01X372705Y1124136D01*
X373512Y1122739D01*
X373602Y1122722D01*
G02X374660Y1121447I-239J-1275D01*
G02X372064I-1298J0D01*
G02X372137Y1121874I1298J-2D01*
G01X372167Y1121960D01*
G37*
G36*
G01X379567D02*
X378759Y1123359D01*
X378669Y1123376D01*
G02X377614Y1124651I243J1275D01*
G02X380208I1297J0D01*
G02X380136Y1124223I-1297J-2D01*
G01X380105Y1124136D01*
X380912Y1122739D01*
X381002Y1122722D01*
G02X382060Y1121447I-239J-1275D01*
G02X379464I-1298J0D01*
G02X379537Y1121874I1298J-2D01*
G01X379567Y1121960D01*
G37*
G36*
G01X386967D02*
X386159Y1123359D01*
X386069Y1123376D01*
G02X385014Y1124651I243J1275D01*
G02X387608I1297J0D01*
G02X387536Y1124223I-1297J-2D01*
G01X387505Y1124136D01*
X388312Y1122739D01*
X388402Y1122722D01*
G02X389460Y1121447I-239J-1275D01*
G02X386864I-1298J0D01*
G02X386937Y1121874I1298J-2D01*
G01X386967Y1121960D01*
G37*
G36*
G01X352859Y1125943D02*
X353667Y1127341D01*
X353636Y1127428D01*
G02X353564Y1127856I1225J426D01*
G02X356158I1297J0D01*
G02X355103Y1126581I-1298J0D01*
G01X355013Y1126564D01*
X354205Y1125166D01*
X354236Y1125079D01*
G02X354308Y1124651I-1225J-426D01*
G02X351714I-1297J0D01*
G02X352769Y1125926I1298J0D01*
G01X352859Y1125943D01*
G37*
G36*
G01X360260D02*
X361068Y1127341D01*
X361037Y1127428D01*
G02X360964Y1127856I1225J429D01*
G02X363560I1298J0D01*
G02X362504Y1126581I-1298J0D01*
G01X362414Y1126564D01*
X361606Y1125166D01*
X361637Y1125079D01*
G02X361710Y1124651I-1225J-429D01*
G02X359114I-1298J0D01*
G02X360170Y1125926I1298J0D01*
G01X360260Y1125943D01*
G37*
G36*
G01X367661D02*
X368468Y1127341D01*
X368437Y1127428D01*
G02X368364Y1127856I1225J429D01*
G02X370960I1298J0D01*
G02X369904Y1126581I-1298J0D01*
G01X369814Y1126564D01*
X369006Y1125165D01*
X369036Y1125078D01*
G02X369108Y1124651I-1225J-426D01*
G02X366514I-1297J0D01*
G02X367570Y1125926I1298J0D01*
G01X367661Y1125943D01*
G37*
G36*
G01X375061D02*
X375868Y1127341D01*
X375837Y1127428D01*
G02X375764Y1127856I1225J429D01*
G02X378360I1298J0D01*
G02X377304Y1126581I-1298J0D01*
G01X377214Y1126564D01*
X376406Y1125165D01*
X376436Y1125078D01*
G02X376508Y1124651I-1225J-426D01*
G02X373914I-1297J0D01*
G02X374970Y1125926I1298J0D01*
G01X375061Y1125943D01*
G37*
G36*
G01X382461D02*
X383268Y1127341D01*
X383237Y1127428D01*
G02X383164Y1127856I1225J429D01*
G02X385760I1298J0D01*
G02X384704Y1126581I-1298J0D01*
G01X384614Y1126564D01*
X383806Y1125165D01*
X383836Y1125078D01*
G02X383908Y1124651I-1225J-426D01*
G02X381314I-1297J0D01*
G02X382370Y1125926I1298J0D01*
G01X382461Y1125943D01*
G37*
G36*
G01X389861D02*
X390668Y1127341D01*
X390637Y1127428D01*
G02X390564Y1127856I1225J429D01*
G02X393160I1298J0D01*
G02X392104Y1126581I-1298J0D01*
G01X392014Y1126564D01*
X391206Y1125165D01*
X391236Y1125078D01*
G02X391308Y1124651I-1225J-426D01*
G02X388714I-1297J0D01*
G02X389770Y1125926I1298J0D01*
G01X389861Y1125943D01*
G37*
G36*
G01X339909Y1129148D02*
X340716Y1130546D01*
X340686Y1130632D01*
G02X340614Y1131060I1225J426D01*
G02X343208I1297J0D01*
G02X342153Y1129785I-1298J0D01*
G01X342063Y1129768D01*
X341256Y1128370D01*
X341286Y1128284D01*
G02X341358Y1127856I-1225J-426D01*
G02X338764I-1297J0D01*
G02X339819Y1129131I1298J0D01*
G01X339909Y1129148D01*
G37*
G36*
G01X356139Y842761D02*
X356980Y844356D01*
X356941Y844444D01*
G02X356830Y844971I1186J525D01*
G02X359424I1297J0D01*
G02X358362Y843695I-1298J0D01*
G01X358267Y843677D01*
X357426Y842082D01*
X357465Y841994D01*
G02X357576Y841467I-1186J-525D01*
G02X354982I-1297J0D01*
G02X356044Y842743I1298J0D01*
G01X356139Y842761D01*
G37*
G36*
G01X363539D02*
X364380Y844356D01*
X364341Y844444D01*
G02X364230Y844971I1186J525D01*
G02X366824I1297J0D01*
G02X365762Y843695I-1298J0D01*
G01X365667Y843677D01*
X364826Y842082D01*
X364865Y841994D01*
G02X364976Y841467I-1186J-525D01*
G02X362382I-1297J0D01*
G02X363444Y842743I1298J0D01*
G01X363539Y842761D01*
G37*
G36*
G01X370939D02*
X371780Y844356D01*
X371741Y844444D01*
G02X371630Y844971I1186J525D01*
G02X374224I1297J0D01*
G02X373162Y843695I-1298J0D01*
G01X373067Y843677D01*
X372226Y842082D01*
X372265Y841994D01*
G02X372376Y841467I-1186J-525D01*
G02X369782I-1297J0D01*
G02X370844Y842743I1298J0D01*
G01X370939Y842761D01*
G37*
G36*
G01X378339D02*
X379180Y844356D01*
X379141Y844444D01*
G02X379030Y844971I1186J525D01*
G02X381624I1297J0D01*
G02X380562Y843695I-1298J0D01*
G01X380467Y843677D01*
X379626Y842082D01*
X379665Y841994D01*
G02X379776Y841467I-1186J-525D01*
G02X377182I-1297J0D01*
G02X378244Y842743I1298J0D01*
G01X378339Y842761D01*
G37*
G36*
G01X385739D02*
X386580Y844356D01*
X386541Y844444D01*
G02X386430Y844971I1186J525D01*
G02X389024I1297J0D01*
G02X387962Y843695I-1298J0D01*
G01X387867Y843677D01*
X387026Y842082D01*
X387065Y841994D01*
G02X387176Y841467I-1186J-525D01*
G02X384582I-1297J0D01*
G02X385644Y842743I1298J0D01*
G01X385739Y842761D01*
G37*
G36*
G01X360633Y845486D02*
X359826Y846884D01*
X359736Y846901D01*
G02X358680Y848176I242J1275D01*
G02X361276I1298J0D01*
G02X361203Y847747I-1297J0D01*
G01X361172Y847661D01*
X361979Y846263D01*
X362069Y846246D01*
G02X363124Y844971I-243J-1275D01*
G02X360530I-1297J0D01*
G02X360602Y845400I1297J3D01*
G01X360633Y845486D01*
G37*
G36*
G01X368033D02*
X367226Y846884D01*
X367136Y846901D01*
G02X366080Y848176I242J1275D01*
G02X368676I1298J0D01*
G02X368603Y847747I-1297J0D01*
G01X368572Y847661D01*
X369379Y846263D01*
X369469Y846246D01*
G02X370524Y844971I-243J-1275D01*
G02X367930I-1297J0D01*
G02X368002Y845400I1297J3D01*
G01X368033Y845486D01*
G37*
G36*
G01X375433D02*
X374626Y846884D01*
X374536Y846901D01*
G02X373480Y848176I242J1275D01*
G02X376076I1298J0D01*
G02X376003Y847747I-1297J0D01*
G01X375972Y847661D01*
X376779Y846263D01*
X376869Y846246D01*
G02X377924Y844971I-243J-1275D01*
G02X375330I-1297J0D01*
G02X375402Y845400I1297J3D01*
G01X375433Y845486D01*
G37*
G36*
G01X382833D02*
X382026Y846884D01*
X381936Y846901D01*
G02X380880Y848176I242J1275D01*
G02X383476I1298J0D01*
G02X383403Y847747I-1297J0D01*
G01X383372Y847661D01*
X384179Y846263D01*
X384269Y846246D01*
G02X385324Y844971I-243J-1275D01*
G02X382730I-1297J0D01*
G02X382802Y845400I1297J3D01*
G01X382833Y845486D01*
G37*
G36*
G01X390233D02*
X389426Y846884D01*
X389336Y846901D01*
G02X388280Y848176I242J1275D01*
G02X390876I1298J0D01*
G02X390803Y847747I-1297J0D01*
G01X390772Y847661D01*
X391579Y846263D01*
X391669Y846246D01*
G02X392724Y844971I-243J-1275D01*
G02X390130I-1297J0D01*
G02X390202Y845400I1297J3D01*
G01X390233Y845486D01*
G37*
G36*
G01X444266Y843894D02*
G02X443227Y843374I-1039J778D01*
G02Y845968I0J1297D01*
G02X444266Y845448I0J-1298D01*
G01X445888D01*
G02X446927Y845968I1039J-778D01*
G02Y843374I0J-1297D01*
G02X445888Y843894I0J1298D01*
G01X444266D01*
G37*
G36*
G01X406884Y855099D02*
X406077Y856497D01*
X405987Y856514D01*
G02X404932Y857789I243J1275D01*
G02X407526I1297J0D01*
G02X407454Y857360I-1297J-3D01*
G01X407423Y857274D01*
X408230Y855876D01*
X408320Y855859D01*
G02X409376Y854584I-242J-1275D01*
G02X406780I-1298J0D01*
G02X406853Y855013I1297J0D01*
G01X406884Y855099D01*
G37*
G36*
G01X414284D02*
X413477Y856497D01*
X413387Y856514D01*
G02X412332Y857789I243J1275D01*
G02X414926I1297J0D01*
G02X414854Y857360I-1297J-3D01*
G01X414823Y857274D01*
X415630Y855876D01*
X415720Y855859D01*
G02X416776Y854584I-242J-1275D01*
G02X414180I-1298J0D01*
G02X414253Y855013I1297J0D01*
G01X414284Y855099D01*
G37*
G36*
G01X421684D02*
X420877Y856497D01*
X420787Y856514D01*
G02X419732Y857789I243J1275D01*
G02X422326I1297J0D01*
G02X422254Y857360I-1297J-3D01*
G01X422223Y857274D01*
X423030Y855876D01*
X423120Y855859D01*
G02X424176Y854584I-242J-1275D01*
G02X421580I-1298J0D01*
G02X421653Y855013I1297J0D01*
G01X421684Y855099D01*
G37*
G36*
G01X429084D02*
X428277Y856497D01*
X428187Y856514D01*
G02X427132Y857789I243J1275D01*
G02X429726I1297J0D01*
G02X429654Y857360I-1297J-3D01*
G01X429623Y857274D01*
X430430Y855876D01*
X430520Y855859D01*
G02X431576Y854584I-242J-1275D01*
G02X428980I-1298J0D01*
G02X429053Y855013I1297J0D01*
G01X429084Y855099D01*
G37*
G36*
G01X436484Y855098D02*
X435677Y856497D01*
X435587Y856514D01*
G02X434532Y857789I243J1275D01*
G02X437126I1297J0D01*
G02X437054Y857360I-1297J-3D01*
G01X437023Y857274D01*
X437830Y855876D01*
X437920Y855859D01*
G02X438976Y854584I-242J-1275D01*
G02X436382I-1297J0D01*
G02X436454Y855012I1297J2D01*
G01X436484Y855098D01*
G37*
G36*
G01X444928Y855876D02*
X445735Y857274D01*
X445704Y857361D01*
G02X445632Y857789I1225J426D01*
G02X448226I1297J0D01*
G02X447171Y856514I-1298J0D01*
G01X447081Y856497D01*
X446273Y855098D01*
X446303Y855011D01*
G02X446376Y854584I-1225J-429D01*
G02X443780I-1298J0D01*
G02X444838Y855859I1297J0D01*
G01X444928Y855876D01*
G37*
G36*
G01X417177Y859081D02*
X417984Y860478D01*
X417953Y860565D01*
G02X417880Y860993I1225J429D01*
G02X420476I1298J0D01*
G02X419420Y859718I-1298J0D01*
G01X419330Y859701D01*
X418523Y858304D01*
X418554Y858217D01*
G02X418626Y857789I-1225J-426D01*
G02X416032I-1297J0D01*
G02X417087Y859064I1298J0D01*
G01X417177Y859081D01*
G37*
G36*
G01X424577D02*
X425384Y860478D01*
X425353Y860565D01*
G02X425280Y860993I1225J429D01*
G02X427876I1298J0D01*
G02X426820Y859718I-1298J0D01*
G01X426730Y859701D01*
X425923Y858304D01*
X425954Y858217D01*
G02X426026Y857789I-1225J-426D01*
G02X423432I-1297J0D01*
G02X424487Y859064I1298J0D01*
G01X424577Y859081D01*
G37*
G36*
G01X431978D02*
X432785Y860478D01*
X432754Y860565D01*
G02X432682Y860993I1225J426D01*
G02X435276I1297J0D01*
G02X434221Y859718I-1298J0D01*
G01X434131Y859701D01*
X433324Y858303D01*
X433354Y858217D01*
G02X433426Y857789I-1225J-426D01*
G02X430832I-1297J0D01*
G02X431888Y859064I1298J0D01*
G01X431978Y859081D01*
G37*
G36*
G01X408484Y943243D02*
G03X408994I255J308D01*
G02X409889Y943566I895J-1078D01*
G02Y940762I0J-1402D01*
G02X408994Y941085I0J1401D01*
G03X408484I-255J-308D01*
G02X406694I-895J1078D01*
G03X406184I-255J-308D01*
G02X405289Y940762I-895J1078D01*
G02X404503Y941003I0J1402D01*
G03X403891Y940767I-224J-332D01*
G02X402529Y939698I-1362J333D01*
G02Y942502I0J1402D01*
G02X403315Y942261I0J-1402D01*
G03X403927Y942497I224J332D01*
G02X405289Y943566I1362J-333D01*
G02X406184Y943243I0J-1401D01*
G03X406694I255J308D01*
G02X408484I895J-1078D01*
G37*
G36*
G01X467139Y842761D02*
X467980Y844356D01*
X467941Y844444D01*
G02X467830Y844971I1186J525D01*
G02X470424I1297J0D01*
G02X469362Y843695I-1298J0D01*
G01X469267Y843677D01*
X468426Y842082D01*
X468465Y841994D01*
G02X468576Y841467I-1186J-525D01*
G02X465982I-1297J0D01*
G02X467044Y842743I1298J0D01*
G01X467139Y842761D01*
G37*
G36*
G01X474539D02*
X475380Y844356D01*
X475341Y844444D01*
G02X475230Y844971I1186J525D01*
G02X477824I1297J0D01*
G02X476762Y843695I-1298J0D01*
G01X476667Y843677D01*
X475826Y842082D01*
X475865Y841994D01*
G02X475976Y841467I-1186J-525D01*
G02X473382I-1297J0D01*
G02X474444Y842743I1298J0D01*
G01X474539Y842761D01*
G37*
G36*
G01X471633Y845486D02*
X470826Y846884D01*
X470736Y846901D01*
G02X469680Y848176I242J1275D01*
G02X472276I1298J0D01*
G02X472203Y847747I-1297J0D01*
G01X472172Y847661D01*
X472979Y846263D01*
X473069Y846246D01*
G02X474124Y844971I-243J-1275D01*
G02X471530I-1297J0D01*
G02X471602Y845400I1297J3D01*
G01X471633Y845486D01*
G37*
G36*
G01X467128Y855876D02*
X467935Y857274D01*
X467904Y857361D01*
G02X467832Y857789I1225J426D01*
G02X470426I1297J0D01*
G02X469371Y856514I-1298J0D01*
G01X469281Y856497D01*
X468473Y855098D01*
X468503Y855011D01*
G02X468576Y854584I-1225J-429D01*
G02X465980I-1298J0D01*
G02X467038Y855859I1297J0D01*
G01X467128Y855876D01*
G37*
G36*
G01X474528D02*
X475335Y857274D01*
X475304Y857361D01*
G02X475232Y857789I1225J426D01*
G02X477826I1297J0D01*
G02X476771Y856514I-1298J0D01*
G01X476681Y856497D01*
X475873Y855098D01*
X475903Y855011D01*
G02X475976Y854584I-1225J-429D01*
G02X473380I-1298J0D01*
G02X474438Y855859I1297J0D01*
G01X474528Y855876D01*
G37*
G36*
G01X481928D02*
X482735Y857274D01*
X482704Y857361D01*
G02X482632Y857789I1225J426D01*
G02X485226I1297J0D01*
G02X484171Y856514I-1298J0D01*
G01X484081Y856497D01*
X483273Y855098D01*
X483303Y855011D01*
G02X483376Y854584I-1225J-429D01*
G02X480780I-1298J0D01*
G02X481838Y855859I1297J0D01*
G01X481928Y855876D01*
G37*
G36*
G01X489328D02*
X490135Y857274D01*
X490104Y857361D01*
G02X490032Y857789I1225J426D01*
G02X492626I1297J0D01*
G02X491571Y856514I-1298J0D01*
G01X491481Y856497D01*
X490673Y855098D01*
X490703Y855011D01*
G02X490776Y854584I-1225J-429D01*
G02X488180I-1298J0D01*
G02X489238Y855859I1297J0D01*
G01X489328Y855876D01*
G37*
G36*
G01X471634Y858302D02*
X470826Y859701D01*
X470736Y859718D01*
G02X469680Y860993I242J1275D01*
G02X472276I1298J0D01*
G02X472203Y860564I-1297J0D01*
G01X472172Y860478D01*
X472978Y859081D01*
X473068Y859064D01*
G02X474126Y857789I-239J-1275D01*
G02X471532I-1297J0D01*
G02X471603Y858215I1297J3D01*
G01X471634Y858302D01*
G37*
G36*
G01X479034D02*
X478226Y859701D01*
X478136Y859718D01*
G02X477080Y860993I242J1275D01*
G02X479676I1298J0D01*
G02X479603Y860564I-1297J0D01*
G01X479572Y860478D01*
X480378Y859081D01*
X480468Y859064D01*
G02X481526Y857789I-239J-1275D01*
G02X478932I-1297J0D01*
G02X479003Y858215I1297J3D01*
G01X479034Y858302D01*
G37*
G36*
G01X486434D02*
X485626Y859701D01*
X485536Y859718D01*
G02X484480Y860993I242J1275D01*
G02X487076I1298J0D01*
G02X487003Y860564I-1297J0D01*
G01X486972Y860478D01*
X487778Y859081D01*
X487868Y859064D01*
G02X488926Y857789I-239J-1275D01*
G02X486332I-1297J0D01*
G02X486403Y858215I1297J3D01*
G01X486434Y858302D01*
G37*
G36*
G01X493834D02*
X493026Y859701D01*
X492936Y859718D01*
G02X491880Y860993I242J1275D01*
G02X494476I1298J0D01*
G02X494403Y860564I-1297J0D01*
G01X494372Y860478D01*
X495178Y859081D01*
X495268Y859064D01*
G02X496326Y857789I-239J-1275D01*
G02X493732I-1297J0D01*
G02X493803Y858215I1297J3D01*
G01X493834Y858302D01*
G37*
G36*
G01X459728Y868693D02*
X460535Y870091D01*
X460504Y870178D01*
G02X460432Y870606I1225J426D01*
G02X463026I1297J0D01*
G02X461971Y869331I-1298J0D01*
G01X461881Y869314D01*
X461073Y867915D01*
X461103Y867828D01*
G02X461176Y867401I-1225J-429D01*
G02X458580I-1298J0D01*
G02X459638Y868676I1297J0D01*
G01X459728Y868693D01*
G37*
G36*
G01X467128D02*
X467935Y870091D01*
X467904Y870178D01*
G02X467832Y870606I1225J426D01*
G02X470426I1297J0D01*
G02X469371Y869331I-1298J0D01*
G01X469281Y869314D01*
X468473Y867915D01*
X468503Y867828D01*
G02X468576Y867401I-1225J-429D01*
G02X465980I-1298J0D01*
G02X467038Y868676I1297J0D01*
G01X467128Y868693D01*
G37*
G36*
G01X474528D02*
X475335Y870091D01*
X475304Y870178D01*
G02X475232Y870606I1225J426D01*
G02X477826I1297J0D01*
G02X476771Y869331I-1298J0D01*
G01X476681Y869314D01*
X475873Y867915D01*
X475903Y867828D01*
G02X475976Y867401I-1225J-429D01*
G02X473380I-1298J0D01*
G02X474438Y868676I1297J0D01*
G01X474528Y868693D01*
G37*
G36*
G01X481928D02*
X482735Y870091D01*
X482704Y870178D01*
G02X482632Y870606I1225J426D01*
G02X485226I1297J0D01*
G02X484171Y869331I-1298J0D01*
G01X484081Y869314D01*
X483273Y867915D01*
X483303Y867828D01*
G02X483376Y867401I-1225J-429D01*
G02X480780I-1298J0D01*
G02X481838Y868676I1297J0D01*
G01X481928Y868693D01*
G37*
G36*
G01X489328D02*
X490135Y870091D01*
X490104Y870178D01*
G02X490032Y870606I1225J426D01*
G02X492626I1297J0D01*
G02X491571Y869331I-1298J0D01*
G01X491481Y869314D01*
X490673Y867915D01*
X490703Y867828D01*
G02X490776Y867401I-1225J-429D01*
G02X488180I-1298J0D01*
G02X489238Y868676I1297J0D01*
G01X489328Y868693D01*
G37*
G36*
G01X464234Y871119D02*
X463426Y872518D01*
X463336Y872535D01*
G02X462280Y873810I242J1275D01*
G02X464876I1298J0D01*
G02X464803Y873381I-1297J0D01*
G01X464772Y873295D01*
X465578Y871898D01*
X465668Y871881D01*
G02X466726Y870606I-239J-1275D01*
G02X464132I-1297J0D01*
G02X464203Y871032I1297J3D01*
G01X464234Y871119D01*
G37*
G36*
G01X479034D02*
X478226Y872518D01*
X478136Y872535D01*
G02X477080Y873810I242J1275D01*
G02X479676I1298J0D01*
G02X479603Y873381I-1297J0D01*
G01X479572Y873295D01*
X480378Y871898D01*
X480468Y871881D01*
G02X481526Y870606I-239J-1275D01*
G02X478932I-1297J0D01*
G02X479003Y871032I1297J3D01*
G01X479034Y871119D01*
G37*
G36*
G01X486434D02*
X485626Y872518D01*
X485536Y872535D01*
G02X484480Y873810I242J1275D01*
G02X487076I1298J0D01*
G02X487003Y873381I-1297J0D01*
G01X486972Y873295D01*
X487778Y871898D01*
X487868Y871881D01*
G02X488926Y870606I-239J-1275D01*
G02X486332I-1297J0D01*
G02X486403Y871032I1297J3D01*
G01X486434Y871119D01*
G37*
G36*
G01X493834D02*
X493026Y872518D01*
X492936Y872535D01*
G02X491880Y873810I242J1275D01*
G02X494476I1298J0D01*
G02X494403Y873381I-1297J0D01*
G01X494372Y873295D01*
X495178Y871898D01*
X495268Y871881D01*
G02X496326Y870606I-239J-1275D01*
G02X493732I-1297J0D01*
G02X493803Y871032I1297J3D01*
G01X493834Y871119D01*
G37*
G36*
G01X630870Y1004454D02*
X635770D01*
G02Y997252I0J-3601D01*
G01X630870D01*
G02Y1004454I0J3601D01*
G37*
G36*
G01X645925Y996880D02*
X643809Y998996D01*
X643768Y999011D01*
G02X642855Y1000325I489J1314D01*
G02X644257Y1001727I1402J0D01*
G02X645571Y1000814I0J-1402D01*
G01X645586Y1000773D01*
X647338Y999021D01*
X647437Y999035D01*
G02X647689Y999053I254J-1784D01*
G02Y995449I0J-1802D01*
G02X645938Y996826I0J1802D01*
G01X645925Y996880D01*
G37*
G36*
G01X630870Y1291266D02*
X635770D01*
G02Y1284062I0J-3602D01*
G01X630870D01*
G02Y1291266I0J3602D01*
G37*
G36*
G01X690270D02*
X695170D01*
G02Y1284062I0J-3602D01*
G01X690270D01*
G02Y1291266I0J3602D01*
G37*
G36*
G01X749670D02*
X754570D01*
G02Y1284062I0J-3602D01*
G01X749670D01*
G02Y1291266I0J3602D01*
G37*
G36*
G01X809070D02*
X813970D01*
G02Y1284062I0J-3602D01*
G01X809070D01*
G02Y1291266I0J3602D01*
G37*
G36*
G01X660570D02*
X665470D01*
G02Y1284062I0J-3602D01*
G01X660570D01*
G02Y1291266I0J3602D01*
G37*
G36*
G01X779370D02*
X784270D01*
G02Y1284062I0J-3602D01*
G01X779370D01*
G02Y1291266I0J3602D01*
G37*
G36*
G01X838770D02*
X843670D01*
G02Y1284062I0J-3602D01*
G01X838770D01*
G02Y1291266I0J3602D01*
G37*
G36*
G01X830731Y1275466D02*
X842761D01*
X845048Y1273179D01*
Y1267149D01*
X844061Y1266162D01*
X830031D01*
X828644Y1267549D01*
Y1273379D01*
X830731Y1275466D01*
G37*
G36*
G01X816031Y1266462D02*
X814944Y1267549D01*
Y1273379D01*
X817031Y1275466D01*
X821861D01*
X823948Y1273379D01*
Y1267549D01*
X822861Y1266462D01*
X816031D01*
G37*
G36*
G01X800031D02*
X798944Y1267549D01*
Y1273379D01*
X801031Y1275466D01*
X805861D01*
X807948Y1273379D01*
Y1267549D01*
X806861Y1266462D01*
X800031D01*
G37*
G36*
G01X786331D02*
X785244Y1267549D01*
Y1273379D01*
X787331Y1275466D01*
X792161D01*
X794248Y1273379D01*
Y1267549D01*
X793161Y1266462D01*
X786331D01*
G37*
G36*
G01X770331D02*
X769244Y1267549D01*
Y1273379D01*
X771331Y1275466D01*
X776161D01*
X778248Y1273379D01*
Y1267549D01*
X777161Y1266462D01*
X770331D01*
G37*
G36*
G01X756631D02*
X755544Y1267549D01*
Y1273379D01*
X757631Y1275466D01*
X762461D01*
X764548Y1273379D01*
Y1267549D01*
X763461Y1266462D01*
X756631D01*
G37*
G36*
G01X740631D02*
X739544Y1267549D01*
Y1273379D01*
X741631Y1275466D01*
X746461D01*
X748548Y1273379D01*
Y1267549D01*
X747461Y1266462D01*
X740631D01*
G37*
G36*
G01X726931D02*
X725844Y1267549D01*
Y1273379D01*
X727931Y1275466D01*
X732761D01*
X734848Y1273379D01*
Y1267549D01*
X733761Y1266462D01*
X726931D01*
G37*
G36*
G01X710931D02*
X709844Y1267549D01*
Y1273379D01*
X711931Y1275466D01*
X716761D01*
X718848Y1273379D01*
Y1267549D01*
X717761Y1266462D01*
X710931D01*
G37*
G36*
G01X697231D02*
X696144Y1267549D01*
Y1273379D01*
X698231Y1275466D01*
X703061D01*
X705148Y1273379D01*
Y1267549D01*
X704061Y1266462D01*
X697231D01*
G37*
G36*
G01X681231D02*
X680144Y1267549D01*
Y1273379D01*
X682231Y1275466D01*
X687061D01*
X689148Y1273379D01*
Y1267549D01*
X688061Y1266462D01*
X681231D01*
G37*
G36*
G01X667531D02*
X666444Y1267549D01*
Y1273379D01*
X668531Y1275466D01*
X673361D01*
X675448Y1273379D01*
Y1267549D01*
X674361Y1266462D01*
X667531D01*
G37*
G36*
G01X651531D02*
X650444Y1267549D01*
Y1273379D01*
X652531Y1275466D01*
X657361D01*
X659448Y1273379D01*
Y1267549D01*
X658361Y1266462D01*
X651531D01*
G37*
G36*
G01X637831D02*
X636744Y1267549D01*
Y1273379D01*
X638831Y1275466D01*
X643661D01*
X645748Y1273379D01*
Y1267549D01*
X644661Y1266462D01*
X637831D01*
G37*
G36*
G01X621831D02*
X620744Y1267549D01*
Y1273379D01*
X622831Y1275466D01*
X627661D01*
X629748Y1273379D01*
Y1267549D01*
X628661Y1266462D01*
X621831D01*
G37*
G36*
G01X695022Y1307050D02*
G02X695910Y1307418I888J-887D01*
G01X701145D01*
G02X702033Y1307050I0J-1255D01*
G01X702533Y1306550D01*
G02X702902Y1305662I-887J-889D01*
G01Y1302412D01*
X704254D01*
Y1302648D01*
X705307D01*
G02X705902Y1302418I-2J-890D01*
G01X706495D01*
X706543Y1302447D01*
G02X707077Y1302644I777J-1285D01*
G03X707387Y1303178I-65J395D01*
G02X707293Y1303701I1408J523D01*
G02X710297I1502J0D01*
G02X710206Y1303185I-1502J-1D01*
G03X710581Y1302648I375J-137D01*
G01X711186D01*
Y1302412D01*
X713254D01*
Y1302648D01*
X714307D01*
G02X714902Y1302418I-2J-890D01*
G01X715452D01*
G02X716340Y1302050I0J-1255D01*
G01X717395Y1300995D01*
G02X717764Y1300107I-887J-889D01*
G01Y1299722D01*
G03X717945Y1299523I200J0D01*
G02X718717Y1299160I-117J-1251D01*
G01X719218Y1298659D01*
G02X719586Y1297771I-887J-888D01*
G01Y1297063D01*
G02X719218Y1296175I-1255J0D01*
G01X718717Y1295674D01*
G02X717945Y1295311I-889J888D01*
G03X717764Y1295112I19J-199D01*
G01Y1294809D01*
G02X717395Y1293921I-1256J1D01*
G01X716928Y1293453D01*
X717395Y1292985D01*
G02X717764Y1292097I-887J-889D01*
G01Y1291234D01*
G03X718344Y1290878I400J1D01*
G02X719970Y1291266I1626J-3213D01*
G01X724870D01*
G02Y1284062I0J-3602D01*
G01X719970D01*
G02X716882Y1285811I1J3602D01*
G03X716156Y1285722I-343J-205D01*
G02X715394Y1284820I-1436J440D01*
G03X715208Y1284300I180J-358D01*
G02X715338Y1283689I-1371J-611D01*
G02X712334I-1502J0D01*
G02X712410Y1284160I1502J-1D01*
G03X711965Y1284680I-380J125D01*
G02X711720Y1284660I-244J1482D01*
G02X710218Y1286162I0J1502D01*
G01Y1286198D01*
G03X709536Y1286491I-400J10D01*
G01X708464Y1285419D01*
X706563D01*
G02X705720Y1285160I-843J1242D01*
G02X704218Y1286662I0J1502D01*
G01Y1286687D01*
X704220Y1286771D01*
X700907Y1290084D01*
Y1295696D01*
X700785Y1295747D01*
G02X700538Y1295906I352J818D01*
G01X699810D01*
G02X698922Y1296274I0J1255D01*
G01X696837Y1298358D01*
X696757Y1298361D01*
G02X695008Y1300162I53J1801D01*
G02X696810Y1301964I1802J0D01*
G02X698611Y1300215I0J-1802D01*
G01X698614Y1300135D01*
X700330Y1298418D01*
X700534D01*
X700588Y1298461D01*
G02X700836Y1298596I544J-704D01*
G01X700878Y1298611D01*
X701602Y1299335D01*
G03X701461Y1299676I-141J141D01*
G01X701133D01*
G02X700243Y1300573I0J890D01*
G01X700244D01*
Y1301751D01*
X700243D01*
G02X700362Y1302201I890J5D01*
G01X700388Y1302247D01*
Y1304906D01*
X696430D01*
X694084Y1302559D01*
X694081Y1302479D01*
G02X692280Y1300730I-1801J53D01*
G02X690478Y1302532I0J1802D01*
G02X692227Y1304333I1802J0D01*
G01X692307Y1304336D01*
X695022Y1307050D01*
G37*
G36*
G01X704204Y450262D02*
X704274D01*
X708475Y454464D01*
X710065D01*
X710952Y453577D01*
Y451697D01*
X710406Y451152D01*
X711112Y450447D01*
Y448657D01*
X710156Y447702D01*
X710252Y447607D01*
Y445157D01*
X710156Y445062D01*
X711152Y444067D01*
Y442527D01*
X710436Y441812D01*
X711232Y441017D01*
Y439437D01*
X710455Y438660D01*
X708065D01*
X704268Y442458D01*
X704204D01*
X703972Y442814D01*
Y442980D01*
X701976D01*
Y442814D01*
X701746Y442458D01*
X701672D01*
X697495Y438280D01*
X695865D01*
X694858Y439287D01*
Y440907D01*
X695589Y441637D01*
X694868Y442357D01*
Y444187D01*
X695734Y445052D01*
X695498Y445287D01*
Y447437D01*
X695824Y447762D01*
X694924Y448662D01*
Y450442D01*
X695564Y451082D01*
X694878Y451767D01*
Y453457D01*
X695825Y454404D01*
X697465D01*
X701606Y450262D01*
X701746D01*
X701978Y449906D01*
Y449754D01*
X703974D01*
Y449906D01*
X704204Y450262D01*
G37*
G36*
G01X727716Y130394D02*
G03Y130982I-270J294D01*
G02X727231Y132088I1017J1105D01*
G02X730235I1502J0D01*
G02X729750Y130982I-1502J-1D01*
G03Y130394I270J-294D01*
G02X730235Y129288I-1017J-1105D01*
G02X729705Y128143I-1502J0D01*
G03Y127533I259J-305D01*
G02X730235Y126388I-972J-1145D01*
G02X727231I-1502J0D01*
G02X727761Y127533I1502J0D01*
G03Y128143I-259J305D01*
G02X727231Y129288I972J1145D01*
G02X727716Y130394I1502J1D01*
G37*
G36*
G01X721197Y123676D02*
G02X719933Y122986I-1264J813D01*
G02Y125990I0J1502D01*
G02X721197Y125300I0J-1503D01*
G03X721869I336J216D01*
G02X723133Y125990I1264J-813D01*
G02Y122986I0J-1502D01*
G02X721869Y123676I0J1503D01*
G03X721197I-336J-216D01*
G37*
G36*
G01X935367Y1528742D02*
G03X935893I263J302D01*
G02X937867I987J-1131D01*
G03X938393I263J302D01*
G02X939380Y1529112I987J-1131D01*
G02X940882Y1527610I0J-1502D01*
G02X940512Y1526623I-1501J0D01*
G03Y1526097I302J-263D01*
G02X940882Y1525110I-1131J-987D01*
G02X939380Y1523608I-1502J0D01*
G02X938393Y1523978I0J1501D01*
G03X937867I-263J-302D01*
G02X935893I-987J1131D01*
G03X935367I-263J-302D01*
G02X933393I-987J1131D01*
G03X932867I-263J-302D01*
G02X930893I-987J1131D01*
G03X930367I-263J-302D01*
G02X928393I-987J1131D01*
G03X927867I-263J-302D01*
G02X925893I-987J1131D01*
G03X925367I-263J-302D01*
G02X923393I-987J1131D01*
G03X922867I-263J-302D01*
G02X921880Y1523608I-987J1131D01*
G02X920378Y1525110I0J1502D01*
G02X920748Y1526097I1501J0D01*
G03Y1526623I-302J263D01*
G02X920378Y1527610I1131J987D01*
G02X921880Y1529112I1502J0D01*
G02X922867Y1528742I0J-1501D01*
G03X923393I263J302D01*
G02X925367I987J-1131D01*
G03X925893I263J302D01*
G02X927867I987J-1131D01*
G03X928393I263J302D01*
G02X930367I987J-1131D01*
G03X930893I263J302D01*
G02X932867I987J-1131D01*
G03X933393I263J302D01*
G02X935367I987J-1131D01*
G37*
G36*
G01X811202Y374057D02*
G03X811713Y374410I112J384D01*
G02X813210Y375794I1497J-118D01*
G02X814197Y375424I0J-1501D01*
G03X814723I263J302D01*
G02X815710Y375794I987J-1131D01*
G02Y372790I0J-1502D01*
G02X814723Y373160I0J1501D01*
G03X814197I-263J-302D01*
G02X813210Y372790I-987J1131D01*
G02X812789Y372850I-1J1502D01*
G03X812278Y372497I-112J-384D01*
G02X810781Y371113I-1497J118D01*
G02Y374117I0J1502D01*
G02X811202Y374057I1J-1502D01*
G37*
G36*
G01X920136Y309603D02*
G02X937342I8603J12050D01*
G01X920136D01*
G37*
G36*
G01X1096418Y1719520D02*
Y1725620D01*
G02X1096920Y1726122I502J0D01*
G01X1103020D01*
G02X1103522Y1725620I0J-502D01*
G01Y1719520D01*
G02X1103020Y1719018I-502J0D01*
G01X1096920D01*
G02X1096418Y1719520I0J502D01*
G37*
G36*
G01X1111077Y1709997D02*
G03X1111062Y1710544I-299J265D01*
G02X1110628Y1711600I1068J1056D01*
G02X1113632I1502J0D01*
G02X1113253Y1710603I-1501J0D01*
G03X1113268Y1710056I299J-265D01*
G02X1113702Y1709000I-1068J-1056D01*
G02X1113224Y1707901I-1502J0D01*
G03X1113235Y1707306I273J-293D01*
G02X1113754Y1706170I-984J-1136D01*
G02X1110750I-1502J0D01*
G02X1111228Y1707269I1502J0D01*
G03X1111217Y1707864I-273J293D01*
G02X1110698Y1709000I984J1136D01*
G02X1111077Y1709997I1501J0D01*
G37*
G36*
G01X1092235Y1672261D02*
G02X1091880Y1672218I-357J1459D01*
G02X1093382Y1673720I0J1502D01*
G02X1093377Y1673592I-1502J-5D01*
G03X1093870Y1673169I398J-34D01*
G02X1094225Y1673212I357J-1459D01*
G02X1092723Y1671710I0J-1502D01*
G02X1092728Y1671838I1502J5D01*
G03X1092235Y1672261I-398J34D01*
G37*
G36*
G01X1118330Y1729076D02*
G02X1117698Y1730300I869J1224D01*
G02X1120702I1502J0D01*
G02X1120070Y1729076I-1501J0D01*
G03Y1728424I232J-326D01*
G02X1120702Y1727200I-869J-1224D01*
G02X1120109Y1726004I-1503J0D01*
G03X1120130Y1725352I242J-319D01*
G02X1120802Y1724100I-830J-1252D01*
G02X1117798I-1502J0D01*
G02X1118391Y1725296I1503J0D01*
G03X1118370Y1725948I-242J319D01*
G02X1117698Y1727200I830J1252D01*
G02X1118330Y1728424I1501J0D01*
G03Y1729076I-232J326D01*
G37*
G36*
G01X1221712Y1291266D02*
X1226612D01*
G02Y1284062I0J-3602D01*
G01X1221712D01*
G02Y1291266I0J3602D01*
G37*
G36*
G01X1162312D02*
X1167212D01*
G02Y1284062I0J-3602D01*
G01X1162312D01*
G02Y1291266I0J3602D01*
G37*
G36*
G01X1102912D02*
X1107812D01*
G02Y1284062I0J-3602D01*
G01X1102912D01*
G02Y1291266I0J3602D01*
G37*
G36*
G01X1043512D02*
X1048412D01*
G02Y1284062I0J-3602D01*
G01X1043512D01*
G02Y1291266I0J3602D01*
G37*
G36*
G01X1192012D02*
X1196912D01*
G02Y1284062I0J-3602D01*
G01X1192012D01*
G02Y1291266I0J3602D01*
G37*
G36*
G01X1132612D02*
X1137512D01*
G02Y1284062I0J-3602D01*
G01X1132612D01*
G02Y1291266I0J3602D01*
G37*
G36*
G01X1073212D02*
X1078112D01*
G02Y1284062I0J-3602D01*
G01X1073212D01*
G02Y1291266I0J3602D01*
G37*
G36*
G01X1227586Y1267529D02*
Y1277001D01*
X1229032Y1278446D01*
X1235593D01*
X1236620Y1277420D01*
Y1272559D01*
X1236590Y1272529D01*
Y1267529D01*
X1235503Y1266442D01*
X1228673D01*
X1227586Y1267529D01*
G37*
G36*
G01X1221881Y1266442D02*
X1212673D01*
X1211586Y1267529D01*
Y1273359D01*
X1212643Y1274416D01*
X1221422D01*
X1223128Y1272709D01*
Y1267690D01*
X1221881Y1266442D01*
G37*
G36*
G01X1162707D02*
X1153273D01*
X1153265Y1266450D01*
X1151843D01*
X1150322Y1267971D01*
Y1273187D01*
X1151983Y1274848D01*
X1162623D01*
X1163932Y1273538D01*
Y1267666D01*
X1162707Y1266442D01*
G37*
G36*
G01X1148342D02*
X1137779D01*
X1135874Y1268347D01*
Y1273059D01*
X1137072Y1274256D01*
X1148312D01*
X1149658Y1272910D01*
Y1267759D01*
X1148342Y1266442D01*
G37*
G36*
G01X1123573D02*
X1122486Y1267529D01*
Y1273359D01*
X1124573Y1275446D01*
X1129403D01*
X1131490Y1273359D01*
Y1267529D01*
X1130403Y1266442D01*
X1123573D01*
G37*
G36*
G01X1093873D02*
X1092786Y1267529D01*
Y1273359D01*
X1094873Y1275446D01*
X1099703D01*
X1101790Y1273359D01*
Y1267529D01*
X1100703Y1266442D01*
X1093873D01*
G37*
G36*
G01X1080173D02*
X1079086Y1267529D01*
Y1273359D01*
X1081173Y1275446D01*
X1086003D01*
X1088090Y1273359D01*
Y1267529D01*
X1087003Y1266442D01*
X1080173D01*
G37*
G36*
G01X1064173D02*
X1063086Y1267529D01*
Y1273359D01*
X1065173Y1275446D01*
X1070003D01*
X1072090Y1273359D01*
Y1267529D01*
X1071003Y1266442D01*
X1064173D01*
G37*
G36*
G01X1050473D02*
X1049386Y1267529D01*
Y1273359D01*
X1051473Y1275446D01*
X1056303D01*
X1058390Y1273359D01*
Y1267529D01*
X1057303Y1266442D01*
X1050473D01*
G37*
G36*
G01X1034473D02*
X1033386Y1267529D01*
Y1273359D01*
X1035473Y1275446D01*
X1040303D01*
X1042390Y1273359D01*
Y1267529D01*
X1041303Y1266442D01*
X1034473D01*
G37*
G36*
G01X1168186Y1267529D02*
Y1272400D01*
X1169893Y1274106D01*
X1177571D01*
X1179088Y1272590D01*
Y1267871D01*
G03X1179277Y1267671I200J0D01*
G02X1180982Y1265872I-97J-1799D01*
G02X1177378I-1802J0D01*
G02X1177383Y1266012I1802J6D01*
G03X1176985Y1266442I-398J30D01*
G01X1169273D01*
X1168186Y1267529D01*
G37*
G36*
G01X1018203Y1275346D02*
X1019938Y1273610D01*
X1021773Y1275446D01*
X1026603D01*
X1028690Y1273359D01*
Y1267529D01*
X1027603Y1266442D01*
X1020773D01*
X1020038Y1267178D01*
X1019203Y1266342D01*
X1012373D01*
X1011286Y1267429D01*
Y1273259D01*
X1013373Y1275346D01*
X1018203D01*
G37*
G36*
G01X1197886Y1273359D02*
X1199973Y1275446D01*
X1204803D01*
X1206890Y1273359D01*
Y1268194D01*
G03X1207555Y1267895I400J0D01*
G02X1208750Y1268348I1195J-1350D01*
G02X1206948Y1266546I0J-1802D01*
G02X1206949Y1266609I1802J3D01*
G03X1206267Y1266906I-400J14D01*
G01X1205803Y1266442D01*
X1198973D01*
X1197886Y1267529D01*
Y1273359D01*
G37*
G36*
G01X1097298Y256262D02*
Y262462D01*
G02X1097700Y262864I402J0D01*
G01X1103900D01*
G02X1104302Y262462I0J-402D01*
G01Y256262D01*
G02X1103900Y255860I-402J0D01*
G01X1097700D01*
G02X1097298Y256262I0J402D01*
G37*
G36*
G01X1097198Y280562D02*
Y286762D01*
G02X1097600Y287164I402J0D01*
G01X1103800D01*
G02X1104202Y286762I0J-402D01*
G01Y280562D01*
G02X1103800Y280160I-402J0D01*
G01X1097600D01*
G02X1097198Y280562I0J402D01*
G37*
G36*
G01X1140444Y228409D02*
G03X1140970I263J302D01*
G02X1142944I987J-1131D01*
G03X1143470I263J302D01*
G02X1144457Y228779I987J-1131D01*
G02Y225775I0J-1502D01*
G02X1143470Y226145I0J1501D01*
G03X1142944I-263J-302D01*
G02X1140970I-987J1131D01*
G03X1140444I-263J-302D01*
G02X1139457Y225775I-987J1131D01*
G02Y228779I0J1502D01*
G02X1140444Y228409I0J-1501D01*
G37*
G36*
G01X1183008Y188967D02*
G02X1184510Y190464I1502J-5D01*
G02Y187460I0J-1502D01*
G02X1184023Y187541I0J1502D01*
G03X1183494Y187126I-131J-378D01*
G02X1183502Y186962I-1794J-170D01*
G02X1181700Y188764I-1802J0D01*
G02X1182443Y188604I1J-1802D01*
G03X1183008Y188967I165J364D01*
G37*
G36*
G01X1151998Y1361862D02*
Y1368062D01*
G02X1152400Y1368464I402J0D01*
G01X1158600D01*
G02X1159002Y1368062I0J-402D01*
G01Y1361862D01*
G02X1158600Y1361460I-402J0D01*
G01X1152400D01*
G02X1151998Y1361862I0J402D01*
G37*
G36*
G01X1176398D02*
Y1368062D01*
G02X1176800Y1368464I402J0D01*
G01X1183000D01*
G02X1183402Y1368062I0J-402D01*
G01Y1361862D01*
G02X1183000Y1361460I-402J0D01*
G01X1176800D01*
G02X1176398Y1361862I0J402D01*
G37*
G36*
G01X1127598D02*
Y1368062D01*
G02X1128000Y1368464I402J0D01*
G01X1134200D01*
G02X1134602Y1368062I0J-402D01*
G01Y1361862D01*
G02X1134200Y1361460I-402J0D01*
G01X1128000D01*
G02X1127598Y1361862I0J402D01*
G37*
G36*
G01X1221712Y1004454D02*
X1226612D01*
G02Y997252I0J-3601D01*
G01X1221712D01*
G02Y1004454I0J3601D01*
G37*
G36*
G01X1299354Y236704D02*
G03X1299376Y237214I-296J268D01*
G02X1299091Y238062I1117J847D01*
G02X1301895I1402J0D01*
G02X1301532Y237120I-1402J-1D01*
G03X1301510Y236610I296J-268D01*
G02X1301795Y235762I-1117J-847D01*
G02X1298991I-1402J0D01*
G02X1299354Y236704I1402J1D01*
G37*
G36*
G01X1409258Y1239685D02*
Y1245885D01*
G02X1409660Y1246286I402J-1D01*
G01X1415860D01*
G02X1416262Y1245885I1J-401D01*
G01Y1239685D01*
G02X1415860Y1239284I-402J1D01*
G01X1409660D01*
G02X1409258Y1239685I-1J401D01*
G37*
G36*
G01X1458058D02*
Y1245885D01*
G02X1458460Y1246286I402J-1D01*
G01X1464660D01*
G02X1465062Y1245885I1J-401D01*
G01Y1239685D01*
G02X1464660Y1239284I-402J1D01*
G01X1458460D01*
G02X1458058Y1239685I-1J401D01*
G37*
G36*
G01X1433658D02*
Y1245885D01*
G02X1434060Y1246286I402J-1D01*
G01X1440260D01*
G02X1440662Y1245885I1J-401D01*
G01Y1239685D01*
G02X1440260Y1239284I-402J1D01*
G01X1434060D01*
G02X1433658Y1239685I-1J401D01*
G37*
G36*
G01X1360536D02*
Y1245885D01*
G02X1360938Y1246286I402J-1D01*
G01X1367138D01*
G02X1367540Y1245885I1J-401D01*
G01Y1239685D01*
G02X1367138Y1239284I-402J1D01*
G01X1360938D01*
G02X1360536Y1239685I-1J401D01*
G37*
G36*
G01X1384936D02*
Y1245885D01*
G02X1385338Y1246286I402J-1D01*
G01X1391538D01*
G02X1391940Y1245885I1J-401D01*
G01Y1239685D01*
G02X1391538Y1239284I-402J1D01*
G01X1385338D01*
G02X1384936Y1239685I-1J401D01*
G37*
G36*
G01X1456371Y1153328D02*
X1455384Y1154314D01*
Y1171164D01*
X1456341Y1172120D01*
X1460181D01*
X1461478Y1170824D01*
Y1154244D01*
X1460561Y1153328D01*
X1456371D01*
G37*
G36*
G01X1430354Y1171064D02*
X1431540Y1172250D01*
X1440022D01*
X1441488Y1170784D01*
Y1152196D01*
X1440211Y1150920D01*
X1431651D01*
X1430354Y1152216D01*
Y1171064D01*
G37*
G36*
G01X1416438Y1170804D02*
Y1152374D01*
X1414923Y1150860D01*
X1406910D01*
X1405300Y1152470D01*
Y1170790D01*
X1406701Y1172190D01*
X1415051D01*
X1416438Y1170804D01*
G37*
G36*
G01X1381990Y1171500D02*
X1389810D01*
X1391526Y1169784D01*
Y1154002D01*
X1388831Y1151308D01*
X1383021D01*
X1380304Y1154024D01*
Y1169814D01*
X1381990Y1171500D01*
G37*
G36*
G01X1405556Y1079791D02*
G02X1408150I1297J0D01*
G02X1407095Y1078516I-1298J0D01*
G01X1407005Y1078499D01*
X1406198Y1077101D01*
X1406228Y1077015D01*
G02X1406300Y1076587I-1225J-426D01*
G02X1403706I-1297J0D01*
G02X1404762Y1077862I1298J0D01*
G01X1404852Y1077879D01*
X1405659Y1079276D01*
X1405628Y1079363D01*
G02X1405556Y1079791I1225J426D01*
G37*
G36*
G01X1401856Y1086200D02*
G02X1404452I1298J0D01*
G02X1403396Y1084925I-1298J0D01*
G01X1403306Y1084908D01*
X1402498Y1083510D01*
X1402529Y1083423D01*
G02X1402602Y1082995I-1225J-429D01*
G02X1400006I-1298J0D01*
G02X1401062Y1084270I1298J0D01*
G01X1401152Y1084287D01*
X1401960Y1085685D01*
X1401929Y1085772D01*
G02X1401856Y1086200I1225J429D01*
G37*
G36*
G01X1403706Y1089404D02*
G02X1406300I1297J0D01*
G02X1406228Y1088976I-1297J-2D01*
G01X1406197Y1088889D01*
X1407004Y1087492D01*
X1407094Y1087475D01*
G02X1408150Y1086200I-242J-1275D01*
G02X1405554I-1298J0D01*
G02X1405627Y1086629I1297J0D01*
G01X1405658Y1086715D01*
X1404851Y1088112D01*
X1404761Y1088129D01*
G02X1403706Y1089404I243J1275D01*
G37*
G36*
G01X1394456Y1092608D02*
G02X1397050I1297J0D01*
G02X1396978Y1092180I-1297J-2D01*
G01X1396947Y1092093D01*
X1397754Y1090696D01*
X1397844Y1090679D01*
G02X1398902Y1089404I-239J-1275D01*
G02X1396306I-1298J0D01*
G02X1396379Y1089831I1298J-2D01*
G01X1396409Y1089917D01*
X1395601Y1091316D01*
X1395511Y1091333D01*
G02X1394456Y1092608I243J1275D01*
G37*
G36*
G01X1403153Y1093906D02*
G02X1404192Y1093386I0J-1298D01*
G01X1405814D01*
G02X1406853Y1093906I1039J-778D01*
G02Y1091310I0J-1298D01*
G02X1405814Y1091830I0J1298D01*
G01X1404192D01*
G02X1403153Y1091310I-1039J778D01*
G02Y1093906I0J1298D01*
G37*
G36*
G01X1400006Y1095813D02*
G02X1402602I1298J0D01*
G02X1401546Y1094538I-1298J0D01*
G01X1401456Y1094521D01*
X1400648Y1093122D01*
X1400678Y1093035D01*
G02X1400750Y1092610I-1225J-426D01*
G01Y1092608D01*
G02X1398156I-1297J0D01*
G02X1399212Y1093883I1298J0D01*
G01X1399303Y1093900D01*
X1400110Y1095298D01*
X1400079Y1095385D01*
G02X1400006Y1095813I1225J429D01*
G37*
G36*
G01X1392053Y1106724D02*
G02X1393092Y1106204I0J-1298D01*
G01X1394714D01*
G02X1395753Y1106724I1039J-778D01*
G02Y1104128I0J-1298D01*
G02X1394714Y1104648I0J1298D01*
G01X1393092D01*
G02X1392053Y1104128I-1039J778D01*
G02Y1106724I0J1298D01*
G37*
G36*
G01X1394456Y1111834D02*
G02X1397050I1297J0D01*
G02X1395995Y1110559I-1298J0D01*
G01X1395905Y1110542D01*
X1395098Y1109145D01*
X1395129Y1109059D01*
G02X1395202Y1108630I-1224J-429D01*
G02X1392606I-1298J0D01*
G02X1393662Y1109905I1298J0D01*
G01X1393752Y1109922D01*
X1394559Y1111319D01*
X1394528Y1111406D01*
G02X1394456Y1111834I1225J426D01*
G37*
G36*
G01X1446256Y1124651D02*
G02X1448850I1297J0D01*
G02X1447795Y1123376I-1298J0D01*
G01X1447705Y1123359D01*
X1446898Y1121962D01*
X1446929Y1121875D01*
G02X1447002Y1121447I-1225J-429D01*
G02X1444406I-1298J0D01*
G02X1445462Y1122722I1298J0D01*
G01X1445552Y1122739D01*
X1446359Y1124136D01*
X1446328Y1124223D01*
G02X1446256Y1124651I1225J426D01*
G37*
G36*
G01X1453656D02*
G02X1456250I1297J0D01*
G02X1455195Y1123376I-1298J0D01*
G01X1455105Y1123359D01*
X1454298Y1121962D01*
X1454329Y1121875D01*
G02X1454402Y1121447I-1225J-429D01*
G02X1451806I-1298J0D01*
G02X1452862Y1122722I1298J0D01*
G01X1452952Y1122739D01*
X1453759Y1124136D01*
X1453728Y1124223D01*
G02X1453656Y1124651I1225J426D01*
G37*
G36*
G01X1461056D02*
G02X1463650I1297J0D01*
G02X1462595Y1123376I-1298J0D01*
G01X1462505Y1123359D01*
X1461698Y1121962D01*
X1461729Y1121875D01*
G02X1461802Y1121447I-1225J-429D01*
G02X1459206I-1298J0D01*
G02X1460262Y1122722I1298J0D01*
G01X1460352Y1122739D01*
X1461159Y1124136D01*
X1461128Y1124223D01*
G02X1461056Y1124651I1225J426D01*
G37*
G36*
G01X1468456D02*
G02X1471050I1297J0D01*
G02X1469995Y1123376I-1298J0D01*
G01X1469905Y1123359D01*
X1469098Y1121962D01*
X1469129Y1121875D01*
G02X1469202Y1121447I-1225J-429D01*
G02X1466606I-1298J0D01*
G02X1467662Y1122722I1298J0D01*
G01X1467752Y1122739D01*
X1468559Y1124136D01*
X1468528Y1124223D01*
G02X1468456Y1124651I1225J426D01*
G37*
G36*
G01X1475856D02*
G02X1478450I1297J0D01*
G02X1477395Y1123376I-1298J0D01*
G01X1477305Y1123359D01*
X1476498Y1121962D01*
X1476529Y1121875D01*
G02X1476602Y1121447I-1225J-429D01*
G02X1474006I-1298J0D01*
G02X1475062Y1122722I1298J0D01*
G01X1475152Y1122739D01*
X1475959Y1124136D01*
X1475928Y1124223D01*
G02X1475856Y1124651I1225J426D01*
G37*
G36*
G01X1483256D02*
G02X1485850I1297J0D01*
G02X1484795Y1123376I-1298J0D01*
G01X1484705Y1123359D01*
X1483898Y1121962D01*
X1483929Y1121875D01*
G02X1484002Y1121447I-1225J-429D01*
G02X1481406I-1298J0D01*
G02X1482462Y1122722I1298J0D01*
G01X1482552Y1122739D01*
X1483359Y1124136D01*
X1483328Y1124223D01*
G02X1483256Y1124651I1225J426D01*
G37*
G36*
G01X1490656D02*
G02X1493250I1297J0D01*
G02X1492195Y1123376I-1298J0D01*
G01X1492105Y1123359D01*
X1491298Y1121962D01*
X1491329Y1121875D01*
G02X1491402Y1121447I-1225J-429D01*
G02X1488806I-1298J0D01*
G02X1489862Y1122722I1298J0D01*
G01X1489952Y1122739D01*
X1490759Y1124136D01*
X1490728Y1124223D01*
G02X1490656Y1124651I1225J426D01*
G37*
G36*
G01X1498056D02*
G02X1500650I1297J0D01*
G02X1499595Y1123376I-1298J0D01*
G01X1499505Y1123359D01*
X1498698Y1121962D01*
X1498729Y1121875D01*
G02X1498802Y1121447I-1225J-429D01*
G02X1496206I-1298J0D01*
G02X1497262Y1122722I1298J0D01*
G01X1497352Y1122739D01*
X1498159Y1124136D01*
X1498128Y1124223D01*
G02X1498056Y1124651I1225J426D01*
G37*
G36*
G01X1448106Y1127856D02*
G02X1450702I1298J0D01*
G02X1450629Y1127427I-1297J0D01*
G01X1450598Y1127341D01*
X1451405Y1125943D01*
X1451495Y1125926D01*
G02X1452550Y1124651I-243J-1275D01*
G02X1449956I-1297J0D01*
G02X1450028Y1125080I1297J3D01*
G01X1450059Y1125166D01*
X1449252Y1126564D01*
X1449162Y1126581D01*
G02X1448106Y1127856I242J1275D01*
G37*
G36*
G01X1455506D02*
G02X1458102I1298J0D01*
G02X1458029Y1127427I-1297J0D01*
G01X1457998Y1127341D01*
X1458805Y1125943D01*
X1458895Y1125926D01*
G02X1459950Y1124651I-243J-1275D01*
G02X1457356I-1297J0D01*
G02X1457428Y1125080I1297J3D01*
G01X1457459Y1125166D01*
X1456652Y1126564D01*
X1456562Y1126581D01*
G02X1455506Y1127856I242J1275D01*
G37*
G36*
G01X1462906D02*
G02X1465502I1298J0D01*
G02X1465429Y1127427I-1297J0D01*
G01X1465398Y1127341D01*
X1466205Y1125943D01*
X1466295Y1125926D01*
G02X1467350Y1124651I-243J-1275D01*
G02X1464756I-1297J0D01*
G02X1464828Y1125080I1297J3D01*
G01X1464859Y1125166D01*
X1464052Y1126564D01*
X1463962Y1126581D01*
G02X1462906Y1127856I242J1275D01*
G37*
G36*
G01X1470306D02*
G02X1472902I1298J0D01*
G02X1472829Y1127427I-1297J0D01*
G01X1472798Y1127341D01*
X1473605Y1125943D01*
X1473695Y1125926D01*
G02X1474750Y1124651I-243J-1275D01*
G02X1472156I-1297J0D01*
G02X1472228Y1125080I1297J3D01*
G01X1472259Y1125166D01*
X1471452Y1126564D01*
X1471362Y1126581D01*
G02X1470306Y1127856I242J1275D01*
G37*
G36*
G01X1477706D02*
G02X1480302I1298J0D01*
G02X1480229Y1127427I-1297J0D01*
G01X1480198Y1127341D01*
X1481005Y1125943D01*
X1481095Y1125926D01*
G02X1482150Y1124651I-243J-1275D01*
G02X1479556I-1297J0D01*
G02X1479628Y1125080I1297J3D01*
G01X1479659Y1125166D01*
X1478852Y1126564D01*
X1478762Y1126581D01*
G02X1477706Y1127856I242J1275D01*
G37*
G36*
G01X1485106D02*
G02X1487702I1298J0D01*
G02X1487629Y1127427I-1297J0D01*
G01X1487598Y1127341D01*
X1488405Y1125943D01*
X1488495Y1125926D01*
G02X1489550Y1124651I-243J-1275D01*
G02X1486956I-1297J0D01*
G02X1487028Y1125080I1297J3D01*
G01X1487059Y1125166D01*
X1486252Y1126564D01*
X1486162Y1126581D01*
G02X1485106Y1127856I242J1275D01*
G37*
G36*
G01X1492506D02*
G02X1495102I1298J0D01*
G02X1495029Y1127427I-1297J0D01*
G01X1494998Y1127341D01*
X1495805Y1125943D01*
X1495895Y1125926D01*
G02X1496950Y1124651I-243J-1275D01*
G02X1494356I-1297J0D01*
G02X1494428Y1125080I1297J3D01*
G01X1494459Y1125166D01*
X1493652Y1126564D01*
X1493562Y1126581D01*
G02X1492506Y1127856I242J1275D01*
G37*
G36*
G01X1499906D02*
G02X1502502I1298J0D01*
G02X1502429Y1127427I-1297J0D01*
G01X1502398Y1127341D01*
X1503205Y1125943D01*
X1503295Y1125926D01*
G02X1504350Y1124651I-243J-1275D01*
G02X1501756I-1297J0D01*
G02X1501828Y1125080I1297J3D01*
G01X1501859Y1125166D01*
X1501052Y1126564D01*
X1500962Y1126581D01*
G02X1499906Y1127856I242J1275D01*
G37*
G36*
G01X1453656Y1137469D02*
G02X1456252I1298J0D01*
G02X1455196Y1136194I-1298J0D01*
G01X1455106Y1136177D01*
X1454298Y1134779D01*
X1454329Y1134692D01*
G02X1454402Y1134264I-1225J-429D01*
G02X1451806I-1298J0D01*
G02X1452862Y1135539I1298J0D01*
G01X1452952Y1135556D01*
X1453760Y1136954D01*
X1453729Y1137041D01*
G02X1453656Y1137469I1225J429D01*
G37*
G36*
G01X1461056D02*
G02X1463652I1298J0D01*
G02X1462596Y1136194I-1298J0D01*
G01X1462506Y1136177D01*
X1461699Y1134779D01*
X1461729Y1134692D01*
G02X1461802Y1134264I-1225J-429D01*
G02X1459206I-1298J0D01*
G02X1460263Y1135539I1297J0D01*
G01X1460353Y1135556D01*
X1461160Y1136954D01*
X1461129Y1137041D01*
G02X1461056Y1137469I1225J429D01*
G37*
G36*
G01X1468456D02*
G02X1471052I1298J0D01*
G02X1469996Y1136194I-1298J0D01*
G01X1469906Y1136177D01*
X1469099Y1134779D01*
X1469129Y1134692D01*
G02X1469202Y1134264I-1225J-429D01*
G02X1466606I-1298J0D01*
G02X1467663Y1135539I1297J0D01*
G01X1467753Y1135556D01*
X1468560Y1136954D01*
X1468529Y1137041D01*
G02X1468456Y1137469I1225J429D01*
G37*
G36*
G01X1475856D02*
G02X1478452I1298J0D01*
G02X1477396Y1136194I-1298J0D01*
G01X1477306Y1136177D01*
X1476499Y1134779D01*
X1476529Y1134692D01*
G02X1476602Y1134264I-1225J-429D01*
G02X1474006I-1298J0D01*
G02X1475063Y1135539I1297J0D01*
G01X1475153Y1135556D01*
X1475960Y1136954D01*
X1475929Y1137041D01*
G02X1475856Y1137469I1225J429D01*
G37*
G36*
G01X1483256D02*
G02X1485852I1298J0D01*
G02X1484796Y1136194I-1298J0D01*
G01X1484706Y1136177D01*
X1483899Y1134779D01*
X1483929Y1134692D01*
G02X1484002Y1134264I-1225J-429D01*
G02X1481406I-1298J0D01*
G02X1482463Y1135539I1297J0D01*
G01X1482553Y1135556D01*
X1483360Y1136954D01*
X1483329Y1137041D01*
G02X1483256Y1137469I1225J429D01*
G37*
G36*
G01X1490656D02*
G02X1493252I1298J0D01*
G02X1492196Y1136194I-1298J0D01*
G01X1492106Y1136177D01*
X1491299Y1134779D01*
X1491329Y1134692D01*
G02X1491402Y1134264I-1225J-429D01*
G02X1488806I-1298J0D01*
G02X1489863Y1135539I1297J0D01*
G01X1489953Y1135556D01*
X1490760Y1136954D01*
X1490729Y1137041D01*
G02X1490656Y1137469I1225J429D01*
G37*
G36*
G01X1498056D02*
G02X1500652I1298J0D01*
G02X1499596Y1136194I-1298J0D01*
G01X1499506Y1136177D01*
X1498699Y1134779D01*
X1498729Y1134692D01*
G02X1498802Y1134264I-1225J-429D01*
G02X1496206I-1298J0D01*
G02X1497263Y1135539I1297J0D01*
G01X1497353Y1135556D01*
X1498160Y1136954D01*
X1498129Y1137041D01*
G02X1498056Y1137469I1225J429D01*
G37*
G36*
G01X1509156D02*
G02X1511752I1298J0D01*
G02X1510696Y1136194I-1298J0D01*
G01X1510606Y1136177D01*
X1509798Y1134779D01*
X1509829Y1134692D01*
G02X1509902Y1134264I-1225J-429D01*
G02X1507306I-1298J0D01*
G02X1508362Y1135539I1298J0D01*
G01X1508452Y1135556D01*
X1509260Y1136954D01*
X1509229Y1137041D01*
G02X1509156Y1137469I1225J429D01*
G37*
G36*
G01X1448106Y1140973D02*
G02X1450700I1297J0D01*
G02X1450589Y1140448I-1297J0D01*
G01X1450550Y1140359D01*
X1451394Y1138763D01*
X1451489Y1138745D01*
G02X1452552Y1137469I-234J-1276D01*
G02X1449956I-1298J0D01*
G02X1450068Y1137994I1297J-2D01*
G01X1450107Y1138083D01*
X1449263Y1139679D01*
X1449168Y1139697D01*
G02X1448106Y1140973I236J1276D01*
G37*
G36*
G01X1455506D02*
G02X1458100I1297J0D01*
G02X1457989Y1140448I-1297J0D01*
G01X1457950Y1140359D01*
X1458794Y1138763D01*
X1458889Y1138745D01*
G02X1459952Y1137469I-234J-1276D01*
G02X1457356I-1298J0D01*
G02X1457468Y1137994I1297J-2D01*
G01X1457507Y1138083D01*
X1456663Y1139679D01*
X1456568Y1139697D01*
G02X1455506Y1140973I236J1276D01*
G37*
G36*
G01X1462906D02*
G02X1465500I1297J0D01*
G02X1465389Y1140448I-1297J0D01*
G01X1465350Y1140359D01*
X1466194Y1138763D01*
X1466289Y1138745D01*
G02X1467352Y1137469I-234J-1276D01*
G02X1464756I-1298J0D01*
G02X1464868Y1137994I1297J-2D01*
G01X1464907Y1138083D01*
X1464063Y1139679D01*
X1463968Y1139697D01*
G02X1462906Y1140973I236J1276D01*
G37*
G36*
G01X1470306D02*
G02X1472900I1297J0D01*
G02X1472789Y1140448I-1297J0D01*
G01X1472750Y1140359D01*
X1473594Y1138763D01*
X1473689Y1138745D01*
G02X1474752Y1137469I-234J-1276D01*
G02X1472156I-1298J0D01*
G02X1472268Y1137994I1297J-2D01*
G01X1472307Y1138083D01*
X1471463Y1139679D01*
X1471368Y1139697D01*
G02X1470306Y1140973I236J1276D01*
G37*
G36*
G01X1477706D02*
G02X1480300I1297J0D01*
G02X1480189Y1140448I-1297J0D01*
G01X1480150Y1140359D01*
X1480994Y1138763D01*
X1481089Y1138745D01*
G02X1482152Y1137469I-234J-1276D01*
G02X1479556I-1298J0D01*
G02X1479668Y1137994I1297J-2D01*
G01X1479707Y1138083D01*
X1478863Y1139679D01*
X1478768Y1139697D01*
G02X1477706Y1140973I236J1276D01*
G37*
G36*
G01X1485106D02*
G02X1487700I1297J0D01*
G02X1487589Y1140448I-1297J0D01*
G01X1487550Y1140359D01*
X1488394Y1138763D01*
X1488489Y1138745D01*
G02X1489552Y1137469I-234J-1276D01*
G02X1486956I-1298J0D01*
G02X1487068Y1137994I1297J-2D01*
G01X1487107Y1138083D01*
X1486263Y1139679D01*
X1486168Y1139697D01*
G02X1485106Y1140973I236J1276D01*
G37*
G36*
G01X1492506D02*
G02X1495100I1297J0D01*
G02X1494989Y1140448I-1297J0D01*
G01X1494950Y1140359D01*
X1495794Y1138763D01*
X1495889Y1138745D01*
G02X1496952Y1137469I-234J-1276D01*
G02X1494356I-1298J0D01*
G02X1494468Y1137994I1297J-2D01*
G01X1494507Y1138083D01*
X1493663Y1139679D01*
X1493568Y1139697D01*
G02X1492506Y1140973I236J1276D01*
G37*
G36*
G01X1499906D02*
G02X1502500I1297J0D01*
G02X1502389Y1140448I-1297J0D01*
G01X1502350Y1140359D01*
X1503194Y1138763D01*
X1503289Y1138745D01*
G02X1504352Y1137469I-234J-1276D01*
G02X1501756I-1298J0D01*
G02X1501868Y1137994I1297J-2D01*
G01X1501907Y1138083D01*
X1501063Y1139679D01*
X1500968Y1139697D01*
G02X1499906Y1140973I236J1276D01*
G37*
G36*
G01X1446692Y1357346D02*
X1446700Y1357347D01*
G02X1446733Y1357348I29J-400D01*
G01X1451733D01*
G02X1451765Y1357347I3J-402D01*
G01X1451773Y1357346D01*
X1452233D01*
G02X1452633Y1356946I0J-400D01*
G01Y1350946D01*
G02X1452233Y1350546I-400J0D01*
G01X1446233D01*
G02X1445833Y1350946I0J400D01*
G01Y1356946D01*
G02X1446233Y1357346I400J0D01*
G01X1446692D01*
G37*
G36*
G01X1430800Y1382362D02*
G02X1431200Y1382762I400J0D01*
G01X1437200D01*
G02X1437600Y1382362I0J-400D01*
G01Y1376362D01*
G02X1437200Y1375962I-400J0D01*
G01X1431200D01*
G02X1430800Y1376362I0J400D01*
G01Y1382362D01*
G37*
G36*
G01X1356365Y1357346D02*
X1356824D01*
X1356832Y1357347D01*
G02X1356865Y1357348I29J-400D01*
G01X1361865D01*
G02X1361897Y1357347I3J-402D01*
G01X1361905Y1357346D01*
X1362365D01*
G02X1362765Y1356946I0J-400D01*
G01Y1350946D01*
G02X1362365Y1350546I-400J0D01*
G01X1356365D01*
G02X1355965Y1350946I0J400D01*
G01Y1356946D01*
G02X1356365Y1357346I400J0D01*
G37*
G36*
G01X1386131D02*
X1386590D01*
X1386598Y1357347D01*
G02X1386631Y1357348I29J-400D01*
G01X1391631D01*
G02X1391663Y1357347I3J-402D01*
G01X1391671Y1357346D01*
X1392131D01*
G02X1392531Y1356946I0J-400D01*
G01Y1350946D01*
G02X1392131Y1350546I-400J0D01*
G01X1386131D01*
G02X1385731Y1350946I0J400D01*
G01Y1356946D01*
G02X1386131Y1357346I400J0D01*
G37*
G36*
G01X1416467D02*
X1416926D01*
X1416934Y1357347D01*
G02X1416967Y1357348I29J-400D01*
G01X1421967D01*
G02X1421999Y1357347I3J-402D01*
G01X1422007Y1357346D01*
X1422467D01*
G02X1422867Y1356946I0J-400D01*
G01Y1350946D01*
G02X1422467Y1350546I-400J0D01*
G01X1416467D01*
G02X1416067Y1350946I0J400D01*
G01Y1356946D01*
G02X1416467Y1357346I400J0D01*
G37*
G36*
G01X1313268Y220376D02*
X1312834Y220810D01*
X1312773Y220821D01*
G02X1311631Y222199I260J1378D01*
G02X1314435I1402J0D01*
G02X1314424Y222020I-1402J-4D01*
G03X1314847Y221570I396J-51D01*
G02X1314970Y221574I120J-1798D01*
G02X1313168Y219772I0J-1802D01*
G02X1313236Y220263I1802J1D01*
G01X1313268Y220376D01*
G37*
G36*
G01X1322408Y1121961D02*
X1321601Y1123359D01*
X1321511Y1123376D01*
G02X1320456Y1124651I243J1275D01*
G02X1323050I1297J0D01*
G02X1322978Y1124223I-1298J-2D01*
G01X1322948Y1124137D01*
X1323755Y1122739D01*
X1323845Y1122722D01*
G02X1324900Y1121447I-243J-1275D01*
G02X1322306I-1297J0D01*
G02X1322378Y1121875I1298J2D01*
G01X1322408Y1121961D01*
G37*
G36*
G01X1313541Y1122224D02*
X1315165D01*
G02X1316203Y1122744I1038J-776D01*
G02Y1120150I0J-1297D01*
G02X1315165Y1120670I0J1296D01*
G01X1313541D01*
G02X1312503Y1120150I-1038J776D01*
G02Y1122744I0J1297D01*
G02X1313541Y1122224I0J-1296D01*
G37*
G36*
G01X1319091Y1106204D02*
X1320715D01*
G02X1321753Y1106724I1038J-776D01*
G02Y1104128I0J-1298D01*
G02X1320715Y1104648I0J1296D01*
G01X1319091D01*
G02X1318053Y1104128I-1038J776D01*
G02Y1106724I0J1298D01*
G02X1319091Y1106204I0J-1296D01*
G37*
G36*
G01X1327959Y1105941D02*
X1327152Y1107338D01*
X1327062Y1107355D01*
G02X1326006Y1108630I242J1275D01*
G02X1328602I1298J0D01*
G01Y1108628D01*
G02X1328529Y1108201I-1298J2D01*
G01X1328499Y1108115D01*
X1329306Y1106718D01*
X1329396Y1106701D01*
G02X1330450Y1105426I-244J-1275D01*
G02X1329153Y1104128I-1297J-1D01*
G02X1327856Y1105426I1J1298D01*
G02X1327929Y1105855I1297J0D01*
G01X1327959Y1105941D01*
G37*
G36*
G01X1326492Y1112612D02*
X1328116D01*
G02X1329154Y1113132I1038J-776D01*
G02Y1110536I0J-1298D01*
G02X1328116Y1111056I0J1296D01*
G01X1326492D01*
G02X1325454Y1110536I-1038J776D01*
G02Y1113132I0J1298D01*
G02X1326492Y1112612I0J-1296D01*
G37*
G36*
G01X1320941Y1128634D02*
X1322565D01*
G02X1323603Y1129154I1038J-776D01*
G02Y1126558I0J-1298D01*
G02X1322565Y1127078I0J1296D01*
G01X1320941D01*
G02X1319903Y1126558I-1038J776D01*
G02Y1129154I0J1298D01*
G02X1320941Y1128634I0J-1296D01*
G37*
G36*
G01X1340101Y1106718D02*
X1340908Y1108116D01*
X1340878Y1108202D01*
G02X1340806Y1108630I1226J426D01*
G02X1343400I1297J0D01*
G02X1342345Y1107355I-1298J0D01*
G01X1342255Y1107338D01*
X1341448Y1105941D01*
X1341478Y1105855D01*
G02X1341551Y1105426I-1224J-429D01*
G02X1340254Y1104128I-1297J-1D01*
G02X1338956Y1105426I0J1298D01*
G02X1340011Y1106701I1298J0D01*
G01X1340101Y1106718D01*
G37*
G36*
G01X1318709Y1109144D02*
X1317902Y1110542D01*
X1317812Y1110559D01*
G02X1316756Y1111834I242J1275D01*
G02X1319352I1298J0D01*
G02X1319279Y1111406I-1299J1D01*
G01X1319249Y1111320D01*
X1320056Y1109922D01*
X1320146Y1109905D01*
G02X1321202Y1108630I-242J-1275D01*
G02X1318606I-1298J0D01*
G02X1318679Y1109058I1299J-1D01*
G01X1318709Y1109144D01*
G37*
G36*
G01X1335359Y1112348D02*
X1334551Y1113747D01*
X1334461Y1113764D01*
G02X1333406Y1115039I243J1275D01*
G02X1336000I1297J0D01*
G01Y1115037D01*
G02X1335928Y1114610I-1298J-1D01*
G01X1335898Y1114524D01*
X1336705Y1113126D01*
X1336795Y1113109D01*
G02X1337852Y1111834I-240J-1275D01*
G02X1335256I-1298J0D01*
G02X1335329Y1112262I1299J-1D01*
G01X1335359Y1112348D01*
G37*
G36*
G01X1328342Y1101444D02*
G02X1327303Y1100924I-1039J778D01*
G02Y1103518I0J1297D01*
G02X1328342Y1102998I0J-1298D01*
G01X1329964D01*
G02X1331003Y1103518I1039J-778D01*
G02Y1100924I0J-1297D01*
G02X1329964Y1101444I0J1298D01*
G01X1328342D01*
G37*
G36*
G01X1377103Y1100309D02*
X1377910Y1101706D01*
X1377879Y1101793D01*
G02X1377806Y1102221I1225J429D01*
G02X1380402I1298J0D01*
G02X1379346Y1100946I-1298J0D01*
G01X1379256Y1100929D01*
X1378448Y1099530D01*
X1378478Y1099444D01*
G02X1378550Y1099017I-1225J-426D01*
G02X1375956I-1297J0D01*
G02X1377013Y1100292I1297J0D01*
G01X1377103Y1100309D01*
G37*
G36*
G01X1352392Y1104648D02*
G02X1351353Y1104128I-1039J778D01*
G02Y1106724I0J1298D01*
G02X1352392Y1106204I0J-1298D01*
G01X1354015D01*
G02X1355054Y1106724I1039J-778D01*
G02Y1104128I0J-1298D01*
G02X1354015Y1104648I0J1298D01*
G01X1352392D01*
G37*
G36*
G01X1356751Y1103513D02*
X1357559Y1104911D01*
X1357528Y1104998D01*
G02X1357456Y1105426I1225J426D01*
G02X1360050I1297J0D01*
G02X1358995Y1104151I-1298J0D01*
G01X1358905Y1104134D01*
X1358098Y1102737D01*
X1358128Y1102650D01*
G02X1358202Y1102221I-1223J-432D01*
G02X1355606I-1298J0D01*
G02X1356661Y1103496I1298J0D01*
G01X1356751Y1103513D01*
G37*
G36*
G01X1335742Y1107852D02*
G02X1334703Y1107332I-1039J778D01*
G02Y1109928I0J1298D01*
G02X1335742Y1109408I0J-1298D01*
G01X1337364D01*
G02X1338403Y1109928I1039J-778D01*
G02Y1107332I0J-1298D01*
G02X1337364Y1107852I0J1298D01*
G01X1335742D01*
G37*
G36*
G01X1361259Y1105941D02*
X1360452Y1107338D01*
X1360362Y1107355D01*
G02X1359306Y1108630I242J1275D01*
G02X1361902I1298J0D01*
G02X1361829Y1108202I-1298J1D01*
G01X1361798Y1108115D01*
X1362605Y1106718D01*
X1362695Y1106701D01*
G02X1363750Y1105426I-243J-1275D01*
G02X1361156I-1297J0D01*
G02X1361228Y1105855I1297J3D01*
G01X1361259Y1105941D01*
G37*
G36*
G01X1369043Y1107852D02*
G02X1368004Y1107332I-1039J778D01*
G02Y1109928I0J1298D01*
G02X1369043Y1109408I0J-1298D01*
G01X1370665D01*
G02X1371704Y1109928I1039J-778D01*
G02Y1107332I0J-1298D01*
G02X1370665Y1107852I0J1298D01*
G01X1369043D01*
G37*
G36*
G01X1373403Y1106718D02*
X1374210Y1108115D01*
X1374179Y1108202D01*
G02X1374106Y1108630I1225J429D01*
G02X1376702I1298J0D01*
G02X1375646Y1107355I-1298J0D01*
G01X1375556Y1107338D01*
X1374748Y1105939D01*
X1374778Y1105853D01*
G02X1374850Y1105426I-1225J-426D01*
G02X1372256I-1297J0D01*
G02X1373313Y1106701I1297J0D01*
G01X1373403Y1106718D01*
G37*
G36*
G01X1344609Y1109145D02*
X1343802Y1110542D01*
X1343712Y1110559D01*
G02X1342656Y1111834I242J1275D01*
G02X1345252I1298J0D01*
G02X1345179Y1111406I-1298J1D01*
G01X1345148Y1111319D01*
X1345955Y1109922D01*
X1346045Y1109905D01*
G02X1347100Y1108630I-243J-1275D01*
G02X1344506I-1297J0D01*
G02X1344578Y1109059I1297J3D01*
G01X1344609Y1109145D01*
G37*
G36*
G01X1352009Y1109143D02*
X1351201Y1110542D01*
X1351111Y1110559D01*
G02X1350056Y1111834I243J1275D01*
G02X1352650I1297J0D01*
G02X1352578Y1111406I-1297J-2D01*
G01X1352547Y1111319D01*
X1353354Y1109922D01*
X1353444Y1109905D01*
G02X1354502Y1108630I-239J-1275D01*
G02X1351906I-1298J0D01*
G02X1351979Y1109057I1298J-2D01*
G01X1352009Y1109143D01*
G37*
G36*
G01X1359792Y1111056D02*
G02X1358753Y1110536I-1039J778D01*
G02Y1113132I0J1298D01*
G02X1359792Y1112612I0J-1298D01*
G01X1361414D01*
G02X1362453Y1113132I1039J-778D01*
G02Y1110536I0J-1298D01*
G02X1361414Y1111056I0J1298D01*
G01X1359792D01*
G37*
G36*
G01X1377909Y1109143D02*
X1377101Y1110542D01*
X1377011Y1110559D01*
G02X1375956Y1111834I243J1275D01*
G02X1378550I1297J0D01*
G02X1378478Y1111406I-1297J-2D01*
G01X1378447Y1111319D01*
X1379254Y1109922D01*
X1379344Y1109905D01*
G02X1380402Y1108630I-239J-1275D01*
G02X1377806I-1298J0D01*
G02X1377879Y1109057I1298J-2D01*
G01X1377909Y1109143D01*
G37*
G36*
G01X1321601Y1113126D02*
X1322409Y1114524D01*
X1322378Y1114611D01*
G02X1322306Y1115039I1225J426D01*
G02X1324900I1297J0D01*
G02X1323845Y1113764I-1298J0D01*
G01X1323755Y1113747D01*
X1322947Y1112349D01*
X1322978Y1112262D01*
G02X1323050Y1111834I-1225J-426D01*
G02X1320456I-1297J0D01*
G02X1321511Y1113109I1298J0D01*
G01X1321601Y1113126D01*
G37*
G36*
G01X1343142Y1114262D02*
G02X1342103Y1113742I-1039J778D01*
G02Y1116336I0J1297D01*
G02X1343142Y1115816I0J-1298D01*
G01X1344764D01*
G02X1345803Y1116336I1039J-778D01*
G02Y1113742I0J-1297D01*
G02X1344764Y1114262I0J1298D01*
G01X1343142D01*
G37*
G36*
G01X1354903Y1113126D02*
X1355710Y1114524D01*
X1355679Y1114611D01*
G02X1355606Y1115039I1225J429D01*
G02X1358202I1298J0D01*
G02X1357146Y1113764I-1298J0D01*
G01X1357056Y1113747D01*
X1356248Y1112348D01*
X1356278Y1112261D01*
G02X1356350Y1111834I-1225J-426D01*
G02X1353756I-1297J0D01*
G02X1354812Y1113109I1298J0D01*
G01X1354903Y1113126D01*
G37*
G36*
G01X1368659Y1112350D02*
X1367852Y1113747D01*
X1367762Y1113764D01*
G02X1366706Y1115039I242J1275D01*
G02X1369302I1298J0D01*
G02X1369229Y1114611I-1298J1D01*
G01X1369198Y1114524D01*
X1370006Y1113126D01*
X1370096Y1113109D01*
G02X1371150Y1111834I-244J-1275D01*
G02X1368556I-1297J0D01*
G02X1368629Y1112263I1297J0D01*
G01X1368659Y1112350D01*
G37*
G36*
G01X1317902Y1119535D02*
X1318709Y1120932D01*
X1318678Y1121019D01*
G02X1318606Y1121447I1225J426D01*
G02X1321200I1297J0D01*
G02X1320145Y1120172I-1298J0D01*
G01X1320055Y1120155D01*
X1319248Y1118758D01*
X1319279Y1118671D01*
G02X1319352Y1118243I-1225J-429D01*
G02X1316756I-1298J0D01*
G02X1317812Y1119518I1298J0D01*
G01X1317902Y1119535D01*
G37*
G36*
G01X1333509Y1121962D02*
X1332702Y1123359D01*
X1332612Y1123376D01*
G02X1331556Y1124651I242J1275D01*
G02X1334152I1298J0D01*
G02X1334079Y1124223I-1298J1D01*
G01X1334048Y1124136D01*
X1334855Y1122739D01*
X1334945Y1122722D01*
G02X1336000Y1121447I-243J-1275D01*
G02X1333406I-1297J0D01*
G02X1333478Y1121876I1297J3D01*
G01X1333509Y1121962D01*
G37*
G36*
G01X1340909Y1121960D02*
X1340101Y1123359D01*
X1340011Y1123376D01*
G02X1338956Y1124651I243J1275D01*
G02X1341550I1297J0D01*
G02X1341478Y1124223I-1297J-2D01*
G01X1341447Y1124136D01*
X1342254Y1122739D01*
X1342344Y1122722D01*
G02X1343402Y1121447I-239J-1275D01*
G02X1340806I-1298J0D01*
G02X1340879Y1121874I1298J-2D01*
G01X1340909Y1121960D01*
G37*
G36*
G01X1348309D02*
X1347501Y1123359D01*
X1347411Y1123376D01*
G02X1346356Y1124651I243J1275D01*
G02X1348950I1297J0D01*
G02X1348878Y1124223I-1297J-2D01*
G01X1348847Y1124136D01*
X1349654Y1122739D01*
X1349744Y1122722D01*
G02X1350802Y1121447I-239J-1275D01*
G02X1348206I-1298J0D01*
G02X1348279Y1121874I1298J-2D01*
G01X1348309Y1121960D01*
G37*
G36*
G01X1355709D02*
X1354901Y1123359D01*
X1354811Y1123376D01*
G02X1353756Y1124651I243J1275D01*
G02X1356350I1297J0D01*
G02X1356278Y1124223I-1297J-2D01*
G01X1356247Y1124136D01*
X1357054Y1122739D01*
X1357144Y1122722D01*
G02X1358202Y1121447I-239J-1275D01*
G02X1355606I-1298J0D01*
G02X1355679Y1121874I1298J-2D01*
G01X1355709Y1121960D01*
G37*
G36*
G01X1363109D02*
X1362301Y1123359D01*
X1362211Y1123376D01*
G02X1361156Y1124651I243J1275D01*
G02X1363750I1297J0D01*
G02X1363678Y1124223I-1297J-2D01*
G01X1363647Y1124136D01*
X1364454Y1122739D01*
X1364544Y1122722D01*
G02X1365602Y1121447I-239J-1275D01*
G02X1363006I-1298J0D01*
G02X1363079Y1121874I1298J-2D01*
G01X1363109Y1121960D01*
G37*
G36*
G01X1329001Y1125943D02*
X1329809Y1127341D01*
X1329778Y1127428D01*
G02X1329706Y1127856I1225J426D01*
G02X1332300I1297J0D01*
G02X1331245Y1126581I-1298J0D01*
G01X1331155Y1126564D01*
X1330347Y1125166D01*
X1330378Y1125079D01*
G02X1330450Y1124651I-1225J-426D01*
G02X1327856I-1297J0D01*
G02X1328911Y1125926I1298J0D01*
G01X1329001Y1125943D01*
G37*
G36*
G01X1336402D02*
X1337210Y1127341D01*
X1337179Y1127428D01*
G02X1337106Y1127856I1225J429D01*
G02X1339702I1298J0D01*
G02X1338646Y1126581I-1298J0D01*
G01X1338556Y1126564D01*
X1337748Y1125166D01*
X1337779Y1125079D01*
G02X1337852Y1124651I-1225J-429D01*
G02X1335256I-1298J0D01*
G02X1336312Y1125926I1298J0D01*
G01X1336402Y1125943D01*
G37*
G36*
G01X1343803D02*
X1344610Y1127341D01*
X1344579Y1127428D01*
G02X1344506Y1127856I1225J429D01*
G02X1347102I1298J0D01*
G02X1346046Y1126581I-1298J0D01*
G01X1345956Y1126564D01*
X1345148Y1125165D01*
X1345178Y1125078D01*
G02X1345250Y1124651I-1225J-426D01*
G02X1342656I-1297J0D01*
G02X1343712Y1125926I1298J0D01*
G01X1343803Y1125943D01*
G37*
G36*
G01X1351203D02*
X1352010Y1127341D01*
X1351979Y1127428D01*
G02X1351906Y1127856I1225J429D01*
G02X1354502I1298J0D01*
G02X1353446Y1126581I-1298J0D01*
G01X1353356Y1126564D01*
X1352548Y1125165D01*
X1352578Y1125078D01*
G02X1352650Y1124651I-1225J-426D01*
G02X1350056I-1297J0D01*
G02X1351112Y1125926I1298J0D01*
G01X1351203Y1125943D01*
G37*
G36*
G01X1358603D02*
X1359410Y1127341D01*
X1359379Y1127428D01*
G02X1359306Y1127856I1225J429D01*
G02X1361902I1298J0D01*
G02X1360846Y1126581I-1298J0D01*
G01X1360756Y1126564D01*
X1359948Y1125165D01*
X1359978Y1125078D01*
G02X1360050Y1124651I-1225J-426D01*
G02X1357456I-1297J0D01*
G02X1358512Y1125926I1298J0D01*
G01X1358603Y1125943D01*
G37*
G36*
G01X1366003D02*
X1366810Y1127341D01*
X1366779Y1127428D01*
G02X1366706Y1127856I1225J429D01*
G02X1369302I1298J0D01*
G02X1368246Y1126581I-1298J0D01*
G01X1368156Y1126564D01*
X1367348Y1125165D01*
X1367378Y1125078D01*
G02X1367450Y1124651I-1225J-426D01*
G02X1364856I-1297J0D01*
G02X1365912Y1125926I1298J0D01*
G01X1366003Y1125943D01*
G37*
G36*
G01X1316051Y1129148D02*
X1316858Y1130546D01*
X1316828Y1130632D01*
G02X1316756Y1131060I1225J426D01*
G02X1319350I1297J0D01*
G02X1318295Y1129785I-1298J0D01*
G01X1318205Y1129768D01*
X1317398Y1128370D01*
X1317428Y1128284D01*
G02X1317500Y1127856I-1225J-426D01*
G02X1314906I-1297J0D01*
G02X1315961Y1129131I1298J0D01*
G01X1316051Y1129148D01*
G37*
G36*
G01X1332281Y842761D02*
X1333122Y844356D01*
X1333083Y844444D01*
G02X1332972Y844971I1186J525D01*
G02X1335566I1297J0D01*
G02X1334504Y843695I-1298J0D01*
G01X1334409Y843677D01*
X1333568Y842082D01*
X1333607Y841994D01*
G02X1333718Y841467I-1186J-525D01*
G02X1331124I-1297J0D01*
G02X1332186Y842743I1298J0D01*
G01X1332281Y842761D01*
G37*
G36*
G01X1339681D02*
X1340522Y844356D01*
X1340483Y844444D01*
G02X1340372Y844971I1186J525D01*
G02X1342966I1297J0D01*
G02X1341904Y843695I-1298J0D01*
G01X1341809Y843677D01*
X1340968Y842082D01*
X1341007Y841994D01*
G02X1341118Y841467I-1186J-525D01*
G02X1338524I-1297J0D01*
G02X1339586Y842743I1298J0D01*
G01X1339681Y842761D01*
G37*
G36*
G01X1347081D02*
X1347922Y844356D01*
X1347883Y844444D01*
G02X1347772Y844971I1186J525D01*
G02X1350366I1297J0D01*
G02X1349304Y843695I-1298J0D01*
G01X1349209Y843677D01*
X1348368Y842082D01*
X1348407Y841994D01*
G02X1348518Y841467I-1186J-525D01*
G02X1345924I-1297J0D01*
G02X1346986Y842743I1298J0D01*
G01X1347081Y842761D01*
G37*
G36*
G01X1354481D02*
X1355322Y844356D01*
X1355283Y844444D01*
G02X1355172Y844971I1186J525D01*
G02X1357766I1297J0D01*
G02X1356704Y843695I-1298J0D01*
G01X1356609Y843677D01*
X1355768Y842082D01*
X1355807Y841994D01*
G02X1355918Y841467I-1186J-525D01*
G02X1353324I-1297J0D01*
G02X1354386Y842743I1298J0D01*
G01X1354481Y842761D01*
G37*
G36*
G01X1361881D02*
X1362722Y844356D01*
X1362683Y844444D01*
G02X1362572Y844971I1186J525D01*
G02X1365166I1297J0D01*
G02X1364104Y843695I-1298J0D01*
G01X1364009Y843677D01*
X1363168Y842082D01*
X1363207Y841994D01*
G02X1363318Y841467I-1186J-525D01*
G02X1360724I-1297J0D01*
G02X1361786Y842743I1298J0D01*
G01X1361881Y842761D01*
G37*
G36*
G01X1336775Y845486D02*
X1335968Y846884D01*
X1335878Y846901D01*
G02X1334822Y848176I242J1275D01*
G02X1337418I1298J0D01*
G02X1337345Y847747I-1297J0D01*
G01X1337314Y847661D01*
X1338121Y846263D01*
X1338211Y846246D01*
G02X1339266Y844971I-243J-1275D01*
G02X1336672I-1297J0D01*
G02X1336744Y845400I1297J3D01*
G01X1336775Y845486D01*
G37*
G36*
G01X1344175D02*
X1343368Y846884D01*
X1343278Y846901D01*
G02X1342222Y848176I242J1275D01*
G02X1344818I1298J0D01*
G02X1344745Y847747I-1297J0D01*
G01X1344714Y847661D01*
X1345521Y846263D01*
X1345611Y846246D01*
G02X1346666Y844971I-243J-1275D01*
G02X1344072I-1297J0D01*
G02X1344144Y845400I1297J3D01*
G01X1344175Y845486D01*
G37*
G36*
G01X1351575D02*
X1350768Y846884D01*
X1350678Y846901D01*
G02X1349622Y848176I242J1275D01*
G02X1352218I1298J0D01*
G02X1352145Y847747I-1297J0D01*
G01X1352114Y847661D01*
X1352921Y846263D01*
X1353011Y846246D01*
G02X1354066Y844971I-243J-1275D01*
G02X1351472I-1297J0D01*
G02X1351544Y845400I1297J3D01*
G01X1351575Y845486D01*
G37*
G36*
G01X1358975D02*
X1358168Y846884D01*
X1358078Y846901D01*
G02X1357022Y848176I242J1275D01*
G02X1359618I1298J0D01*
G02X1359545Y847747I-1297J0D01*
G01X1359514Y847661D01*
X1360321Y846263D01*
X1360411Y846246D01*
G02X1361466Y844971I-243J-1275D01*
G02X1358872I-1297J0D01*
G02X1358944Y845400I1297J3D01*
G01X1358975Y845486D01*
G37*
G36*
G01X1366375D02*
X1365568Y846884D01*
X1365478Y846901D01*
G02X1364422Y848176I242J1275D01*
G02X1367018I1298J0D01*
G02X1366945Y847747I-1297J0D01*
G01X1366914Y847661D01*
X1367721Y846263D01*
X1367811Y846246D01*
G02X1368866Y844971I-243J-1275D01*
G02X1366272I-1297J0D01*
G02X1366344Y845400I1297J3D01*
G01X1366375Y845486D01*
G37*
G36*
G01X1383026Y855099D02*
X1382219Y856497D01*
X1382129Y856514D01*
G02X1381074Y857789I243J1275D01*
G02X1383668I1297J0D01*
G02X1383596Y857360I-1297J-3D01*
G01X1383565Y857274D01*
X1384372Y855876D01*
X1384462Y855859D01*
G02X1385518Y854584I-242J-1275D01*
G02X1382922I-1298J0D01*
G02X1382995Y855013I1297J0D01*
G01X1383026Y855099D01*
G37*
G36*
G01X1390426D02*
X1389619Y856497D01*
X1389529Y856514D01*
G02X1388474Y857789I243J1275D01*
G02X1391068I1297J0D01*
G02X1390996Y857360I-1297J-3D01*
G01X1390965Y857274D01*
X1391772Y855876D01*
X1391862Y855859D01*
G02X1392918Y854584I-242J-1275D01*
G02X1390322I-1298J0D01*
G02X1390395Y855013I1297J0D01*
G01X1390426Y855099D01*
G37*
G36*
G01X1397826D02*
X1397019Y856497D01*
X1396929Y856514D01*
G02X1395874Y857789I243J1275D01*
G02X1398468I1297J0D01*
G02X1398396Y857360I-1297J-3D01*
G01X1398365Y857274D01*
X1399172Y855876D01*
X1399262Y855859D01*
G02X1400318Y854584I-242J-1275D01*
G02X1397722I-1298J0D01*
G02X1397795Y855013I1297J0D01*
G01X1397826Y855099D01*
G37*
G36*
G01X1405226D02*
X1404419Y856497D01*
X1404329Y856514D01*
G02X1403274Y857789I243J1275D01*
G02X1405868I1297J0D01*
G02X1405796Y857360I-1297J-3D01*
G01X1405765Y857274D01*
X1406572Y855876D01*
X1406662Y855859D01*
G02X1407718Y854584I-242J-1275D01*
G02X1405122I-1298J0D01*
G02X1405195Y855013I1297J0D01*
G01X1405226Y855099D01*
G37*
G36*
G01X1412626Y855098D02*
X1411819Y856497D01*
X1411729Y856514D01*
G02X1410674Y857789I243J1275D01*
G02X1413268I1297J0D01*
G02X1413196Y857360I-1297J-3D01*
G01X1413165Y857274D01*
X1413972Y855876D01*
X1414062Y855859D01*
G02X1415118Y854584I-242J-1275D01*
G02X1412524I-1297J0D01*
G02X1412596Y855012I1297J2D01*
G01X1412626Y855098D01*
G37*
G36*
G01X1421070Y855876D02*
X1421877Y857274D01*
X1421846Y857361D01*
G02X1421774Y857789I1225J426D01*
G02X1424368I1297J0D01*
G02X1423313Y856514I-1298J0D01*
G01X1423223Y856497D01*
X1422415Y855098D01*
X1422445Y855011D01*
G02X1422518Y854584I-1225J-429D01*
G02X1419922I-1298J0D01*
G02X1420980Y855859I1297J0D01*
G01X1421070Y855876D01*
G37*
G36*
G01X1393319Y859081D02*
X1394126Y860478D01*
X1394095Y860565D01*
G02X1394022Y860993I1225J429D01*
G02X1396618I1298J0D01*
G02X1395562Y859718I-1298J0D01*
G01X1395472Y859701D01*
X1394665Y858304D01*
X1394696Y858217D01*
G02X1394768Y857789I-1225J-426D01*
G02X1392174I-1297J0D01*
G02X1393229Y859064I1298J0D01*
G01X1393319Y859081D01*
G37*
G36*
G01X1400719D02*
X1401526Y860478D01*
X1401495Y860565D01*
G02X1401422Y860993I1225J429D01*
G02X1404018I1298J0D01*
G02X1402962Y859718I-1298J0D01*
G01X1402872Y859701D01*
X1402065Y858304D01*
X1402096Y858217D01*
G02X1402168Y857789I-1225J-426D01*
G02X1399574I-1297J0D01*
G02X1400629Y859064I1298J0D01*
G01X1400719Y859081D01*
G37*
G36*
G01X1408120D02*
X1408927Y860478D01*
X1408896Y860565D01*
G02X1408824Y860993I1225J426D01*
G02X1411418I1297J0D01*
G02X1410363Y859718I-1298J0D01*
G01X1410273Y859701D01*
X1409466Y858303D01*
X1409496Y858217D01*
G02X1409568Y857789I-1225J-426D01*
G02X1406974I-1297J0D01*
G02X1408030Y859064I1298J0D01*
G01X1408120Y859081D01*
G37*
G36*
G01X1393939Y941018D02*
G03X1393429I-255J-308D01*
G02X1392534Y940695I-895J1078D01*
G02Y943499I0J1402D01*
G02X1393429Y943176I0J-1401D01*
G03X1393939I255J308D01*
G02X1394834Y943499I895J-1078D01*
G02Y940695I0J-1402D01*
G02X1393939Y941018I0J1401D01*
G37*
G36*
G01X1382325Y943242D02*
G03X1382835I255J308D01*
G02X1384625I895J-1078D01*
G03X1385135I255J308D01*
G02X1386030Y943565I895J-1078D01*
G02Y940761I0J-1402D01*
G02X1385135Y941084I0J1401D01*
G03X1384625I-255J-308D01*
G02X1382835I-895J1078D01*
G03X1382325I-255J-308D01*
G02X1381430Y940761I-895J1078D01*
G02Y943565I0J1402D01*
G02X1382325Y943242I0J-1401D01*
G37*
G36*
G01X1443974Y857789D02*
G02X1446568I1297J0D01*
G02X1445513Y856514I-1298J0D01*
G01X1445423Y856497D01*
X1444615Y855098D01*
X1444645Y855011D01*
G02X1444718Y854584I-1225J-429D01*
G02X1442122I-1298J0D01*
G02X1443180Y855859I1297J0D01*
G01X1443270Y855876D01*
X1444077Y857274D01*
X1444046Y857361D01*
G02X1443974Y857789I1225J426D01*
G37*
G36*
G01X1451374D02*
G02X1453968I1297J0D01*
G02X1452913Y856514I-1298J0D01*
G01X1452823Y856497D01*
X1452015Y855098D01*
X1452045Y855011D01*
G02X1452118Y854584I-1225J-429D01*
G02X1449522I-1298J0D01*
G02X1450580Y855859I1297J0D01*
G01X1450670Y855876D01*
X1451477Y857274D01*
X1451446Y857361D01*
G02X1451374Y857789I1225J426D01*
G37*
G36*
G01X1458774D02*
G02X1461368I1297J0D01*
G02X1460313Y856514I-1298J0D01*
G01X1460223Y856497D01*
X1459415Y855098D01*
X1459445Y855011D01*
G02X1459518Y854584I-1225J-429D01*
G02X1456922I-1298J0D01*
G02X1457980Y855859I1297J0D01*
G01X1458070Y855876D01*
X1458877Y857274D01*
X1458846Y857361D01*
G02X1458774Y857789I1225J426D01*
G37*
G36*
G01X1466174D02*
G02X1468768I1297J0D01*
G02X1467713Y856514I-1298J0D01*
G01X1467623Y856497D01*
X1466815Y855098D01*
X1466845Y855011D01*
G02X1466918Y854584I-1225J-429D01*
G02X1464322I-1298J0D01*
G02X1465380Y855859I1297J0D01*
G01X1465470Y855876D01*
X1466277Y857274D01*
X1466246Y857361D01*
G02X1466174Y857789I1225J426D01*
G37*
G36*
G01X1438422Y860993D02*
G02X1441018I1298J0D01*
G02X1440945Y860564I-1297J0D01*
G01X1440914Y860478D01*
X1441720Y859081D01*
X1441810Y859064D01*
G02X1442868Y857789I-239J-1275D01*
G02X1440274I-1297J0D01*
G02X1440345Y858215I1297J3D01*
G01X1440376Y858302D01*
X1439568Y859701D01*
X1439478Y859718D01*
G02X1438422Y860993I242J1275D01*
G37*
G36*
G01X1445822D02*
G02X1448418I1298J0D01*
G02X1448345Y860564I-1297J0D01*
G01X1448314Y860478D01*
X1449120Y859081D01*
X1449210Y859064D01*
G02X1450268Y857789I-239J-1275D01*
G02X1447674I-1297J0D01*
G02X1447745Y858215I1297J3D01*
G01X1447776Y858302D01*
X1446968Y859701D01*
X1446878Y859718D01*
G02X1445822Y860993I242J1275D01*
G37*
G36*
G01X1453222D02*
G02X1455818I1298J0D01*
G02X1455745Y860564I-1297J0D01*
G01X1455714Y860478D01*
X1456520Y859081D01*
X1456610Y859064D01*
G02X1457668Y857789I-239J-1275D01*
G02X1455074I-1297J0D01*
G02X1455145Y858215I1297J3D01*
G01X1455176Y858302D01*
X1454368Y859701D01*
X1454278Y859718D01*
G02X1453222Y860993I242J1275D01*
G37*
G36*
G01X1460622D02*
G02X1463218I1298J0D01*
G02X1463145Y860564I-1297J0D01*
G01X1463114Y860478D01*
X1463920Y859081D01*
X1464010Y859064D01*
G02X1465068Y857789I-239J-1275D01*
G02X1462474I-1297J0D01*
G02X1462545Y858215I1297J3D01*
G01X1462576Y858302D01*
X1461768Y859701D01*
X1461678Y859718D01*
G02X1460622Y860993I242J1275D01*
G37*
G36*
G01X1446442Y1013466D02*
G03X1445930Y1013469I-258J-306D01*
G02X1445036Y1013147I-894J1080D01*
G02Y1015951I0J1402D01*
G02X1445939Y1015622I1J-1402D01*
G03X1446451Y1015619I258J306D01*
G02X1447345Y1015941I894J-1080D01*
G02Y1013137I0J-1402D01*
G02X1446442Y1013466I-1J1402D01*
G37*
G36*
G01X1514349Y1431908D02*
G02X1514335Y1432135I1788J224D01*
G02X1516137Y1430333I1802J0D01*
G02X1515659Y1430398I2J1802D01*
G03X1515159Y1430010I-105J-381D01*
G01Y1429985D01*
G02X1513964Y1428515I-1502J0D01*
G03X1513656Y1428059I81J-387D01*
G02X1513679Y1427795I-1479J-262D01*
G02X1512213Y1426293I-1502J0D01*
G03X1511828Y1425885I10J-395D01*
G02X1511829Y1425825I-1801J-60D01*
G02X1510027Y1424023I-1802J0D01*
G01X1510025D01*
G02X1509580Y1424079I1J1802D01*
G03X1509093Y1423769I-99J-382D01*
G02X1507617Y1422543I-1476J275D01*
G02Y1425547I0J1502D01*
G02X1507788Y1425537I-2J-1502D01*
G03X1508227Y1425911I44J393D01*
G02X1510027Y1427627I1800J-86D01*
G01X1510029D01*
G02X1510244Y1427614I-1J-1802D01*
G03X1510684Y1427962I48J392D01*
G02X1511870Y1429265I1493J-167D01*
G03X1512178Y1429721I-81J387D01*
G02X1512155Y1429985I1479J262D01*
G02X1513657Y1431487I1502J0D01*
G02X1513895Y1431468I0J-1502D01*
G03X1514349Y1431908I62J390D01*
G37*
G36*
G01X1508038Y307063D02*
Y308467D01*
G02X1511040I1501J0D01*
G01Y307687D01*
X1511487Y307241D01*
G02X1511926Y306181I-1062J-1061D01*
G01Y300122D01*
G02X1511487Y299062I-1501J1D01*
G01X1510060Y297635D01*
Y291175D01*
G02X1507056I-1502J0D01*
G01Y298257D01*
G02X1507496Y299319I1502J0D01*
G01X1508924Y300746D01*
Y305557D01*
X1508477Y306003D01*
G02X1508038Y307063I1062J1061D01*
G37*
G36*
G01X1573498Y596662D02*
Y602862D01*
G02X1573900Y603264I402J0D01*
G01X1580100D01*
G02X1580502Y602862I0J-402D01*
G01Y596662D01*
G02X1580100Y596260I-402J0D01*
G01X1573900D01*
G02X1573498Y596662I0J402D01*
G37*
G36*
G01Y645662D02*
Y651862D01*
G02X1573900Y652264I402J0D01*
G01X1580100D01*
G02X1580502Y651862I0J-402D01*
G01Y645662D01*
G02X1580100Y645260I-402J0D01*
G01X1573900D01*
G02X1573498Y645662I0J402D01*
G37*
G36*
G01Y694562D02*
Y700762D01*
G02X1573900Y701164I402J0D01*
G01X1580100D01*
G02X1580502Y700762I0J-402D01*
G01Y694562D01*
G02X1580100Y694160I-402J0D01*
G01X1573900D01*
G02X1573498Y694562I0J402D01*
G37*
G36*
G01Y670062D02*
Y676262D01*
G02X1573900Y676664I402J0D01*
G01X1580100D01*
G02X1580502Y676262I0J-402D01*
G01Y670062D01*
G02X1580100Y669660I-402J0D01*
G01X1573900D01*
G02X1573498Y670062I0J402D01*
G37*
G36*
G01Y719062D02*
Y725262D01*
G02X1573900Y725664I402J0D01*
G01X1580100D01*
G02X1580502Y725262I0J-402D01*
G01Y719062D01*
G02X1580100Y718660I-402J0D01*
G01X1573900D01*
G02X1573498Y719062I0J402D01*
G37*
G36*
G01X1607012Y1004454D02*
X1611912D01*
G02Y997252I0J-3601D01*
G01X1607012D01*
G02Y1004454I0J3601D01*
G37*
G36*
G01X1621940Y997007D02*
X1619951Y998996D01*
X1619910Y999011D01*
G02X1618997Y1000325I489J1314D01*
G02X1620399Y1001727I1402J0D01*
G02X1621713Y1000814I0J-1402D01*
G01X1621728Y1000773D01*
X1623717Y998784D01*
X1623797Y998781D01*
G02X1625546Y996980I-53J-1801D01*
G02X1623744Y995178I-1802J0D01*
G02X1621943Y996927I0J1802D01*
G01X1621940Y997007D01*
G37*
G36*
G01X1607012Y1291266D02*
X1611912D01*
G02Y1284062I0J-3602D01*
G01X1607012D01*
G02Y1291266I0J3602D01*
G37*
G36*
G01X1666412D02*
X1671312D01*
G02Y1284062I0J-3602D01*
G01X1666412D01*
G02Y1291266I0J3602D01*
G37*
G36*
G01X1725812D02*
X1730712D01*
G02Y1284062I0J-3602D01*
G01X1725812D01*
G02Y1291266I0J3602D01*
G37*
G36*
G01X1785212D02*
X1790112D01*
G02Y1284062I0J-3602D01*
G01X1785212D01*
G02Y1291266I0J3602D01*
G37*
G36*
G01X1636712D02*
X1641612D01*
G02Y1284062I0J-3602D01*
G01X1636712D01*
G02Y1291266I0J3602D01*
G37*
G36*
G01X1696112D02*
X1701012D01*
G02Y1284062I0J-3602D01*
G01X1696112D01*
G02Y1291266I0J3602D01*
G37*
G36*
G01X1755512D02*
X1760412D01*
G02Y1284062I0J-3602D01*
G01X1755512D01*
G02Y1291266I0J3602D01*
G37*
G36*
G01X1806299Y1266342D02*
X1805012Y1267629D01*
Y1273959D01*
X1806399Y1275346D01*
X1819529D01*
X1820716Y1274159D01*
Y1267429D01*
X1819629Y1266342D01*
X1806299D01*
G37*
G36*
G01X1792599Y1266142D02*
X1791712Y1267029D01*
Y1274459D01*
X1792699Y1275446D01*
X1798929D01*
X1800116Y1274259D01*
Y1266929D01*
X1799329Y1266142D01*
X1792599D01*
G37*
G36*
G01X1776599D02*
X1775712Y1267029D01*
Y1274459D01*
X1776699Y1275446D01*
X1782929D01*
X1784116Y1274259D01*
Y1266929D01*
X1783329Y1266142D01*
X1776599D01*
G37*
G36*
G01X1762899D02*
X1762012Y1267029D01*
Y1274459D01*
X1762999Y1275446D01*
X1769229D01*
X1770416Y1274259D01*
Y1266929D01*
X1769629Y1266142D01*
X1762899D01*
G37*
G36*
G01X1746899D02*
X1746012Y1267029D01*
Y1274459D01*
X1746999Y1275446D01*
X1753229D01*
X1754416Y1274259D01*
Y1266929D01*
X1753629Y1266142D01*
X1746899D01*
G37*
G36*
G01X1733199D02*
X1732312Y1267029D01*
Y1274459D01*
X1733299Y1275446D01*
X1739529D01*
X1740716Y1274259D01*
Y1266929D01*
X1739929Y1266142D01*
X1733199D01*
G37*
G36*
G01X1717199D02*
X1716312Y1267029D01*
Y1274459D01*
X1717299Y1275446D01*
X1723529D01*
X1724716Y1274259D01*
Y1266929D01*
X1723929Y1266142D01*
X1717199D01*
G37*
G36*
G01X1703499D02*
X1702612Y1267029D01*
Y1274459D01*
X1703599Y1275446D01*
X1709829D01*
X1711016Y1274259D01*
Y1266929D01*
X1710229Y1266142D01*
X1703499D01*
G37*
G36*
G01X1687499D02*
X1686612Y1267029D01*
Y1274459D01*
X1687599Y1275446D01*
X1693829D01*
X1695016Y1274259D01*
Y1266929D01*
X1694229Y1266142D01*
X1687499D01*
G37*
G36*
G01X1673799D02*
X1672912Y1267029D01*
Y1274459D01*
X1673899Y1275446D01*
X1680129D01*
X1681316Y1274259D01*
Y1266929D01*
X1680529Y1266142D01*
X1673799D01*
G37*
G36*
G01X1657799D02*
X1656912Y1267029D01*
Y1274459D01*
X1657899Y1275446D01*
X1664129D01*
X1665316Y1274259D01*
Y1266929D01*
X1664529Y1266142D01*
X1657799D01*
G37*
G36*
G01X1644099D02*
X1643212Y1267029D01*
Y1274459D01*
X1644199Y1275446D01*
X1650429D01*
X1651616Y1274259D01*
Y1266929D01*
X1650829Y1266142D01*
X1644099D01*
G37*
G36*
G01X1614399D02*
X1613512Y1267029D01*
Y1274459D01*
X1614499Y1275446D01*
X1620729D01*
X1621916Y1274259D01*
Y1266929D01*
X1621129Y1266142D01*
X1614399D01*
G37*
G36*
G01X1598399D02*
X1597512Y1267029D01*
Y1274459D01*
X1598499Y1275446D01*
X1604729D01*
X1605916Y1274259D01*
Y1266929D01*
X1605129Y1266142D01*
X1598399D01*
G37*
G36*
G01X1640183Y1268656D02*
G03X1639650Y1268455I-167J-363D01*
G02X1638277Y1267563I-1373J611D01*
G02Y1270567I0J1502D01*
G02X1638906Y1270429I0J-1502D01*
G03X1639439Y1270630I167J363D01*
G02X1640812Y1271522I1373J-611D01*
G02Y1268518I0J-1502D01*
G02X1640183Y1268656I0J1502D01*
G37*
G36*
G01X1747999Y1309591D02*
G03X1747377I-311J-252D01*
G02X1746288Y1309072I-1089J883D01*
G02Y1311876I0J1402D01*
G02X1747377Y1311357I0J-1402D01*
G03X1747999I311J252D01*
G02X1749088Y1311876I1089J-883D01*
G02Y1309072I0J-1402D01*
G02X1747999Y1309591I0J1402D01*
G37*
G36*
G01X1627212Y1274459D02*
X1628199Y1275446D01*
X1634429D01*
X1635616Y1274259D01*
Y1266929D01*
X1634829Y1266142D01*
X1628099D01*
X1627731Y1266510D01*
G03X1627067Y1266347I-283J-283D01*
G02X1625729Y1265364I-1338J419D01*
G02Y1268168I0J1402D01*
G02X1626572Y1267886I0J-1401D01*
G03X1627212Y1268206I240J320D01*
G01Y1274459D01*
G37*
G36*
G01X1620179Y1388971D02*
X1621741Y1390533D01*
G02X1621760Y1390549I138J-145D01*
G01X1621789Y1390520D01*
X1707579D01*
G02X1707721Y1390461I0J-200D01*
G01X1710051Y1388131D01*
G02X1710110Y1387989I-141J-142D01*
G01Y1359745D01*
G02X1710051Y1359603I-200J0D01*
G01X1707642Y1357194D01*
G02X1707500Y1357135I-142J141D01*
G01X1706824D01*
G03X1706748Y1357120I0J-200D01*
G01X1706709Y1357104D01*
X1686180D01*
G03X1685858Y1356467I1J-400D01*
G02X1686534Y1354399I-2825J-2068D01*
G02X1679530I-3502J0D01*
G02X1680206Y1356467I3501J0D01*
G03X1679884Y1357104I-323J237D01*
G01X1661780D01*
G03X1661458Y1356467I1J-400D01*
G02X1662134Y1354399I-2825J-2068D01*
G02X1655130I-3502J0D01*
G02X1655806Y1356467I3501J0D01*
G03X1655484Y1357104I-323J237D01*
G01X1637389D01*
G03X1637068Y1356465I0J-400D01*
G02X1637761Y1354374I-2808J-2091D01*
G02X1630757I-3502J0D01*
G02X1631450Y1356465I3501J0D01*
G03X1631129Y1357104I-321J239D01*
G01X1623224D01*
G02X1623148Y1357119I0J200D01*
G01X1623110Y1357135D01*
X1622190D01*
G02X1622048Y1357194I0J200D01*
G01X1620179Y1359063D01*
G02X1620120Y1359205I141J142D01*
G01Y1388829D01*
G02X1620179Y1388971I200J0D01*
G37*
G36*
G01X1701598Y403062D02*
G03X1700983Y403049I-302J-262D01*
G02X1699809Y402483I-1175J936D01*
G02Y405487I0J1502D01*
G02X1700815Y405100I0J-1501D01*
G03X1701424Y405187I268J297D01*
G02X1702959Y406045I1535J-944D01*
G02Y402441I0J-1802D01*
G02X1701598Y403062I0J1802D01*
G37*
G36*
G01X1695201Y405439D02*
G03X1695475Y405967I-100J387D01*
G02X1695359Y406602I1686J636D01*
G02X1698963I1802J0D01*
G02X1697382Y404814I-1802J0D01*
G03X1697042Y404326I50J-397D01*
G02X1697081Y403987I-1463J-340D01*
G01Y403985D01*
G02X1695579Y402483I-1502J0D01*
G02X1694490Y402951I0J1501D01*
G03X1693878Y402914I-290J-275D01*
G02X1692429Y402183I-1449J1071D01*
G02Y405787I0J1802D01*
G02X1693878Y405056I0J-1802D01*
G03X1694490Y405019I322J238D01*
G02X1695201Y405439I1090J-1033D01*
G37*
G36*
G01X1646178Y409909D02*
G03Y410435I-302J263D01*
G02X1645808Y411422I1131J987D01*
G02X1647310Y412924I1502J0D01*
G02X1648368Y412488I0J-1502D01*
G03X1648938Y412494I282J284D01*
G02X1650020Y412954I1082J-1043D01*
G02X1651522Y411452I0J-1502D01*
G02X1651152Y410465I-1501J0D01*
G03Y409939I302J-263D01*
G02X1651522Y408952I-1131J-987D01*
G02X1650020Y407450I-1502J0D01*
G02X1648962Y407886I0J1502D01*
G03X1648392Y407880I-282J-284D01*
G02X1647310Y407420I-1082J1043D01*
G02X1645808Y408922I0J1502D01*
G02X1646178Y409909I1501J0D01*
G37*
G36*
G01X1705368Y414349D02*
G03Y414875I-302J263D01*
G02X1704998Y415862I1131J987D01*
G02X1706500Y417364I1502J0D01*
G02X1707487Y416994I0J-1501D01*
G03X1708013I263J302D01*
G02X1709000Y417364I987J-1131D01*
G02X1710502Y415862I0J-1502D01*
G02X1710132Y414875I-1501J0D01*
G03Y414349I302J-263D01*
G02X1710502Y413362I-1131J-987D01*
G02X1709625Y411996I-1502J0D01*
G03X1709427Y411470I167J-363D01*
G02X1709582Y410740I-1647J-731D01*
G01Y410738D01*
G02X1705978I-1802J0D01*
G02X1706126Y411452I1802J-1D01*
G03X1705914Y411979I-367J158D01*
G02X1704998Y413362I586J1383D01*
G02X1705368Y414349I1501J0D01*
G37*
G36*
G01X1635877Y437167D02*
G03Y437797I-246J315D01*
G02X1635298Y438982I923J1185D01*
G02X1636800Y440484I1502J0D01*
G02X1637985Y439905I0J-1502D01*
G03X1638615I315J246D01*
G02X1639800Y440484I1185J-923D01*
G02X1641302Y438982I0J-1502D01*
G02X1640723Y437797I-1502J0D01*
G03Y437167I246J-315D01*
G02Y434797I-923J-1185D01*
G03Y434167I246J-315D01*
G02Y431797I-923J-1185D01*
G03Y431167I246J-315D01*
G02Y428797I-923J-1185D01*
G03Y428167I246J-315D01*
G02X1641302Y426982I-923J-1185D01*
G02X1639800Y425480I-1502J0D01*
G02X1638615Y426059I0J1502D01*
G03X1637985I-315J-246D01*
G02X1636800Y425480I-1185J923D01*
G02X1635298Y426982I0J1502D01*
G02X1635877Y428167I1502J0D01*
G03Y428797I-246J315D01*
G02Y431167I923J1185D01*
G03Y431797I-246J315D01*
G02Y434167I923J1185D01*
G03Y434797I-246J315D01*
G02Y437167I923J1185D01*
G37*
G36*
G01X1680761Y620962D02*
X1680763D01*
G02X1685001I2119J-2787D01*
G01X1685003D01*
G02X1686385Y618174I-2121J-2788D01*
G02X1679379I-3503J0D01*
G02X1680761Y620962I3503J0D01*
G37*
G36*
G01X1758724Y1539079D02*
Y1496017D01*
G02X1758372Y1495167I-1201J0D01*
G01X1757317Y1494112D01*
G02X1756467Y1493760I-850J849D01*
G01X1722988D01*
G02X1722138Y1494112I0J1201D01*
G01X1722000Y1494250D01*
G02X1721648Y1495100I849J850D01*
G01Y1539079D01*
G02X1722000Y1539929I1201J0D01*
G01X1723965Y1541894D01*
Y1541895D01*
G02X1724815Y1542248I851J-849D01*
G01X1755557D01*
G02X1756407Y1541895I-1J-1202D01*
G01Y1541894D01*
X1758372Y1539929D01*
G02X1758724Y1539079I-849J-850D01*
G37*
G36*
G01X1828421Y1499228D02*
G03Y1499777I-291J274D01*
G02X1828012Y1500807I1092J1030D01*
G02X1829514Y1502309I1502J0D01*
G02X1830541Y1501903I0J-1502D01*
G03X1831087I273J292D01*
G02X1832114Y1502309I1027J-1096D01*
G02X1833616Y1500807I0J-1502D01*
G02X1833207Y1499777I-1501J0D01*
G03Y1499228I291J-275D01*
G02X1833616Y1498198I-1092J-1030D01*
G02X1832114Y1496696I-1502J0D01*
G02X1831087Y1497102I0J1502D01*
G03X1830541I-273J-292D01*
G02X1829514Y1496696I-1027J1096D01*
G02X1828012Y1498198I0J1502D01*
G02X1828421Y1499228I1501J0D01*
G37*
G36*
G01X1793960Y1506902D02*
X1794672D01*
G02X1795759Y1507368I1087J-1035D01*
G01X1799814D01*
G02X1800801Y1506997I-1J-1502D01*
G02X1802252Y1505230I-350J-1767D01*
G02X1800450Y1503428I-1802J0D01*
G02X1798869Y1504364I0J1803D01*
G01X1796620D01*
X1796568Y1504328D01*
G02X1796057Y1504166I-512J728D01*
G01X1795764D01*
X1795750Y1504165D01*
G02X1795545Y1504150I-212J1487D01*
G02X1795340Y1504165I7J1502D01*
G01X1795326Y1504166D01*
X1795004D01*
Y1504246D01*
X1794891Y1504301D01*
G02X1794712Y1504402I647J1355D01*
G01X1793960D01*
Y1506902D01*
G37*
G36*
G01X1794060Y1516791D02*
Y1523733D01*
G02X1793759Y1524729I1501J997D01*
G02X1797363I1802J0D01*
G02X1797062Y1523733I-1802J1D01*
G01Y1517413D01*
X1802537Y1511938D01*
X1809747D01*
G02X1809952Y1511924I0J-1501D01*
G01X1809966Y1511922D01*
X1810288D01*
Y1511843D01*
X1810401Y1511788D01*
G02X1810580Y1511686I-652J-1352D01*
G01X1812087D01*
X1813101Y1512701D01*
G02X1814131Y1513128I1030J-1029D01*
G01X1816354D01*
G02X1817384Y1512701I0J-1456D01*
G01X1818282Y1511802D01*
X1818343Y1511791D01*
G02Y1508251I-339J-1770D01*
G01X1818282Y1508240D01*
X1816904Y1506861D01*
G02X1815874Y1506434I-1030J1029D01*
G01X1814362D01*
X1814339Y1506429D01*
G02X1813994Y1506389I-344J1462D01*
G02X1812492Y1507891I0J1502D01*
G02X1812585Y1508413I1502J2D01*
G03X1812356Y1508924I-375J139D01*
G01Y1509079D01*
X1812245Y1509135D01*
G02X1812149Y1509188I655J1300D01*
G01X1810580D01*
G02X1810401Y1509086I-831J1250D01*
G01X1810288Y1509031D01*
Y1508952D01*
X1809966D01*
X1809952Y1508950D01*
G02X1809747Y1508936I-205J1487D01*
G01X1801915D01*
G02X1800853Y1509375I-1J1501D01*
G01X1794499Y1515729D01*
G02X1794060Y1516791I1062J1061D01*
G37*
G36*
G01X1795948Y201632D02*
Y207632D01*
G02X1796350Y208034I402J0D01*
G01X1802350D01*
G02X1802752Y207632I0J-402D01*
G01Y201632D01*
G02X1802350Y201230I-402J0D01*
G01X1796350D01*
G02X1795948Y201632I0J402D01*
G37*
G36*
G01X1766388D02*
Y207632D01*
G02X1766790Y208034I402J0D01*
G01X1772790D01*
G02X1773192Y207632I0J-402D01*
G01Y201632D01*
G02X1772790Y201230I-402J0D01*
G01X1766790D01*
G02X1766388Y201632I0J402D01*
G37*
G36*
G01X1779860Y289510D02*
X1786670Y296320D01*
Y301450D01*
X1788320Y303100D01*
X1813660D01*
X1816190Y305630D01*
X1831280D01*
X1832230Y304680D01*
Y260680D01*
X1830860Y259310D01*
X1818400D01*
X1816350Y261360D01*
Y275060D01*
X1815860Y275550D01*
X1797590D01*
X1794000Y279140D01*
X1780480D01*
X1779860Y279760D01*
Y289510D01*
G37*
G36*
G01X1786951Y83067D02*
G03X1786823Y83611I-342J207D01*
G02X1785988Y85132I968J1521D01*
G02X1789592I1802J0D01*
G02X1789178Y83983I-1801J0D01*
G03X1789223Y83426I308J-255D01*
G02X1789740Y82292I-985J-1134D01*
G02X1786736I-1502J0D01*
G02X1786951Y83067I1502J1D01*
G37*
G54D130*
X95849Y716358D03*
X219752Y1398599D03*
X279277Y99183D03*
X292942Y67513D03*
Y71499D03*
X284482Y569548D03*
X509246Y1420002D03*
X576220Y1423862D03*
X555057Y1449395D03*
X571620Y1424492D03*
X692784Y1298845D03*
X748033Y116288D03*
X747230Y108572D03*
X716612Y1584635D03*
X774982Y446908D03*
X821164Y372312D03*
X848000Y374622D03*
X830600Y449200D03*
X840400Y418900D03*
X844200Y418800D03*
X833300Y386500D03*
X825003Y397276D03*
X823600Y421194D03*
X871320Y416752D03*
X839200Y434300D03*
X809800Y360600D03*
X818000Y378800D03*
X846040Y399210D03*
X832400Y427100D03*
X824980Y413260D03*
X870700Y390620D03*
X824980Y409260D03*
X870700Y394620D03*
Y402581D03*
X824980Y405260D03*
X979380Y373082D03*
X1110663Y1719189D03*
X1161076Y1680624D03*
X1088790Y1641830D03*
X1108320Y1680200D03*
X1113110Y1666460D03*
X1084000Y1647110D03*
X1157700Y1681100D03*
X1114300Y1722700D03*
X1106480Y1641275D03*
X1031702Y264130D03*
X1156609Y1286685D03*
X1099030Y245140D03*
X1148795Y213731D03*
X1148354Y222677D03*
X1146670Y230110D03*
X1160630Y213870D03*
X1158172Y230157D03*
X1183460Y205342D03*
X1256454Y252122D03*
X1522258Y288956D03*
X1713720Y381152D03*
Y391652D03*
Y384652D03*
Y388152D03*
X1717220Y391652D03*
Y388152D03*
Y384652D03*
X1699110Y727452D03*
X1726120Y1490262D03*
X1818289Y1501591D03*
X1811494Y1505349D03*
X1824995Y1502201D03*
X1813700Y1494762D03*
X1758063Y68637D03*
X1764400Y57462D03*
X1759700Y57662D03*
X1758568Y79697D03*
X1758573Y83607D03*
X1758063Y72623D03*
X1754234Y190836D03*
X1749450Y293862D03*
X1778478Y90627D03*
G54D133*
X219752Y1401999D03*
Y1405499D03*
X570645Y1361358D03*
X571555Y1352487D03*
X1783018Y301729D03*
G54D132*
X174393Y668511D03*
X393067Y1354446D03*
X422833D03*
X453169D03*
X718638Y1429579D03*
X1178470Y1466363D03*
X1682882Y669109D03*
X1679944Y1463655D03*
G54D141*
X728172Y474707D03*
X725022Y471557D03*
Y465258D03*
X718723Y452659D03*
Y449510D03*
Y458959D03*
X721873Y462108D03*
X728172Y468407D03*
X734471Y481006D03*
X725022Y468407D03*
X731322Y477856D03*
X728172Y471557D03*
G54D140*
X569236Y1441207D03*
X559236D03*
X1099970Y1712570D03*
G54D145*
X1459076Y1353946D03*
X1444043Y1379362D03*
X1429310Y1353946D03*
X1369208D03*
X1398974D03*
G54D139*
X340061Y1095813D03*
X338211Y1105426D03*
X539861Y1076587D03*
X536162Y1082996D03*
X541711Y1073383D03*
X1314353Y1105426D03*
X1316203Y1095813D03*
X1512304Y1082996D03*
X1516003Y1076587D03*
X1517853Y1073383D03*
G54D135*
X275289Y599861D03*
Y624015D03*
Y575702D03*
X278126Y676260D03*
X275289Y648169D03*
X493293Y1242785D03*
X395771D03*
X420171D03*
X468893D03*
X444493D03*
X1100700Y275788D03*
X1100800Y251488D03*
X1371912Y1242785D03*
X1469434D03*
X1396312D03*
X1445034D03*
X1420634D03*
X1577000Y616388D03*
Y591888D03*
Y640888D03*
Y714288D03*
Y689788D03*
Y665288D03*
G54D131*
X83004Y705141D03*
X417960Y1650072D03*
X661400Y1263522D03*
X729933Y108388D03*
X736720Y101662D03*
X745035Y94632D03*
X735770Y94988D03*
X741308Y108742D03*
X750700Y106642D03*
X838784Y392880D03*
X846490Y422131D03*
X857560Y417762D03*
X856842Y410760D03*
X868113Y409372D03*
X859740Y399081D03*
X940410Y188852D03*
X979766Y377507D03*
X949560Y981392D03*
X1114150Y1715726D03*
X1037618Y261200D03*
X1025004Y374662D03*
X1044930Y1263492D03*
X1120190Y255652D03*
X1124360Y259712D03*
X1181470Y208802D03*
X1181500Y222162D03*
X1172795Y222174D03*
X1191020Y170862D03*
X1208518Y174162D03*
X1266715Y244692D03*
X1265065Y249982D03*
X1320387Y258901D03*
X1498984Y282797D03*
X1517669Y291516D03*
X1505922Y304583D03*
X1683500Y1264312D03*
X1701124Y423802D03*
X1694050Y416643D03*
X1695455Y422287D03*
X1707544Y431745D03*
X1707568Y420370D03*
X1807150Y1505675D03*
X1746484Y279682D03*
X1781485Y88192D03*
G54D134*
X244299Y991011D03*
X421462Y1095813D03*
X458462Y1102221D03*
X504712Y1105426D03*
X456611Y1099017D03*
X460312Y1105426D03*
X480661Y1095813D03*
X464012Y1105426D03*
X419612Y1099017D03*
X469562Y1095813D03*
X484361Y1140973D03*
X504712Y1111833D03*
X447361Y1121447D03*
X480662Y1134264D03*
X506561Y1102220D03*
X502861Y1108629D03*
X508412Y1105426D03*
X460312Y1099016D03*
X512112Y1111833D03*
X464012Y1099017D03*
X447361Y1115039D03*
Y1127856D03*
X467712Y1124651D03*
X464012Y1111834D03*
X467711Y1105426D03*
X423312Y1137469D03*
X480662Y1108630D03*
X434412Y1137769D03*
X434411Y1060565D03*
X476961Y1115039D03*
X478811Y1105426D03*
X482511Y1099017D03*
X478811Y1111834D03*
X473262Y1102221D03*
X471411Y1099017D03*
X482511Y1105426D03*
X471411Y1111834D03*
X482511D03*
X478811Y1099017D03*
X473262Y1108630D03*
X469562Y1102221D03*
X475112Y1099017D03*
X475111Y1111834D03*
X476962Y1102221D03*
X484362Y1108630D03*
X469562D03*
X447361D03*
X489911Y1131060D03*
X488062Y1134264D03*
X502862Y1102221D03*
X488061D03*
X491762Y1115039D03*
X446930Y973144D03*
Y979553D03*
X491761Y1140973D03*
X447361Y1102221D03*
X506562Y1108630D03*
X508411Y1099017D03*
X475111Y1118243D03*
X504711Y1099017D03*
X510262Y1134264D03*
X499161Y1127856D03*
X491761D03*
X493611Y1105426D03*
X456611Y1086200D03*
X434411Y1124651D03*
X430712Y1047749D03*
X417761Y1115039D03*
X421462D03*
X452911Y1086200D03*
X434411Y1028524D03*
X451062Y1089404D03*
X452911Y1099017D03*
X458462Y1115039D03*
X473262D03*
Y1121447D03*
X434411Y1131060D03*
X480662Y1121447D03*
X434411Y1009298D03*
X476962Y1108630D03*
X475111Y1105426D03*
X469561Y1115039D03*
X480662Y1102221D03*
X484362D03*
X471411Y1105426D03*
X458462Y1134264D03*
X446930Y966736D03*
Y953918D03*
Y960327D03*
Y947510D03*
X428861Y1095813D03*
X434411Y1086200D03*
Y1092608D03*
X432561Y1082995D03*
Y1089404D03*
X425162D03*
X428861Y1082995D03*
X430711Y1066974D03*
X428862Y1070178D03*
X434411Y1079791D03*
X427012D03*
X434411Y1066974D03*
Y1073383D03*
X432561Y1076587D03*
X434412Y1002889D03*
X415912Y1099017D03*
X417762Y1095813D03*
X430711Y1073383D03*
X432560Y1070178D03*
X428861Y1063770D03*
X433980Y982757D03*
X415911Y1118243D03*
X478811Y1131060D03*
X428862Y1044544D03*
X471412Y1137469D03*
X432561Y1095813D03*
X447362Y1018911D03*
X465861Y1102221D03*
X417762D03*
X423311Y1124651D03*
X434412Y1034932D03*
X423311Y1131060D03*
Y1099017D03*
X480661Y1115039D03*
X434411Y1118243D03*
X433980Y950714D03*
X434411Y1111834D03*
X484362Y1115039D03*
X433980Y957123D03*
X513961Y1095813D03*
X476961Y1095812D03*
X458462Y1121447D03*
X471411Y1118243D03*
X447362Y1031728D03*
X449212Y1086200D03*
X415911Y1092608D03*
X451062Y1095813D03*
X462162Y1102221D03*
X517662Y1095813D03*
X433980Y963531D03*
X447362Y1006094D03*
Y999685D03*
X545411Y1118243D03*
X484361Y1127856D03*
X434411Y1022115D03*
X476961Y1127856D03*
X475111Y1131060D03*
X471412D03*
X476961Y1140973D03*
X447362Y1012502D03*
X497312Y1111834D03*
X469561Y1140973D03*
X484362Y1095813D03*
X467711Y1111834D03*
Y1099017D03*
X462162Y1108630D03*
X473261Y1134264D03*
X465861Y1108630D03*
X482511Y1131060D03*
X473262Y1095813D03*
X508412Y1111833D03*
X460311Y1092608D03*
X506561Y1115038D03*
X427012Y1041340D03*
X423311Y1118243D03*
X425161Y1102221D03*
X447361Y1134264D03*
X452911Y1092608D03*
X447360Y1038136D03*
X423311Y1111834D03*
X482511Y1118243D03*
X433980Y944305D03*
X478811Y1118243D03*
X469562Y1127856D03*
X433980Y976348D03*
X434412Y1015706D03*
X417761Y1089404D03*
X433980Y969940D03*
X497311Y1118243D03*
X458461Y1089403D03*
X538010Y1118242D03*
X467711Y1118243D03*
X447362Y1025319D03*
X513962Y1102221D03*
X465862Y1121447D03*
X458462Y1127856D03*
X465862Y1115039D03*
X501012Y1105426D03*
X510261Y1108630D03*
X501012Y1111833D03*
X515811Y1111834D03*
X495462Y1121447D03*
X488062D03*
X493611Y1131060D03*
X497311D03*
X512112Y1099017D03*
X497312Y1105426D03*
X491762Y1102221D03*
X486211Y1131060D03*
X495462Y1115039D03*
X488062D03*
X539861Y1108630D03*
X427011Y1099017D03*
X421462Y1102221D03*
Y1108630D03*
X434411Y1105426D03*
X423311D03*
X538011D03*
X488062Y1095813D03*
X502862Y1134264D03*
X495462Y1095813D03*
X517662Y1108630D03*
X501011Y1131060D03*
X486211Y1105426D03*
X497311Y1099017D03*
X493612Y1118243D03*
X495462Y1134264D03*
Y1102221D03*
X512111Y1131060D03*
X508411Y1118243D03*
X491762Y1095813D03*
X499161Y1140973D03*
X541711Y1131060D03*
X543562Y1115039D03*
X513961Y1140973D03*
X521362Y1108630D03*
X525062Y1134264D03*
X530611Y1118243D03*
X528762Y1121447D03*
X523211Y1118243D03*
X499161Y1102221D03*
X534311Y1111834D03*
X528762Y1102221D03*
X525062D03*
X530611Y1105426D03*
X493611Y1099017D03*
X526911Y1111834D03*
X519511D03*
X528762Y1108630D03*
X499161D03*
X486212Y1099017D03*
X502862Y1095813D03*
X488062Y1108630D03*
X510262Y1102221D03*
X491762Y1108630D03*
X493611Y1111834D03*
X486211D03*
X506561Y1127856D03*
X489911Y1105426D03*
X454761Y1089403D03*
X543561Y1121446D03*
X521361Y1115039D03*
X499161D03*
X489911Y1118243D03*
X501011Y1099017D03*
X513962Y1108630D03*
X515811Y1131060D03*
X545411Y1124651D03*
X530611D03*
X523212Y1099017D03*
X532461Y1115039D03*
X502862D03*
X536162Y1134264D03*
X543561Y1108630D03*
X523211Y1105426D03*
X534311D03*
X510262Y1121447D03*
X517662D03*
X502862D03*
X504711Y1118243D03*
X536161Y1095813D03*
X515811Y1105426D03*
X523211Y1111834D03*
X489911D03*
X534311Y1131060D03*
X460311Y1086200D03*
X499162Y1095813D03*
X504711Y1131060D03*
X508411D03*
X532460Y1102221D03*
X501011Y1118243D03*
X528761Y1095813D03*
X534311Y1124650D03*
X506561Y1140973D03*
X517662Y1115039D03*
X495462Y1108630D03*
X519512Y1099017D03*
X541711Y1118243D03*
X545412Y1105426D03*
X517662Y1134264D03*
X526911Y1099017D03*
X532461Y1108630D03*
X521361Y1102221D03*
X512111Y1118243D03*
X521361Y1140973D03*
X532461Y1127855D03*
X526911Y1105426D03*
X489911Y1099017D03*
X536161Y1115039D03*
X528761Y1134264D03*
X519511Y1131060D03*
Y1118243D03*
X515811D03*
X519511Y1105426D03*
X538011Y1124651D03*
X513961Y1115039D03*
X512112Y1105426D03*
X528761Y1127856D03*
X510261Y1115039D03*
X538011Y1111834D03*
X528762Y1115039D03*
X525062Y1121447D03*
X526911Y1118243D03*
X530612Y1131060D03*
Y1137469D03*
X534311Y1118243D03*
X525062Y1115039D03*
X521361Y1127856D03*
X534311Y1099017D03*
X513961Y1127856D03*
X523211Y1131060D03*
X526912D03*
X536161Y1121446D03*
X532461D03*
X530612Y1111834D03*
X539861Y1121446D03*
X465861Y1095812D03*
X462161D03*
X458461D03*
X541711Y1105426D03*
X454761Y1095812D03*
X539862Y1115039D03*
X536161Y1108630D03*
X539861Y1102221D03*
X545411Y1111834D03*
X541711D03*
X536161Y1102221D03*
X486211Y1118243D03*
X525062Y1108630D03*
X456612Y1092607D03*
X539861Y1127855D03*
X543561D03*
X538012Y1131059D03*
X541711Y1124650D03*
X536161Y1127855D03*
X373361Y1108630D03*
X386312Y1099017D03*
X373361Y1102221D03*
X380762Y1108630D03*
X378911Y1099017D03*
X386311Y1131060D03*
X382611Y1118243D03*
X384462Y1102221D03*
X358561Y1127856D03*
X360411Y1118243D03*
X365962Y1127856D03*
X356711Y1118243D03*
X367811D03*
X390011Y1131060D03*
X395561Y1115039D03*
X364111Y1118243D03*
X388161Y1115039D03*
Y1127856D03*
X390011Y1118243D03*
X371511D03*
X362261Y1115039D03*
X388162Y1102221D03*
X356711Y1099017D03*
X336361Y1115039D03*
Y1127856D03*
X364112Y1111834D03*
X371512D03*
X356712D03*
X401112Y1092608D03*
X338211Y1124651D03*
X390011Y1111834D03*
X401111Y1105426D03*
X360412Y1131060D03*
X384462Y1095813D03*
X397411Y1111834D03*
X349311Y1124651D03*
X390011Y1105426D03*
X340061Y1115039D03*
X356712Y1092608D03*
X358561Y1095813D03*
X365962D03*
X354861Y1108630D03*
X343761Y1134264D03*
X353011Y1131060D03*
X343707Y1091513D03*
X395562Y1102221D03*
X371512Y1105426D03*
X365962Y1102221D03*
X402962Y1095813D03*
X343761Y1102221D03*
X351161Y1115039D03*
X391862Y1095813D03*
X347461Y1108630D03*
X362262Y1102221D03*
X360411Y1099017D03*
X378911Y1092608D03*
X340061Y1102221D03*
X397412Y1099017D03*
X378911Y1118243D03*
X377062Y1102221D03*
X373362Y1095813D03*
X386311Y1118243D03*
X388162Y1108630D03*
X353011Y1099017D03*
X399262Y1102221D03*
X371511Y1131060D03*
X367811D03*
X356712D03*
X375211Y1092608D03*
X338211Y1111834D03*
X343761Y1115039D03*
X353011Y1092608D03*
X345611Y1131060D03*
X349311D03*
X354861Y1115039D03*
X351161Y1121447D03*
X345611Y1118243D03*
X373361Y1115039D03*
X341911Y1124651D03*
X349312Y1118243D03*
X347461Y1102221D03*
X377061Y1115039D03*
X375211Y1118243D03*
X340061Y1108630D03*
X380761Y1127856D03*
X373361D03*
X384461Y1115039D03*
X356711Y1105426D03*
X382611Y1092608D03*
X349311Y1099017D03*
X399261Y1095813D03*
X349310Y1092609D03*
X364112Y1131060D03*
X371512Y1099017D03*
X382611Y1131060D03*
X375211D03*
X378911D03*
X375211Y1099017D03*
X389579Y841467D03*
X367379D03*
X359979D03*
X369229Y851380D03*
X384029D03*
X372929D03*
X376629D03*
X380329D03*
X382179Y841467D03*
X374779D03*
X365529Y851380D03*
X387729D03*
X441379Y854584D03*
X445078Y848176D03*
X446929Y851380D03*
X439529D03*
X441378Y848176D03*
X443228Y851380D03*
X437680Y860992D03*
X419179Y854584D03*
X424729Y851380D03*
X428429D03*
X435829D03*
X413629D03*
X417329D03*
X406229D03*
X409929D03*
X404379Y854584D03*
X411779D03*
X421029Y851380D03*
X432129D03*
X433979Y854584D03*
X439529Y844671D03*
X439528Y857789D03*
X448779Y854584D03*
X426579D03*
X402529Y851380D03*
X432130Y928283D03*
X435830D03*
X432130Y934692D03*
X443230D03*
X439530Y928283D03*
Y934692D03*
X445079Y931487D03*
X450630Y928283D03*
X437679Y931487D03*
X430279D03*
X435830Y934692D03*
X443230Y928283D03*
X446930Y934692D03*
X448780Y931487D03*
X400678Y957122D03*
X396978D03*
X400678Y969939D03*
X395129Y973143D03*
X396979Y969939D03*
X400678Y963530D03*
X398829Y966735D03*
X396979Y950713D03*
X402529Y960326D03*
X395129Y953917D03*
X398828Y960326D03*
X547262Y1082996D03*
X538011Y1073383D03*
X515811Y1086200D03*
X510262Y1070178D03*
X489911Y1086200D03*
X536161Y1076587D03*
X521361Y1070178D03*
X502862Y1076587D03*
X489911Y1079791D03*
X508411D03*
X515811Y1073383D03*
X523212Y1079791D03*
X515811D03*
X489911Y1073383D03*
X532462Y1082996D03*
X510262Y1076587D03*
X495461Y1089404D03*
X512111Y1073383D03*
X502862Y1070178D03*
X486211Y1073383D03*
X497312Y1079791D03*
X499161Y1082995D03*
X528762Y1089404D03*
X536162Y1070178D03*
X534311Y1086200D03*
X528762Y1082995D03*
X525061D03*
X519512Y1073383D03*
X528762Y1070178D03*
X493612Y1073383D03*
X495462Y1076587D03*
X534311Y1079791D03*
X528762Y1076587D03*
X521362D03*
X508412Y1086200D03*
X523211D03*
X521361Y1089404D03*
X478812Y1086199D03*
X471412D03*
X476961Y1082994D03*
X473261Y1089403D03*
X475112Y1086199D03*
X469561Y1089404D03*
X482512Y1086200D03*
X484362Y1089404D03*
X476962D03*
X452911Y1073383D03*
X469562Y1076587D03*
X467712Y1086200D03*
X473262Y1082995D03*
X482511Y1073383D03*
X480662Y1082995D03*
X469560Y1070178D03*
X502862Y1089404D03*
X467711Y1079791D03*
X484362Y1070178D03*
X469562Y1082995D03*
X462162Y1070178D03*
X467711Y1073383D03*
X464011D03*
X465862Y1076587D03*
X478812Y1079791D03*
X460311Y1073383D03*
X471411Y1079791D03*
X476962Y1070178D03*
X475111Y1073383D03*
X480662Y1089404D03*
X473262Y1076587D03*
X480662Y1070178D03*
X475111Y1079791D03*
X465860Y1070178D03*
X480662Y1076587D03*
X476962D03*
X454762Y1070178D03*
X482511Y1079791D03*
X458460Y1070178D03*
X456611Y1073383D03*
X478811D03*
X454761Y1076587D03*
X484361D03*
X471411Y1073383D03*
X473262Y1070178D03*
X497311Y1086200D03*
X502862Y1082995D03*
X495461Y1070178D03*
X506562Y1082995D03*
X536161Y1089404D03*
X510262D03*
X465429Y864197D03*
X470979Y867401D03*
X476529Y864197D03*
X472829D03*
X478379Y854584D03*
X470979D03*
X483929Y864197D03*
X480229D03*
X469129D03*
X463579Y867401D03*
X495029Y851380D03*
X491329D03*
X487629D03*
X493179Y854584D03*
X495029Y864197D03*
X491329D03*
X485779Y854584D03*
X476529Y851380D03*
X470979Y873810D03*
X472828Y870606D03*
X493179Y867401D03*
X485779D03*
X461729Y864197D03*
X483929Y851380D03*
X487629Y864197D03*
X469129Y851380D03*
X472829D03*
X480229D03*
X470979Y841467D03*
X478379Y867401D03*
X620899Y991011D03*
X629599D03*
X1030780Y1266532D03*
X1074480Y1263742D03*
X1211741Y991011D03*
X1220441D03*
X1519703Y1127855D03*
X1477154Y1111833D03*
X1519703Y1121446D03*
X1517853Y1124650D03*
X1512303Y1121446D03*
X1484554Y1105426D03*
X1480854D03*
X1486403Y1108630D03*
X1477154Y1105426D03*
X1488254D03*
X1458654Y1092607D03*
X1484554Y1111833D03*
X1480854D03*
X1482703Y1115038D03*
X1488254Y1111833D03*
X1434603Y1095812D03*
X1438303D03*
X1442003D03*
X1432754Y1092607D03*
X1430903Y1095812D03*
X1516003Y1121446D03*
X1482703Y1102220D03*
X1508603Y1127855D03*
X1510453Y1124650D03*
X1514154Y1131059D03*
X1512303Y1127855D03*
X1453103Y1095812D03*
X1393903Y1089404D03*
X1392053Y1092608D03*
X1395754Y1099017D03*
X1393904Y1095813D03*
Y1102221D03*
X1392054Y1099017D03*
X1393903Y1115039D03*
X1392053Y1118243D03*
X1410121Y944304D03*
Y957122D03*
Y950713D03*
Y963530D03*
Y976347D03*
Y969939D03*
Y982756D03*
X1410553Y1009297D03*
Y1002888D03*
Y1028523D03*
Y1022114D03*
Y1015705D03*
X1405004Y1044544D03*
X1410553Y1034931D03*
X1406854Y1047749D03*
X1403154Y1041340D03*
X1408703Y1050952D03*
X1410553Y1060565D03*
Y1054157D03*
X1408703Y1057361D03*
Y1063770D03*
X1405004Y1050952D03*
X1405003Y1063770D03*
X1406853Y1060565D03*
X1408703Y1076587D03*
X1406853Y1073383D03*
X1410553D03*
Y1066974D03*
X1403154Y1079791D03*
X1410553D03*
X1408702Y1070178D03*
X1405004D03*
X1406853Y1066974D03*
X1408703Y1089404D03*
Y1082995D03*
X1405003D03*
X1401304Y1089404D03*
X1410553Y1092608D03*
Y1086200D03*
X1408703Y1095813D03*
X1405003D03*
X1397604D03*
X1403153Y1099017D03*
X1401303Y1102221D03*
X1399453Y1105426D03*
X1397604Y1108630D03*
X1410553Y1105426D03*
X1399453Y1111834D03*
X1410553D03*
X1397604Y1102221D03*
X1399453Y1099017D03*
Y1124651D03*
Y1118243D03*
X1397604Y1115039D03*
X1410553Y1124651D03*
Y1118243D03*
X1399454Y1137469D03*
X1399453Y1131060D03*
X1410554Y1137769D03*
X1410553Y1131060D03*
X1423071Y947509D03*
Y960326D03*
Y953917D03*
Y966735D03*
Y979552D03*
Y973143D03*
X1423503Y1006093D03*
Y999684D03*
Y1012501D03*
Y1025318D03*
Y1018910D03*
Y1031727D03*
Y1038136D03*
X1429053Y1092608D03*
X1427204Y1089404D03*
X1425354Y1086200D03*
X1427203Y1095812D03*
X1429053Y1086200D03*
Y1099017D03*
X1423503Y1108630D03*
Y1102221D03*
Y1121447D03*
Y1115039D03*
Y1127856D03*
Y1134264D03*
X1436453Y1092608D03*
X1443854D03*
X1436454Y1105426D03*
X1434604Y1102221D03*
X1432753Y1099017D03*
X1442003Y1108630D03*
Y1102221D03*
X1440154Y1105426D03*
Y1099017D03*
X1438304Y1108630D03*
X1440154Y1111834D03*
X1443853Y1105426D03*
Y1111834D03*
X1438304Y1102221D03*
X1443853Y1099017D03*
X1434604Y1121447D03*
Y1115039D03*
X1443854Y1124651D03*
X1443853Y1118243D03*
X1442004Y1121447D03*
Y1115039D03*
X1434604Y1127856D03*
Y1134264D03*
X1445704Y1095813D03*
X1460504D03*
X1456803D03*
X1449404D03*
X1445704Y1102221D03*
X1458653Y1105426D03*
X1456804Y1108630D03*
X1454953Y1099017D03*
X1449404Y1108630D03*
X1453104Y1102221D03*
X1451254Y1099017D03*
X1447553D03*
X1458653Y1111834D03*
X1460504Y1108630D03*
X1451253Y1111834D03*
X1447553D03*
X1454953Y1105426D03*
X1445704Y1108630D03*
X1449404Y1102221D03*
X1458653Y1099017D03*
X1454953Y1111834D03*
X1453104Y1108630D03*
X1447553Y1105426D03*
X1451253D03*
X1460504Y1102221D03*
X1456804D03*
X1445703Y1115039D03*
X1458653Y1118243D03*
X1456803Y1115039D03*
X1454953Y1118243D03*
X1453103Y1115039D03*
X1451253Y1118243D03*
X1447553D03*
X1445704Y1127856D03*
X1460503D03*
X1453103D03*
X1460504Y1115039D03*
X1449404D03*
X1456804Y1121447D03*
X1449404D03*
X1445703Y1140973D03*
X1458653Y1131060D03*
X1454953D03*
X1453103Y1140973D03*
X1451253Y1131060D03*
X1447554Y1137469D03*
Y1131060D03*
X1449403Y1134264D03*
X1460503Y1140973D03*
X1456804Y1134264D03*
X1462353Y1092608D03*
X1469754D03*
X1466053D03*
X1475304Y1095813D03*
X1471604D03*
X1467904D03*
X1464204D03*
X1462353Y1105426D03*
X1462354Y1099017D03*
X1475303Y1108630D03*
Y1102221D03*
X1473454Y1105426D03*
X1469753D03*
X1467904Y1102221D03*
X1464203D03*
X1473454Y1111834D03*
X1466053D03*
Y1099017D03*
X1471604Y1102221D03*
X1477153Y1099017D03*
X1469753D03*
X1473453D03*
X1471604Y1108630D03*
X1466053Y1105426D03*
X1462353Y1111834D03*
X1469753D03*
X1467904Y1108630D03*
X1464204D03*
X1462353Y1118243D03*
X1477153D03*
X1475303Y1115039D03*
X1473453Y1118243D03*
X1471604Y1121447D03*
X1469754Y1118243D03*
X1466053D03*
X1475303Y1127856D03*
X1467903D03*
X1467904Y1115039D03*
X1471604D03*
X1464204D03*
Y1121447D03*
X1462353Y1131060D03*
X1477153D03*
X1475303Y1140973D03*
X1473453Y1131060D03*
X1469753D03*
X1466053D03*
X1467903Y1140973D03*
X1471604Y1134264D03*
X1464204D03*
X1488254Y1092608D03*
X1491954D03*
X1479004Y1095813D03*
X1490103D03*
X1493804D03*
X1479004Y1102221D03*
X1490104Y1108630D03*
Y1102221D03*
X1488254Y1099017D03*
X1484553D03*
X1482704Y1108630D03*
X1480853Y1099017D03*
X1491953Y1105426D03*
Y1111834D03*
X1493804Y1108630D03*
X1486404Y1102221D03*
X1490103Y1115039D03*
X1488253Y1118243D03*
X1484553D03*
X1480853D03*
X1486403Y1115039D03*
X1491953Y1118243D03*
X1490103Y1127856D03*
X1482703D03*
X1493804Y1115039D03*
X1479004D03*
Y1121447D03*
X1493804D03*
X1486404D03*
X1490103Y1140973D03*
X1488253Y1131060D03*
X1484553D03*
X1480853D03*
X1482703Y1140973D03*
X1491953Y1131060D03*
X1479004Y1134264D03*
X1493804D03*
X1486404D03*
X1495653Y1092608D03*
X1504903Y1095813D03*
X1503053Y1105426D03*
X1497503Y1102221D03*
X1495653Y1105426D03*
X1495654Y1099017D03*
X1508603Y1108630D03*
X1506754Y1111834D03*
X1499353D03*
X1503053Y1099017D03*
X1510453D03*
X1508602Y1102221D03*
X1497504Y1108630D03*
X1501204D03*
X1510453Y1111834D03*
X1499353Y1105426D03*
X1510453D03*
X1504904Y1108630D03*
X1495653Y1111834D03*
X1503053D03*
X1506753Y1105426D03*
X1504904Y1102221D03*
X1501204D03*
X1499354Y1099017D03*
X1506753Y1124651D03*
Y1118243D03*
X1504904Y1121447D03*
X1499353Y1118243D03*
X1497503Y1115039D03*
X1495653Y1118243D03*
X1508603Y1115039D03*
X1504904Y1127856D03*
X1497503D03*
X1501204Y1115039D03*
X1504904D03*
X1503053Y1118243D03*
X1510453D03*
X1501204Y1121447D03*
X1506754Y1137469D03*
X1506753Y1131060D03*
X1503053D03*
X1499353D03*
X1495653D03*
X1504904Y1134264D03*
X1497503Y1140973D03*
X1510453Y1131060D03*
X1501204Y1134264D03*
X1514153Y1092608D03*
X1512303Y1095813D03*
X1521554Y1105426D03*
X1517853D03*
X1516003Y1108630D03*
Y1102221D03*
X1512303D03*
X1517853Y1111834D03*
X1521553D03*
X1514153Y1105426D03*
X1512303Y1108630D03*
X1514153Y1111834D03*
X1519703Y1108630D03*
X1521553Y1124651D03*
Y1118243D03*
X1519704Y1115039D03*
X1516004D03*
X1514153Y1124651D03*
X1512303Y1115039D03*
X1517853Y1118243D03*
X1517854Y1131560D03*
X1512304Y1134264D03*
X1516003Y1127855D03*
X1508603Y1121446D03*
X1479003Y1108629D03*
X1454954Y1092607D03*
X1430903Y1089403D03*
X1436454Y1099016D03*
X1440154Y1092607D03*
X1447554D03*
X1451254D03*
X1313027Y185199D03*
X1313032Y214799D03*
X1309833Y220349D03*
X1316242Y209249D03*
X1309828Y224049D03*
X1319442Y218499D03*
X1325852Y214799D03*
X1319442Y207399D03*
X1325852Y211099D03*
X1322652Y209249D03*
X1325857Y218499D03*
X1322652Y216649D03*
X1319442Y222199D03*
X1325856D03*
X1322652Y224049D03*
Y220349D03*
X1314353Y1111834D03*
X1311486Y1097289D03*
X1314353Y1124651D03*
X1312503Y1115039D03*
Y1127856D03*
X1329153Y1092608D03*
X1325452Y1092609D03*
X1323603Y1089404D03*
X1319849Y1091513D03*
X1331003Y1108630D03*
X1329153Y1099017D03*
X1323603Y1108630D03*
X1316203D03*
Y1102221D03*
X1325453Y1099017D03*
X1323603Y1102221D03*
X1319903D03*
X1316203Y1115039D03*
X1331003D03*
X1327303Y1121447D03*
Y1115039D03*
X1325453Y1124651D03*
X1325454Y1118243D03*
X1321753D03*
X1319903Y1115039D03*
X1318053Y1124651D03*
X1329153Y1131060D03*
X1321753D03*
X1325453D03*
X1319903Y1134264D03*
X1342104Y1089404D03*
X1334703D03*
X1332854Y1092608D03*
X1342104Y1095813D03*
X1334703D03*
X1342104Y1102221D03*
X1338404D03*
X1336553Y1099017D03*
X1332853Y1105426D03*
Y1099017D03*
X1347654Y1105426D03*
Y1099017D03*
X1340254Y1111834D03*
X1332854D03*
X1347654D03*
X1343953Y1118243D03*
X1340253D03*
X1338403Y1115039D03*
X1336553Y1118243D03*
X1332853D03*
X1347653D03*
X1342104Y1127856D03*
X1334703D03*
X1343953Y1131060D03*
X1340254D03*
X1336554D03*
X1332854D03*
X1347653D03*
X1360603Y1089404D03*
X1358753Y1092608D03*
X1355053D03*
X1351353D03*
X1349504Y1089404D03*
X1360604Y1095813D03*
X1349504D03*
X1362454Y1099017D03*
X1360604Y1102221D03*
X1356904Y1108630D03*
X1355053Y1099017D03*
X1353204Y1102221D03*
X1349503Y1108630D03*
Y1102221D03*
X1362453Y1118243D03*
X1360603Y1115039D03*
X1358753Y1118243D03*
X1355053D03*
X1353203Y1115039D03*
X1351353Y1118243D03*
X1349503Y1115039D03*
X1356903Y1127856D03*
X1349503D03*
X1362453Y1131060D03*
X1358753D03*
X1355053D03*
X1351353D03*
X1377254Y1092608D03*
X1375404Y1089404D03*
X1368004D03*
X1379104Y1095813D03*
X1375403D03*
X1368004D03*
X1364304Y1108630D03*
Y1102221D03*
X1377253Y1105426D03*
X1375404Y1102221D03*
X1373554Y1099017D03*
X1371704Y1102221D03*
X1366153Y1105426D03*
X1373553Y1111834D03*
X1366153D03*
X1364303Y1115039D03*
X1371703D03*
X1369853Y1118243D03*
X1366153D03*
X1364303Y1127856D03*
X1371703D03*
X1373553Y1131060D03*
X1369853D03*
X1366153D03*
X1382804Y1095813D03*
X1380954Y1105426D03*
X1382803Y1108630D03*
Y1102221D03*
X1380954Y1111834D03*
X1351354Y1099017D03*
X1329062Y168549D03*
Y172249D03*
X1343521Y841467D03*
X1336121D03*
X1345371Y851380D03*
X1341671D03*
X1358321Y841467D03*
X1350921D03*
X1360171Y851380D03*
X1356471D03*
X1352771D03*
X1349071D03*
X1363871D03*
X1365721Y841467D03*
X1339727Y183349D03*
Y187049D03*
X1346147Y198149D03*
X1378671Y851380D03*
X1393471D03*
X1389771D03*
X1386071D03*
X1382371D03*
X1380521Y854584D03*
X1395321D03*
X1387921D03*
X1397171Y851380D03*
X1408271D03*
X1404571D03*
X1400871D03*
X1411971D03*
X1402721Y854584D03*
X1410121D03*
X1421220Y848176D03*
X1423070Y851380D03*
X1419370D03*
X1415671D03*
X1413822Y860993D03*
X1424921Y854584D03*
X1417521D03*
X1415671Y857789D03*
X1411971Y934691D03*
X1408271Y928283D03*
X1406420Y931488D03*
X1411971Y928283D03*
X1408271Y934691D03*
X1424921Y931488D03*
X1419371Y928283D03*
X1413820Y931488D03*
X1419371Y934691D03*
X1421220Y931488D03*
X1415671Y928283D03*
X1426771D03*
X1423071Y934691D03*
X1415671D03*
X1376820Y957122D03*
X1374970Y960326D03*
X1373120Y957122D03*
X1373121Y950713D03*
X1371271Y953917D03*
X1376820Y963530D03*
X1374971Y966735D03*
X1378671Y960326D03*
X1376820Y969939D03*
X1373121D03*
X1371271Y973143D03*
X1451254Y1086199D03*
X1523404Y1082996D03*
X1514153Y1073383D03*
X1512303Y1076587D03*
X1510453Y1086200D03*
X1508604Y1082996D03*
X1501203Y1082995D03*
X1504904D03*
X1499353Y1086200D03*
X1510453Y1079791D03*
X1499354D03*
X1495654Y1073383D03*
X1497503Y1070178D03*
X1497504Y1076587D03*
X1504904Y1070178D03*
Y1076587D03*
X1491953Y1086200D03*
X1482704Y1082995D03*
X1484554Y1086200D03*
X1479004Y1082995D03*
X1491953Y1079791D03*
X1484553D03*
X1491953Y1073383D03*
X1488253D03*
X1486404Y1070178D03*
Y1076587D03*
X1479004Y1070178D03*
Y1076587D03*
X1466053Y1086200D03*
X1473453D03*
X1475303Y1082995D03*
X1466053Y1079791D03*
X1473454D03*
X1466053Y1073383D03*
X1471603Y1070178D03*
X1469754Y1073383D03*
X1471604Y1076587D03*
X1462353Y1073383D03*
X1445704Y1082995D03*
X1449404D03*
X1456804D03*
X1458654Y1086200D03*
X1458653Y1073383D03*
X1451253D03*
X1447553Y1079791D03*
X1445704Y1076587D03*
X1449404D03*
X1447553Y1073383D03*
X1453104Y1070178D03*
X1456804D03*
Y1076587D03*
X1453104D03*
X1445702Y1070178D03*
X1451253Y1079791D03*
X1454954D03*
X1458653D03*
X1454953Y1073383D03*
X1460504Y1070178D03*
X1449404D03*
X1460503Y1076587D03*
X1443854Y1086200D03*
X1440153Y1073383D03*
X1442004Y1076587D03*
X1442002Y1070178D03*
X1434602D03*
X1436453Y1073383D03*
X1443853Y1079791D03*
X1438304Y1070178D03*
X1443853Y1073383D03*
X1430904Y1070178D03*
X1430903Y1076587D03*
X1432753Y1073383D03*
X1429053D03*
X1453103Y1082994D03*
X1447554Y1086199D03*
X1454954D03*
X1445271Y851380D03*
X1447121Y841467D03*
X1460071Y851380D03*
X1452671D03*
X1456371D03*
X1448971D03*
X1454521Y854584D03*
X1447121D03*
X1471171Y851380D03*
X1467471D03*
X1463771D03*
X1461921Y854584D03*
X1469321D03*
X1597041Y991011D03*
X1605741D03*
X1626741D03*
G54D136*
X566510Y1352217D03*
X505777Y1425579D03*
X1645300Y612202D03*
G54D146*
X1769790Y194789D03*
X1799350D03*
X1836248Y269763D03*
Y299056D03*
G54D137*
X525062Y1095813D03*
X530611Y1099017D03*
X517662Y1102221D03*
X510262Y1095813D03*
X515811Y1099017D03*
X506561Y1095813D03*
X521362D03*
X532461D03*
X354429Y979552D03*
X372929Y953917D03*
X387729Y947509D03*
X385878Y944304D03*
X363678Y957122D03*
X369229Y979552D03*
X372929Y973143D03*
X384029D03*
X361829Y960326D03*
X384029Y953917D03*
X367378Y950713D03*
Y976347D03*
X371078Y963530D03*
X367378Y969939D03*
X380329Y947509D03*
X376629D03*
X385878Y963530D03*
X363678Y969939D03*
X347029Y973143D03*
X387729Y979552D03*
X358129Y953917D03*
X359978Y963530D03*
X350729Y953917D03*
X369229Y960326D03*
X367378Y957122D03*
X350729Y966735D03*
X348878Y976347D03*
X350729Y960326D03*
X348878Y969939D03*
X350729Y947509D03*
X387729Y960326D03*
X374778Y957122D03*
X350729Y979552D03*
X354429Y953917D03*
X356278Y950713D03*
X354429Y960326D03*
X358129Y973143D03*
X387729Y966735D03*
X356278Y957122D03*
X376629Y979552D03*
X363678Y950713D03*
X382178Y976347D03*
X374778D03*
X361829Y979552D03*
Y966735D03*
X369229D03*
X363678Y944304D03*
Y976347D03*
X371078Y944304D03*
X382178Y950713D03*
X348878Y957122D03*
X380329Y966735D03*
X354429Y947509D03*
Y966735D03*
X356278Y969939D03*
Y976347D03*
X347030Y953917D03*
X374778Y969939D03*
X359978Y982756D03*
X363678D03*
X367378D03*
X371078D03*
X380329Y979552D03*
X385878Y982756D03*
X382178Y969939D03*
X348878Y950713D03*
X361829Y947509D03*
X376629Y953917D03*
X369229Y947509D03*
X359978Y944304D03*
X376629Y966735D03*
X374778Y950713D03*
X382178Y957122D03*
X376629Y960326D03*
X367378Y944304D03*
X380329Y960326D03*
Y953917D03*
X369662Y1095813D03*
X390011Y1099017D03*
X364111Y1092608D03*
X386311D03*
X360411D03*
X388162Y1095813D03*
X390011Y1092608D03*
X393711Y1099017D03*
Y1092608D03*
X395562Y1095813D03*
X397411Y1092608D03*
X367811Y1099017D03*
X364111D03*
X367811Y1092608D03*
X362262Y1095813D03*
X371511Y1092608D03*
X393278Y969939D03*
X396978Y963530D03*
X393278D03*
Y957122D03*
X395129Y966735D03*
X402529Y973143D03*
X398829D03*
X395129Y960326D03*
X393278Y950713D03*
X486211Y1086200D03*
X530611D03*
X510262Y1082995D03*
X513962D03*
X517662Y1089404D03*
X526911Y1086200D03*
X495462Y1082995D03*
X491762D03*
X488062D03*
X499162Y1089404D03*
X517662Y1070178D03*
Y1076587D03*
X504711Y1073383D03*
X512111Y1086200D03*
X513962Y1089404D03*
X488062D03*
X512111Y1079791D03*
X513962Y1076587D03*
X519511Y1086200D03*
X506562Y1076587D03*
X508411Y1073383D03*
X517662Y1082995D03*
X493611Y1086200D03*
X506562Y1089404D03*
X513962Y1070178D03*
X504711Y1079791D03*
X491762Y1089404D03*
X521362Y1082995D03*
X501011Y1086200D03*
Y1073383D03*
X497311D03*
X499162Y1076587D03*
X501011Y1079791D03*
X499162Y1070178D03*
X486211Y1079791D03*
X488062Y1076587D03*
X493611Y1079791D03*
X491762Y1076587D03*
X488062Y1070178D03*
X491762D03*
X506562D03*
X525062Y1089404D03*
X484362Y1082995D03*
X504711Y1086200D03*
X530611Y1079791D03*
Y1073383D03*
X519511Y1079791D03*
X526911Y1073383D03*
X534311D03*
X523211D03*
X525062Y1076587D03*
X526911Y1079791D03*
X532462Y1070178D03*
X525062D03*
X532462Y1076587D03*
Y1089404D03*
X1506753Y1092608D03*
X1510452D03*
X1503053D03*
X1508603Y1095813D03*
X1499353Y1092608D03*
X1501204Y1095813D03*
X1497504D03*
X1506753Y1099017D03*
X1480853Y1092608D03*
X1484553D03*
X1482703Y1095813D03*
X1491953Y1099017D03*
X1493804Y1102221D03*
X1486404Y1095813D03*
X1477153Y1092608D03*
X1473453D03*
X1356471Y966735D03*
X1360171Y953917D03*
X1356471D03*
X1358320Y957122D03*
X1356471Y960326D03*
X1358320Y950713D03*
X1352771Y966735D03*
Y953917D03*
X1349071D03*
X1350920Y957122D03*
X1352771Y960326D03*
X1350920Y950713D03*
X1360171Y973143D03*
X1358320Y976347D03*
X1356471Y979552D03*
X1362020Y982756D03*
X1358320Y969939D03*
X1349071Y973143D03*
X1350920Y976347D03*
X1352771Y979552D03*
X1350920Y969939D03*
X1362020Y944304D03*
X1356471Y947509D03*
X1352771D03*
X1362020Y963530D03*
X1347220Y982756D03*
X1339820D03*
X1343520D03*
X1334271Y973143D03*
X1332420Y969939D03*
Y976347D03*
X1336120Y982756D03*
X1343520Y950713D03*
X1339820D03*
X1334271Y953917D03*
X1332420Y957122D03*
X1336120Y963530D03*
X1332420Y950713D03*
X1343520Y969939D03*
X1339820D03*
Y976347D03*
X1337971Y979552D03*
X1343520Y976347D03*
X1337971Y960326D03*
X1345371Y966735D03*
X1337971D03*
X1347220Y963530D03*
X1343520Y957122D03*
X1345371Y947509D03*
X1337971D03*
X1339820Y944304D03*
X1347220D03*
X1343520D03*
X1336120D03*
X1345371Y960326D03*
X1339820Y957122D03*
X1325020Y976347D03*
X1330571Y979552D03*
X1326871D03*
Y960326D03*
X1330571Y947509D03*
X1326871D03*
X1323172Y953917D03*
X1330571D03*
X1326871D03*
X1330571Y966735D03*
X1326871D03*
X1345371Y979552D03*
X1323171Y973143D03*
X1325020Y969939D03*
Y950713D03*
Y957122D03*
X1330571Y960326D03*
X1369853Y1099017D03*
X1366153D03*
X1373553Y1092608D03*
X1369853D03*
X1371704Y1089404D03*
Y1095813D03*
X1366153Y1092608D03*
X1364304Y1095813D03*
Y1089404D03*
X1362453Y1092608D03*
X1353204Y1089404D03*
X1356904D03*
X1343953Y1092608D03*
X1336553D03*
X1345804Y1089404D03*
X1338404D03*
X1345804Y1095813D03*
X1338404D03*
X1343953Y1099017D03*
X1340253D03*
X1347653Y1092608D03*
X1331003Y1089404D03*
X1327303D03*
X1340253Y1092608D03*
X1369420Y950713D03*
X1378671Y973143D03*
X1374971D03*
X1369420Y969939D03*
X1373120Y963530D03*
X1371271Y966735D03*
Y960326D03*
X1369420Y963530D03*
Y957122D03*
X1469753Y1086200D03*
X1462353Y1079791D03*
X1464204Y1076587D03*
X1467904D03*
X1464204Y1070178D03*
X1467904D03*
X1475304D03*
X1477153Y1079791D03*
X1475304Y1076587D03*
X1473453Y1073383D03*
X1477153D03*
X1469753Y1079791D03*
X1464204Y1082995D03*
X1467904D03*
X1480853Y1086200D03*
X1490104Y1082995D03*
X1486404D03*
X1493804D03*
X1462353Y1086200D03*
X1471604Y1082995D03*
X1477153Y1086200D03*
X1482704Y1076587D03*
X1488253Y1079791D03*
X1490104Y1076587D03*
X1493804D03*
Y1070178D03*
X1490104D03*
X1482704D03*
X1484553Y1073383D03*
X1480853D03*
Y1079791D03*
X1488253Y1086200D03*
X1497504Y1082995D03*
X1495653Y1086200D03*
X1503053D03*
X1506753D03*
X1460504Y1082995D03*
X1506753Y1079791D03*
X1508604Y1076587D03*
Y1070178D03*
X1503053Y1079791D03*
X1510453Y1073383D03*
X1503053D03*
X1506753D03*
X1501204Y1076587D03*
Y1070178D03*
X1495653Y1079791D03*
X1499353Y1073383D03*
G54D144*
X1066280Y1704890D03*
G54D147*
X1766929Y1714960D03*
G54D138*
X525275Y1171319D03*
X356062D03*
X1332204D03*
X1501417D03*
G54D142*
X805690Y204724D03*
X1057658D03*
G54D143*
X841240Y1420330D03*
X1016240D03*
%LPD*%
G75*
G36*
G01X28546Y1272964D02*
X30046Y1274464D01*
X34046D01*
X35546Y1272964D01*
Y1267964D01*
X35046Y1267464D01*
X29046D01*
X28546Y1267964D01*
Y1272964D01*
G37*
G36*
G01X44546D02*
X46046Y1274464D01*
X50046D01*
X51546Y1272964D01*
Y1267964D01*
X51046Y1267464D01*
X45046D01*
X44546Y1267964D01*
Y1272964D01*
G37*
G36*
G01X58246D02*
X59746Y1274464D01*
X63746D01*
X65246Y1272964D01*
Y1267964D01*
X64746Y1267464D01*
X58746D01*
X58246Y1267964D01*
Y1272964D01*
G37*
G36*
G01X74246D02*
X75746Y1274464D01*
X79746D01*
X81246Y1272964D01*
Y1267964D01*
X80746Y1267464D01*
X74746D01*
X74246Y1267964D01*
Y1272964D01*
G37*
G36*
G01X87946D02*
X89446Y1274464D01*
X93446D01*
X94946Y1272964D01*
Y1267964D01*
X94446Y1267464D01*
X88446D01*
X87946Y1267964D01*
Y1272964D01*
G37*
G36*
G01X103946D02*
X105446Y1274464D01*
X109446D01*
X110946Y1272964D01*
Y1267964D01*
X110446Y1267464D01*
X104446D01*
X103946Y1267964D01*
Y1272964D01*
G37*
G36*
G01X117646D02*
X119146Y1274464D01*
X123146D01*
X124646Y1272964D01*
Y1267964D01*
X124146Y1267464D01*
X118146D01*
X117646Y1267964D01*
Y1272964D01*
G37*
G36*
G01X133646D02*
X135146Y1274464D01*
X139146D01*
X140646Y1272964D01*
Y1267964D01*
X140146Y1267464D01*
X134146D01*
X133646Y1267964D01*
Y1272964D01*
G37*
G36*
G01X147346D02*
X148846Y1274464D01*
X152846D01*
X154346Y1272964D01*
Y1267964D01*
X153846Y1267464D01*
X147846D01*
X147346Y1267964D01*
Y1272964D01*
G37*
G36*
G01X163346D02*
X164846Y1274464D01*
X168846D01*
X170346Y1272964D01*
Y1267964D01*
X169846Y1267464D01*
X163846D01*
X163346Y1267964D01*
Y1272964D01*
G37*
G36*
G01X177046D02*
X178546Y1274464D01*
X182546D01*
X184046Y1272964D01*
Y1267964D01*
X183546Y1267464D01*
X177546D01*
X177046Y1267964D01*
Y1272964D01*
G37*
G36*
G01X200046D02*
Y1267964D01*
X199546Y1267464D01*
X191769D01*
X191317Y1267916D01*
Y1273670D01*
X192111Y1274464D01*
X198546D01*
X200046Y1272964D01*
G37*
G36*
G01X213746D02*
Y1267964D01*
X213246Y1267464D01*
X206116D01*
X205238Y1268342D01*
Y1273821D01*
X205881Y1274464D01*
X212246D01*
X213746Y1272964D01*
G37*
G36*
G01X222746D02*
X224246Y1274464D01*
X228246D01*
X229746Y1272964D01*
Y1267964D01*
X229246Y1267464D01*
X223246D01*
X222746Y1267964D01*
Y1272964D01*
G37*
G36*
G01X236446D02*
X237946Y1274464D01*
X241946D01*
X243446Y1272964D01*
Y1267964D01*
X242946Y1267464D01*
X236946D01*
X236446Y1267964D01*
Y1272964D01*
G37*
G36*
G01X252446D02*
X253946Y1274464D01*
X257946D01*
X259446Y1272964D01*
Y1267964D01*
X258946Y1267464D01*
X252946D01*
X252446Y1267964D01*
Y1272964D01*
G37*
G36*
G01X405242Y1153033D02*
Y1170033D01*
X406399Y1171190D01*
X413329D01*
X414381Y1170138D01*
Y1152648D01*
X413595Y1151863D01*
X406412D01*
X405242Y1153033D01*
G37*
G36*
G01X438367Y1151863D02*
X431184D01*
X430189Y1152858D01*
Y1170170D01*
X431209Y1171190D01*
X438249D01*
X439327Y1170112D01*
Y1152822D01*
X438367Y1151863D01*
G37*
G36*
G01X464379Y1152902D02*
X463399Y1151922D01*
X456059D01*
X455229Y1152752D01*
Y1170178D01*
X456300Y1171249D01*
X463329D01*
X464379Y1170199D01*
Y1152902D01*
G37*
G36*
G01X480229Y1171160D02*
X480810Y1171741D01*
X483808D01*
X484359Y1171190D01*
Y1152671D01*
X483819Y1152131D01*
X480839D01*
X480229Y1152741D01*
Y1171160D01*
G37*
G36*
G01X621746Y1272964D02*
X623246Y1274464D01*
X627246D01*
X628746Y1272964D01*
Y1267964D01*
X628246Y1267464D01*
X622246D01*
X621746Y1267964D01*
Y1272964D01*
G37*
G36*
G01X637746D02*
X639246Y1274464D01*
X643246D01*
X644746Y1272964D01*
Y1267964D01*
X644246Y1267464D01*
X638246D01*
X637746Y1267964D01*
Y1272964D01*
G37*
G36*
G01X651446D02*
X652946Y1274464D01*
X656946D01*
X658446Y1272964D01*
Y1267964D01*
X657946Y1267464D01*
X651946D01*
X651446Y1267964D01*
Y1272964D01*
G37*
G36*
G01X667446D02*
X668946Y1274464D01*
X672946D01*
X674446Y1272964D01*
Y1267964D01*
X673946Y1267464D01*
X667946D01*
X667446Y1267964D01*
Y1272964D01*
G37*
G36*
G01X681146D02*
X682646Y1274464D01*
X686646D01*
X688146Y1272964D01*
Y1267964D01*
X687646Y1267464D01*
X681646D01*
X681146Y1267964D01*
Y1272964D01*
G37*
G36*
G01X708890Y453462D02*
X709650D01*
X709950Y453162D01*
Y452112D01*
X709560Y451722D01*
X708780D01*
X708510Y451452D01*
Y450722D01*
X708740Y450492D01*
X709572D01*
X710110Y449954D01*
Y449072D01*
X709610Y448572D01*
X708780D01*
X708510Y448302D01*
Y447532D01*
X708735Y447307D01*
X709135D01*
X709250Y447192D01*
Y445572D01*
X709060Y445382D01*
X708720D01*
X708510Y445172D01*
Y444402D01*
X708740Y444172D01*
X709593D01*
X710150Y443615D01*
Y442942D01*
X709510Y442302D01*
X708790D01*
X708520Y442032D01*
Y441222D01*
X708720Y441022D01*
X709594D01*
X710230Y440386D01*
Y439852D01*
X710040Y439662D01*
X708480D01*
X705250Y442892D01*
Y443632D01*
X704900Y443982D01*
X701050D01*
X700800Y443732D01*
Y443002D01*
X697080Y439282D01*
X696280D01*
X695860Y439702D01*
Y440492D01*
X696420Y441052D01*
X697220D01*
X697440Y441272D01*
Y441992D01*
X697200Y442232D01*
X696410D01*
X695870Y442772D01*
Y443685D01*
X696387Y444202D01*
X697220D01*
X697440Y444422D01*
Y445142D01*
X697210Y445372D01*
X696830D01*
X696500Y445702D01*
Y447022D01*
X696820Y447342D01*
X697210D01*
X697440Y447572D01*
Y448292D01*
X697210Y448522D01*
X696480D01*
X695925Y449077D01*
Y450027D01*
X696400Y450502D01*
X697220D01*
X697440Y450722D01*
Y451442D01*
X697210Y451672D01*
X696390D01*
X695880Y452182D01*
Y453042D01*
X696240Y453402D01*
X697050D01*
X700780Y449672D01*
Y448982D01*
X701010Y448752D01*
X704930D01*
X705170Y448992D01*
Y449742D01*
X708890Y453462D01*
G37*
G36*
G01X697146Y1272964D02*
X698646Y1274464D01*
X702646D01*
X704146Y1272964D01*
Y1267964D01*
X703646Y1267464D01*
X697646D01*
X697146Y1267964D01*
Y1272964D01*
G37*
G36*
G01X710846D02*
X712346Y1274464D01*
X716346D01*
X717846Y1272964D01*
Y1267964D01*
X717346Y1267464D01*
X711346D01*
X710846Y1267964D01*
Y1272964D01*
G37*
G36*
G01X726846D02*
X728346Y1274464D01*
X732346D01*
X733846Y1272964D01*
Y1267964D01*
X733346Y1267464D01*
X727346D01*
X726846Y1267964D01*
Y1272964D01*
G37*
G36*
G01X740546D02*
X742046Y1274464D01*
X746046D01*
X747546Y1272964D01*
Y1267964D01*
X747046Y1267464D01*
X741046D01*
X740546Y1267964D01*
Y1272964D01*
G37*
G36*
G01X756546D02*
X758046Y1274464D01*
X762046D01*
X763546Y1272964D01*
Y1267964D01*
X763046Y1267464D01*
X757046D01*
X756546Y1267964D01*
Y1272964D01*
G37*
G36*
G01X770246D02*
X771746Y1274464D01*
X775746D01*
X777246Y1272964D01*
Y1267964D01*
X776746Y1267464D01*
X770746D01*
X770246Y1267964D01*
Y1272964D01*
G37*
G36*
G01X786246D02*
X787746Y1274464D01*
X791746D01*
X793246Y1272964D01*
Y1267964D01*
X792746Y1267464D01*
X786746D01*
X786246Y1267964D01*
Y1272964D01*
G37*
G36*
G01X799946D02*
X801446Y1274464D01*
X805446D01*
X806946Y1272964D01*
Y1267964D01*
X806446Y1267464D01*
X800446D01*
X799946Y1267964D01*
Y1272964D01*
G37*
G36*
G01X815946D02*
X817446Y1274464D01*
X821446D01*
X822946Y1272964D01*
Y1267964D01*
X822446Y1267464D01*
X816446D01*
X815946Y1267964D01*
Y1272964D01*
G37*
G36*
G01X844046Y1272764D02*
Y1267564D01*
X843646Y1267164D01*
X830446D01*
X829646Y1267964D01*
Y1272964D01*
X831146Y1274464D01*
X842346D01*
X844046Y1272764D01*
G37*
G36*
G01X1020688Y1272944D02*
X1022188Y1274444D01*
X1026188D01*
X1027688Y1272944D01*
Y1267944D01*
X1027188Y1267444D01*
X1021188D01*
X1020688Y1267944D01*
Y1272944D01*
G37*
G36*
G01X1012288Y1272844D02*
X1013788Y1274344D01*
X1017788D01*
X1019288Y1272844D01*
Y1267844D01*
X1018788Y1267344D01*
X1012788D01*
X1012288Y1267844D01*
Y1272844D01*
G37*
G36*
G01X1034388Y1272944D02*
X1035888Y1274444D01*
X1039888D01*
X1041388Y1272944D01*
Y1267944D01*
X1040888Y1267444D01*
X1034888D01*
X1034388Y1267944D01*
Y1272944D01*
G37*
G36*
G01X1050388D02*
X1051888Y1274444D01*
X1055888D01*
X1057388Y1272944D01*
Y1267944D01*
X1056888Y1267444D01*
X1050888D01*
X1050388Y1267944D01*
Y1272944D01*
G37*
G36*
G01X1064088D02*
X1065588Y1274444D01*
X1069588D01*
X1071088Y1272944D01*
Y1267944D01*
X1070588Y1267444D01*
X1064588D01*
X1064088Y1267944D01*
Y1272944D01*
G37*
G36*
G01X1080088D02*
X1081588Y1274444D01*
X1085588D01*
X1087088Y1272944D01*
Y1267944D01*
X1086588Y1267444D01*
X1080588D01*
X1080088Y1267944D01*
Y1272944D01*
G37*
G36*
G01X1093788D02*
X1095288Y1274444D01*
X1099288D01*
X1100788Y1272944D01*
Y1267944D01*
X1100288Y1267444D01*
X1094288D01*
X1093788Y1267944D01*
Y1272944D01*
G37*
G36*
G01X1123488D02*
X1124988Y1274444D01*
X1128988D01*
X1130488Y1272944D01*
Y1267944D01*
X1129988Y1267444D01*
X1123988D01*
X1123488Y1267944D01*
Y1272944D01*
G37*
G36*
G01X1136876Y1268762D02*
Y1272644D01*
X1137487Y1273255D01*
X1147897D01*
X1148657Y1272495D01*
Y1268174D01*
X1147927Y1267444D01*
X1138194D01*
X1136876Y1268762D01*
G37*
G36*
G01X1153680Y1267452D02*
X1152258D01*
X1151324Y1268386D01*
Y1272772D01*
X1152398Y1273846D01*
X1162208D01*
X1162931Y1273123D01*
Y1268081D01*
X1162293Y1267444D01*
X1153688D01*
X1153680Y1267452D01*
G37*
G36*
G01X1169188Y1267944D02*
Y1271985D01*
X1170308Y1273105D01*
X1177156D01*
X1178086Y1272175D01*
Y1268356D01*
X1177174Y1267444D01*
X1169688D01*
X1169188Y1267944D01*
G37*
G36*
G01X1198888Y1272944D02*
X1200388Y1274444D01*
X1204388D01*
X1205888Y1272944D01*
Y1267944D01*
X1205388Y1267444D01*
X1199388D01*
X1198888Y1267944D01*
Y1272944D01*
G37*
G36*
G01X1212588Y1267944D02*
Y1272944D01*
X1213058Y1273414D01*
X1221007D01*
X1222127Y1272294D01*
Y1268105D01*
X1221466Y1267444D01*
X1213088D01*
X1212588Y1267944D01*
G37*
G36*
G01X1229447Y1277445D02*
X1235178D01*
X1235618Y1277005D01*
Y1272974D01*
X1235588Y1272944D01*
Y1267944D01*
X1235088Y1267444D01*
X1229088D01*
X1228588Y1267944D01*
Y1276586D01*
X1229447Y1277445D01*
G37*
G36*
G01X1388416Y1152309D02*
X1383436D01*
X1381306Y1154439D01*
Y1169399D01*
X1382405Y1170498D01*
X1389395D01*
X1390524Y1169369D01*
Y1154417D01*
X1388416Y1152309D01*
G37*
G36*
G01X1406302Y1152885D02*
Y1170375D01*
X1407116Y1171189D01*
X1414636D01*
X1415436Y1170389D01*
Y1152789D01*
X1414508Y1151862D01*
X1407325D01*
X1406302Y1152885D01*
G37*
G36*
G01X1440486Y1152611D02*
X1439796Y1151921D01*
X1432066D01*
X1431356Y1152631D01*
Y1170649D01*
X1431955Y1171248D01*
X1439607D01*
X1440486Y1170369D01*
Y1152611D01*
G37*
G36*
G01X1459766Y1171119D02*
X1460476Y1170409D01*
Y1154659D01*
X1460146Y1154329D01*
X1456786D01*
X1456386Y1154729D01*
Y1170749D01*
X1456756Y1171119D01*
X1459766D01*
G37*
G36*
G01X1598514Y1274044D02*
X1598914Y1274444D01*
X1604314D01*
X1604914Y1273844D01*
Y1267344D01*
X1604714Y1267144D01*
X1598814D01*
X1598514Y1267444D01*
Y1274044D01*
G37*
G36*
G01X1614514D02*
X1614914Y1274444D01*
X1620314D01*
X1620914Y1273844D01*
Y1267344D01*
X1620714Y1267144D01*
X1614814D01*
X1614514Y1267444D01*
Y1274044D01*
G37*
G36*
G01X1622286Y1389490D02*
X1706337D01*
X1708587Y1387240D01*
Y1360355D01*
X1706338Y1358106D01*
X1686179D01*
G03X1686146Y1358105I26J-1401D01*
G01X1679918D01*
G03X1679885Y1358106I-59J-1400D01*
G01X1661779D01*
G03X1661746Y1358105I26J-1401D01*
G01X1655518D01*
G03X1655485Y1358106I-59J-1400D01*
G01X1637389D01*
G03X1637354Y1358105I23J-1402D01*
G01X1631164D01*
G03X1631129Y1358106I-58J-1401D01*
G01X1623556D01*
X1621516Y1360146D01*
Y1388720D01*
X1622286Y1389490D01*
G37*
G36*
G01X1628214Y1274044D02*
X1628614Y1274444D01*
X1634014D01*
X1634614Y1273844D01*
Y1267344D01*
X1634414Y1267144D01*
X1628514D01*
X1628214Y1267444D01*
Y1274044D01*
G37*
G36*
G01X1644214D02*
X1644614Y1274444D01*
X1650014D01*
X1650614Y1273844D01*
Y1267344D01*
X1650414Y1267144D01*
X1644514D01*
X1644214Y1267444D01*
Y1274044D01*
G37*
G36*
G01X1657914D02*
X1658314Y1274444D01*
X1663714D01*
X1664314Y1273844D01*
Y1267344D01*
X1664114Y1267144D01*
X1658214D01*
X1657914Y1267444D01*
Y1274044D01*
G37*
G36*
G01X1673914D02*
X1674314Y1274444D01*
X1679714D01*
X1680314Y1273844D01*
Y1267344D01*
X1680114Y1267144D01*
X1674214D01*
X1673914Y1267444D01*
Y1274044D01*
G37*
G36*
G01X1687614D02*
X1688014Y1274444D01*
X1693414D01*
X1694014Y1273844D01*
Y1267344D01*
X1693814Y1267144D01*
X1687914D01*
X1687614Y1267444D01*
Y1274044D01*
G37*
G36*
G01X1703614D02*
X1704014Y1274444D01*
X1709414D01*
X1710014Y1273844D01*
Y1267344D01*
X1709814Y1267144D01*
X1703914D01*
X1703614Y1267444D01*
Y1274044D01*
G37*
G36*
G01X1717314D02*
X1717714Y1274444D01*
X1723114D01*
X1723714Y1273844D01*
Y1267344D01*
X1723514Y1267144D01*
X1717614D01*
X1717314Y1267444D01*
Y1274044D01*
G37*
G36*
G01X1733314D02*
X1733714Y1274444D01*
X1739114D01*
X1739714Y1273844D01*
Y1267344D01*
X1739514Y1267144D01*
X1733614D01*
X1733314Y1267444D01*
Y1274044D01*
G37*
G36*
G01X1722708Y1539220D02*
X1724674Y1541187D01*
G02X1724816Y1541246I142J-141D01*
G01X1755556D01*
G02X1755698Y1541187I0J-200D01*
G01X1757664Y1539220D01*
G02X1757723Y1539078I-141J-142D01*
G01Y1496018D01*
G02X1757664Y1495876I-200J0D01*
G01X1756608Y1494820D01*
G02X1756466Y1494761I-142J141D01*
G01X1722989D01*
G02X1722847Y1494820I0J200D01*
G01X1722708Y1494959D01*
G02X1722649Y1495101I141J142D01*
G01Y1539078D01*
G02X1722708Y1539220I200J0D01*
G37*
G36*
G01X1747014Y1274044D02*
X1747414Y1274444D01*
X1752814D01*
X1753414Y1273844D01*
Y1267344D01*
X1753214Y1267144D01*
X1747314D01*
X1747014Y1267444D01*
Y1274044D01*
G37*
G36*
G01X1763014D02*
X1763414Y1274444D01*
X1768814D01*
X1769414Y1273844D01*
Y1267344D01*
X1769214Y1267144D01*
X1763314D01*
X1763014Y1267444D01*
Y1274044D01*
G37*
G36*
G01X1817190Y304162D02*
X1830600D01*
X1831320Y303442D01*
Y262392D01*
X1829900Y260972D01*
X1819220D01*
X1818260Y261932D01*
Y275522D01*
X1816760Y277022D01*
X1797650D01*
X1794520Y280152D01*
X1781568D01*
X1781075Y280645D01*
Y289145D01*
X1781232Y289302D01*
X1781250Y289314D01*
G03X1783529Y291593I-3896J6175D01*
G01X1783541Y291611D01*
X1787819Y295889D01*
Y300029D01*
X1789642Y301852D01*
X1814880D01*
X1817190Y304162D01*
G37*
G36*
G01X1776714Y1274044D02*
X1777114Y1274444D01*
X1782514D01*
X1783114Y1273844D01*
Y1267344D01*
X1782914Y1267144D01*
X1777014D01*
X1776714Y1267444D01*
Y1274044D01*
G37*
G36*
G01X1792714D02*
X1793114Y1274444D01*
X1798514D01*
X1799114Y1273844D01*
Y1267344D01*
X1798914Y1267144D01*
X1793014D01*
X1792714Y1267444D01*
Y1274044D01*
G37*
G36*
G01X1806014Y1273544D02*
X1806814Y1274344D01*
X1819114D01*
X1819714Y1273744D01*
Y1267844D01*
X1819214Y1267344D01*
X1806714D01*
X1806014Y1268044D01*
Y1273544D01*
G37*
%LPC*%
G75*
G36*
G01X1655130Y1359173D02*
Y1365373D01*
G02X1655532Y1365774I402J-1D01*
G01X1661732D01*
G02X1662134Y1365373I1J-401D01*
G01Y1359173D01*
G02X1661732Y1358772I-402J1D01*
G01X1655532D01*
G02X1655130Y1359173I-1J401D01*
G37*
G36*
G01X1679530D02*
Y1365373D01*
G02X1679932Y1365774I402J-1D01*
G01X1686132D01*
G02X1686534Y1365373I1J-401D01*
G01Y1359173D01*
G02X1686132Y1358772I-402J1D01*
G01X1679932D01*
G02X1679530Y1359173I-1J401D01*
G37*
G36*
G01X1630758Y1359148D02*
Y1365348D01*
G02X1631159Y1365750I401J1D01*
G01X1637359D01*
G02X1637760Y1365348I-1J-402D01*
G01Y1359148D01*
G02X1637359Y1358746I-401J-1D01*
G01X1631159D01*
G02X1630758Y1359148I1J402D01*
G37*
%LPD*%
G75*
G54D100*
X1202549Y1249708D03*
X1265642Y143511D03*
X1263947Y148462D03*
X1266282Y156855D03*
X1269082Y153785D03*
G54D101*
X1249473Y140119D03*
X1249959Y153904D03*
X1252193Y137419D03*
X1256530Y160252D03*
G54D110*
X1360652Y231659D03*
X1362136Y233143D03*
X1363198Y229113D03*
X1364682Y230597D03*
G54D120*
G01X27520Y434992D02*
X30000Y432512D01*
X35150D01*
X42478Y439840D01*
X44396D01*
G01X152470Y495383D02*
Y494091D01*
X141464Y483085D01*
X121984D01*
X119810Y485259D01*
Y490227D01*
X119158Y490879D01*
X112017D01*
X111338Y490200D01*
Y482739D01*
X110171Y481572D01*
X96710D01*
X28820Y549462D01*
Y583962D01*
X13374Y599408D01*
Y763748D01*
X19320Y769694D01*
Y1310362D01*
X27820Y1318862D01*
X56220D01*
X58920Y1321562D01*
X137020D01*
X155320Y1303262D01*
X260186D01*
X269212Y1312288D01*
Y1381678D01*
X269427Y1381893D01*
G01X39993Y726874D02*
X27885D01*
X16200Y715189D01*
Y602782D01*
X29120Y589862D01*
X38220D01*
G01X39993Y722374D02*
X25974D01*
X18030Y714430D01*
Y604152D01*
X29320Y592862D01*
X38220D01*
G01X343354Y391643D02*
X338459D01*
X330790Y399312D01*
Y506552D01*
X283820Y553522D01*
X127270D01*
X74850Y605942D01*
Y644672D01*
X58622Y660900D01*
X26240D01*
X23940Y663200D01*
Y683940D01*
X62000Y722000D01*
Y745900D01*
X65162Y749062D01*
X81594D01*
X91401Y758869D01*
X95779D01*
G01X59500Y738700D02*
X58100Y737300D01*
Y723340D01*
X20235Y685475D01*
Y661665D01*
X24705Y657195D01*
X55405D01*
X69800Y642800D01*
Y615300D01*
X64600Y610100D01*
X59500D01*
X48400Y599000D01*
Y586000D01*
G01X39000Y731600D02*
X34500D01*
X25700Y740400D01*
Y758300D01*
X27636Y760236D01*
X37721D01*
G01X51878Y733922D02*
X35178D01*
X27900Y741200D01*
Y756500D01*
X29076Y757676D01*
X37721D01*
G01X27520Y1245162D02*
X28462D01*
X33005Y1249705D01*
Y1252145D01*
X33674Y1252814D01*
Y1252965D01*
G01X27699Y1255381D02*
X26050Y1253732D01*
Y1252272D01*
G01D02*
X26743Y1252965D01*
X30524D01*
G01X27699Y1262074D02*
X24647D01*
G01X88520Y1491482D02*
X88382Y1491620D01*
X35652D01*
X25550Y1501722D01*
Y1582088D01*
X45620Y1602158D01*
Y1625652D01*
X76640Y1656672D01*
X90407D01*
G01X88520Y1487982D02*
X87022Y1489480D01*
X34765D01*
X23410Y1500835D01*
Y1582975D01*
X43480Y1603045D01*
Y1627132D01*
X77682Y1661334D01*
X88333D01*
G01X88520Y1494982D02*
X87348Y1493810D01*
X36560D01*
X27740Y1502630D01*
Y1581180D01*
X47810Y1601250D01*
Y1624682D01*
X70670Y1647542D01*
X98540D01*
X109030Y1658032D01*
Y1706802D01*
X114700Y1712472D01*
X139410D01*
X142200Y1709682D01*
X151310D01*
X155145Y1713517D01*
G01X88520Y1484482D02*
X85842Y1487160D01*
X33804D01*
X21090Y1499874D01*
Y1583936D01*
X41160Y1604006D01*
Y1628202D01*
X86030Y1673072D01*
Y1683092D01*
G01X33830Y445519D02*
X34785Y444564D01*
X35982D01*
X38620Y447202D01*
G01D02*
X41258Y444564D01*
X44396D01*
G01X33830Y441130D02*
X35689Y442989D01*
X36343D01*
X38340Y440992D01*
G01D02*
X40337Y442989D01*
X44396D01*
G01X33350Y434992D02*
X36030D01*
X42453Y441415D01*
X44396D01*
G01X48293Y722374D02*
Y720293D01*
X47500Y719500D01*
X41100D01*
X39993Y720607D01*
Y722374D01*
G01X48293Y726874D02*
Y728307D01*
X47100Y729500D01*
X40800D01*
X39993Y728693D01*
Y726874D01*
G01X39000Y731600D02*
X48701D01*
X51443Y728858D01*
Y726874D01*
G01X30200Y754822D02*
X37721D01*
G01X39505Y987865D02*
Y990021D01*
X43841Y994357D01*
G01X61775Y1244886D02*
X61766Y1244895D01*
X55711D01*
X53307Y1242491D01*
X42487D01*
X40207Y1244771D01*
X35855D01*
X34505Y1246121D01*
Y1252406D01*
X33946Y1252965D01*
X33674D01*
G01X39927Y1249845D02*
Y1251855D01*
X40920Y1252848D01*
Y1254400D01*
G01X43841Y1255381D02*
X42860Y1254400D01*
X40920D01*
G01X40217Y1258925D02*
X42247D01*
X42445Y1258727D01*
X43841D01*
G01Y1252034D02*
X47190D01*
G01X47567Y1246625D02*
X45504Y1248688D01*
X43841D01*
G01Y1258727D02*
X46135D01*
X46524Y1258338D01*
Y1256964D01*
G01X50696Y441415D02*
X54153D01*
X56440Y443702D01*
X57920D01*
G01D02*
X62328D01*
X62353Y443677D01*
G01X55564Y449734D02*
X54130Y448300D01*
Y447065D01*
X51629Y444564D01*
X50696D01*
G01X185191Y502439D02*
Y519493D01*
X154829Y549855D01*
X126089D01*
X76690Y599254D01*
X61817D01*
X57595Y603476D01*
G01X51878Y733922D02*
X53300Y732500D01*
Y724231D01*
X51443Y722374D01*
G01X63487Y761105D02*
X61447D01*
X60578Y760236D01*
X54847D01*
G01X68209Y754726D02*
X62926D01*
X61539Y756113D01*
G01D02*
X59976Y757676D01*
X54847D01*
G01X60997Y768875D02*
X58920Y766798D01*
X57299D01*
G01X52541Y957546D02*
X50482D01*
X48697Y959331D01*
G01X52541Y954200D02*
X50416D01*
X48697Y952481D01*
G01X79374Y1256964D02*
Y1250201D01*
X76908Y1247735D01*
X69687D01*
X63810Y1253612D01*
X59192D01*
X57067Y1255737D01*
X56031Y1256166D01*
X52020Y1256964D01*
X49674D01*
G01X52820Y1253862D02*
X53623Y1253059D01*
X55816D01*
X56777Y1252098D01*
G01D02*
X59959Y1248916D01*
X60895D01*
X61775Y1248036D01*
G01X57399Y1262074D02*
Y1261671D01*
X54620Y1258892D01*
G01X65937Y48720D02*
Y52465D01*
X77107Y63635D01*
X110375D01*
X113360Y66620D01*
Y70692D01*
X111410Y72642D01*
Y78362D01*
X118710Y85662D01*
Y154782D01*
X88584Y184908D01*
Y278059D01*
X87845Y278798D01*
G01X83320Y445212D02*
X89127Y439405D01*
Y437932D01*
X86629Y435434D01*
X81090D01*
X76746Y439778D01*
Y452160D01*
X84783Y460197D01*
X104985D01*
X110756Y465968D01*
G01X74559Y667814D02*
X84626Y677881D01*
X88933D01*
G01X80971Y693006D02*
X77121D01*
G01D02*
X73311D01*
X73281Y693036D01*
G01X63930Y739300D02*
X66200Y737030D01*
Y733942D01*
X66700Y733442D01*
X80894D01*
X88531Y741079D01*
Y743479D01*
X95337Y750285D01*
X122087D01*
X129771Y757969D01*
X136029D01*
G01X85877Y759275D02*
X78917Y752315D01*
X70620D01*
X68209Y754726D01*
G01X81966Y759246D02*
X79711Y756991D01*
X70464D01*
X68209Y759246D01*
G01D02*
X65346D01*
X63487Y761105D01*
G01X91123Y1243960D02*
X90626Y1244457D01*
X85495D01*
X84724Y1243686D01*
X80827D01*
X79774Y1242633D01*
X72520D01*
X71467Y1243686D01*
X64651D01*
X63451Y1244886D01*
X61775D01*
G01X73541Y1255381D02*
X72753Y1254593D01*
X70852D01*
G01D02*
Y1250055D01*
G01X73541Y1258727D02*
X75665D01*
X76224Y1258168D01*
Y1256964D01*
G01X69877Y1259125D02*
X71747D01*
X72145Y1258727D01*
X73541D01*
G01Y1252034D02*
X76890D01*
G01X77040Y1601102D02*
X66940Y1591002D01*
Y1530070D01*
X70730Y1526280D01*
X90440D01*
X93409Y1523311D01*
X100071D01*
X114642Y1508740D01*
X156160D01*
X159440Y1505460D01*
X404200D01*
X432420Y1533680D01*
Y1534062D01*
X445458Y1547100D01*
X456501D01*
X459100Y1549699D01*
X468499D01*
X480000Y1561200D01*
X670000D01*
X673300Y1564500D01*
Y1570400D01*
X675800Y1572900D01*
Y1616080D01*
X668580Y1623300D01*
Y1662120D01*
X668695Y1662235D01*
G01X233339Y17662D02*
X228639Y12962D01*
X197920D01*
X193220Y17662D01*
X184720D01*
X180820Y13762D01*
X152920D01*
X141030Y25652D01*
Y34072D01*
X122420Y52682D01*
Y71132D01*
X124220Y72932D01*
Y156021D01*
X91259Y188982D01*
Y279223D01*
X87620Y282862D01*
Y285321D01*
G01X148784Y48720D02*
X148781D01*
X144220Y53281D01*
Y71212D01*
X146510Y73502D01*
Y76772D01*
X145620Y77662D01*
Y165972D01*
X102420Y209172D01*
Y285062D01*
X87820Y299662D01*
Y302821D01*
G01X147924Y28258D02*
Y41388D01*
X135510Y53802D01*
Y71842D01*
X133430Y73922D01*
Y172762D01*
X100020Y206172D01*
Y283623D01*
X87845Y295798D01*
G01X94439Y450081D02*
X93710Y449352D01*
Y436203D01*
X85826Y428319D01*
G01X84410Y438519D02*
X79650Y443279D01*
Y449952D01*
X86170Y456472D01*
X118098D01*
X150113Y488487D01*
G01X81505Y447377D02*
X85485D01*
X91830Y453722D01*
X128145D01*
G01X93069Y631917D02*
Y642670D01*
X96408Y646009D01*
G01X107489Y630917D02*
X103842Y627270D01*
X97030D01*
X93069Y631231D01*
Y631917D01*
G01X110374Y630879D02*
X104456Y624961D01*
X96717D01*
X90565Y631113D01*
Y636612D01*
G01X96368Y649839D02*
X93207Y646678D01*
X90384D01*
X88575Y644869D01*
Y638602D01*
X90565Y636612D01*
G01X95725Y654540D02*
X94723D01*
X89622Y659641D01*
X87853D01*
G01X80241Y659011D02*
X81461Y660231D01*
X82457D01*
X83047Y659641D01*
X84703D01*
G01X80123Y664031D02*
X81519Y662635D01*
X82541D01*
X83047Y663141D01*
X84703D01*
G01X90115Y667952D02*
Y667576D01*
X87762Y665223D01*
Y663232D01*
X87853Y663141D01*
G01X95860Y659622D02*
X92341Y663141D01*
X87853D01*
G01X80135Y667933D02*
X86083Y673881D01*
X88933D01*
G01X90396Y692338D02*
Y691674D01*
X92878Y689192D01*
X94357D01*
X95793Y690628D01*
X95876D01*
G01X99021Y663732D02*
Y668932D01*
X94072Y673881D01*
X92083D01*
G01X103397Y667272D02*
Y669468D01*
X94984Y677881D01*
X92083D01*
G01X84035Y697604D02*
Y693556D01*
X83485Y693006D01*
X80971D01*
G01X90396Y692338D02*
X86148D01*
X83614Y689804D01*
X81285D01*
G01X82357Y737803D02*
Y745135D01*
X92807Y755585D01*
X117787D01*
X136167Y773965D01*
Y998603D01*
X152965Y1015401D01*
X163634D01*
X166273Y1018040D01*
Y1225045D01*
X164976Y1226342D01*
G01X84623Y741249D02*
Y744441D01*
X93677Y753495D01*
X119488D01*
X130133Y764140D01*
X132993D01*
X138368Y769515D01*
Y997691D01*
X153877Y1013200D01*
X164162D01*
X168474Y1017512D01*
Y1216664D01*
X170547Y1218737D01*
X172196D01*
X173991Y1220532D01*
X181970D01*
X182250Y1220252D01*
X187510D01*
X191380Y1224122D01*
X194460D01*
X198420Y1220162D01*
G01X204670D02*
X212447Y1227939D01*
X226910D01*
G01X86999Y766798D02*
X90000D01*
G01X82241Y957546D02*
X80182D01*
X78397Y959331D01*
G01X82241Y954200D02*
X80116D01*
X78397Y952481D01*
G01X85747Y994357D02*
X82241D01*
G01X122774Y1250499D02*
X121497Y1249222D01*
Y1246800D01*
X120171Y1245474D01*
X116398D01*
X113702Y1242778D01*
X99734D01*
X97537Y1244975D01*
X94013D01*
X92998Y1243960D01*
X91123D01*
G01X109074Y1256964D02*
Y1249461D01*
X107428Y1247815D01*
X99328D01*
X95528Y1251615D01*
X92630D01*
G01D02*
X90671D01*
X85484Y1256802D01*
X79536D01*
X79374Y1256964D01*
G01X82241Y1248688D02*
Y1252037D01*
G01X84334Y1254263D02*
Y1253859D01*
X86501Y1251692D01*
X87450D01*
G01D02*
Y1251083D01*
X91123Y1247410D01*
Y1247110D01*
G01X87099Y1262074D02*
Y1261691D01*
X84390Y1258982D01*
G01X96438Y642149D02*
X95253Y640964D01*
Y632733D01*
X98490Y629496D01*
G01D02*
X102564D01*
X106110Y633042D01*
Y633732D01*
G01X97560Y637624D02*
Y639020D01*
X98027Y639487D01*
X105400D01*
G01X111920Y632922D02*
X109541D01*
X106367Y636096D01*
X105747D01*
X103822Y638021D01*
X100275D01*
X99878Y637624D01*
X97560D01*
G01X114540Y633032D02*
X112744Y634828D01*
X110003D01*
X109200Y635631D01*
Y637287D01*
G01X95876Y693778D02*
X99496D01*
X99516Y693798D01*
G01X102420Y697262D02*
Y702031D01*
X101512Y702939D01*
G01D02*
X99785Y701212D01*
Y694067D01*
X99516Y693798D01*
G01X103779Y762019D02*
X107779D01*
G01X107852Y767065D02*
X107779Y766992D01*
Y762019D01*
G01X141641Y1057940D02*
X138539D01*
X136600Y1056001D01*
Y1013455D01*
X132282Y1009137D01*
X124351D01*
X120562Y1005348D01*
Y784700D01*
X107852Y771990D01*
Y767065D01*
G01X99779Y758869D02*
X95779D01*
G01X103779D02*
X99779D01*
G01X111941Y957546D02*
X109882D01*
X108097Y959331D01*
G01X111941Y954200D02*
X109816D01*
X108097Y952481D01*
G01X98905Y987865D02*
Y990021D01*
X103241Y994357D01*
G01Y1255381D02*
X102324Y1254464D01*
X100287D01*
G01D02*
Y1249926D01*
G01X103241Y1258727D02*
X105425D01*
X105924Y1258228D01*
Y1256964D01*
G01X99577Y1259125D02*
X101447D01*
X101845Y1258727D01*
X103241D01*
G01X135950Y1254567D02*
X136041Y1254658D01*
X137690D01*
X138774Y1253574D01*
Y1249022D01*
X137517Y1247765D01*
X129151D01*
X123254Y1253662D01*
X118014D01*
X114712Y1256964D01*
X109074D01*
G01X103241Y1252034D02*
X106590D01*
G01X111941Y1248688D02*
X109675Y1246422D01*
X109320D01*
G01X270276Y1643661D02*
X270275Y1643660D01*
Y1631547D01*
X264520Y1625792D01*
Y1618272D01*
X262790Y1616542D01*
Y1598132D01*
X260920Y1596262D01*
X201630D01*
X196950Y1591582D01*
Y1586122D01*
X194740Y1583912D01*
X187450D01*
X179938Y1576400D01*
X132980D01*
X115270Y1558690D01*
X107620D01*
X103750Y1554820D01*
X99580D01*
X96480Y1557920D01*
Y1574690D01*
X98250Y1576460D01*
Y1605379D01*
X98738Y1605867D01*
G01X104318Y1589352D02*
X107392Y1592426D01*
X159994D01*
X173300Y1605732D01*
X178332D01*
X191798Y1619198D01*
X193145Y1620030D01*
X206369Y1633252D01*
X232483D01*
X238780Y1639549D01*
Y1643661D01*
G01X110756Y465968D02*
X116171Y471383D01*
Y485041D01*
G01X117750Y633232D02*
X117042D01*
X115512Y634762D01*
X115369D01*
X113410Y636721D01*
Y637210D01*
X112900Y637720D01*
Y637887D01*
G01X117430Y636052D02*
Y638729D01*
X120575Y641874D01*
Y642762D01*
G01X120440Y633347D02*
X120345D01*
X117640Y636052D01*
X117430D01*
G01X116567Y766775D02*
Y763774D01*
G01X132298Y1242353D02*
X128722D01*
X127425Y1243650D01*
X123943D01*
X123321Y1244272D01*
Y1249600D01*
X122774Y1250147D01*
Y1250499D01*
G01X114191Y1254604D02*
Y1251761D01*
X114604Y1251348D01*
G01D02*
X115080Y1250872D01*
X119251D01*
X119624Y1250499D01*
G01X116799Y1262074D02*
Y1261811D01*
X114020Y1259032D01*
G01X123220Y1324662D02*
X136601D01*
X152465Y1308798D01*
X168027D01*
X168537Y1308288D01*
Y1307041D01*
X169047Y1306531D01*
X170537D01*
X171047Y1307041D01*
Y1308288D01*
X171557Y1308798D01*
X173047D01*
X173557Y1308288D01*
Y1307041D01*
X174067Y1306531D01*
X175557D01*
X176067Y1307041D01*
Y1308288D01*
X176577Y1308798D01*
X250763D01*
X259834Y1317869D01*
Y1389439D01*
X308740Y1438345D01*
X384055D01*
X390687Y1431713D01*
G01X394067Y1435323D02*
X388995Y1440395D01*
X307286D01*
X257357Y1390466D01*
Y1318896D01*
X248969Y1310508D01*
X153174D01*
X136930Y1326752D01*
X122186D01*
X120220Y1324786D01*
Y1324662D01*
G01X185895Y1557875D02*
X176200Y1548180D01*
Y1533020D01*
X171090Y1527910D01*
X139240D01*
X130237Y1518907D01*
X112270D01*
G01X181845Y401071D02*
X174834Y408082D01*
X170620D01*
X169040Y409662D01*
Y444812D01*
X160130Y453722D01*
X150909D01*
X150399Y453212D01*
Y450472D01*
X149889Y449962D01*
X148399D01*
X147889Y450472D01*
Y453212D01*
X147379Y453722D01*
X145889D01*
X145379Y453212D01*
Y450472D01*
X144869Y449962D01*
X143379D01*
X142869Y450472D01*
Y453212D01*
X142359Y453722D01*
X140869D01*
X140359Y453212D01*
Y450472D01*
X139849Y449962D01*
X138359D01*
X137849Y450472D01*
Y453212D01*
X137339Y453722D01*
X128145D01*
G01X139370Y492560D02*
Y495370D01*
X141220Y497220D01*
Y498810D01*
G01X143972Y493640D02*
X140450D01*
X139370Y492560D01*
G01X137672Y502106D02*
X139372Y503806D01*
X141325D01*
G01D02*
X141806D01*
X143972Y501640D01*
G01X135428Y510312D02*
X135894Y509846D01*
X138975D01*
X139616Y510487D01*
X141329D01*
G01X141220Y498810D02*
X142802D01*
X143972Y497640D01*
G01X143922Y514980D02*
Y514898D01*
X141329Y512305D01*
Y510487D01*
G01X136029Y757969D02*
X140029D01*
G01X144029D02*
X140029D01*
G01X141641Y957546D02*
X143766D01*
X145485Y959265D01*
G01X145181Y950660D02*
X141641Y954200D01*
G01X145147Y994357D02*
X141641D01*
G01X129933Y1238461D02*
Y1238944D01*
X132298Y1241309D01*
Y1242353D01*
G01X135448D02*
X137279D01*
X138612Y1243686D01*
X142965D01*
X144359Y1245080D01*
Y1246662D01*
G01X130147Y1249975D02*
Y1252454D01*
X129753Y1252848D01*
Y1254528D01*
G01X132941Y1255381D02*
X132088Y1254528D01*
X129753D01*
G01X135950Y1257717D02*
X135624Y1258043D01*
Y1258398D01*
X135295Y1258727D01*
X132941D01*
G01D02*
X131545D01*
X131147Y1259125D01*
X129277D01*
G01X140665Y1257952D02*
X139146Y1256433D01*
X137717D01*
X135950Y1254666D01*
Y1254567D01*
G01X132941Y1252034D02*
X133858D01*
X136010Y1249882D01*
G01X141641Y1248688D02*
Y1252037D01*
G01X230906Y1734212D02*
X221520Y1724826D01*
Y1714862D01*
X212481Y1705823D01*
X128656D01*
X127195Y1704362D01*
G01X147122Y501640D02*
X147902Y500860D01*
X151390D01*
X153673Y503143D01*
X161267D01*
G01X147122Y497640D02*
X148052Y496710D01*
X150440D01*
X154512Y500782D01*
X165176D01*
G01X160000Y510052D02*
X158236D01*
X157193Y511095D01*
G01X153737Y514893D02*
X150817Y517813D01*
X148069D01*
X147072Y518810D01*
G01X143922D02*
X143923Y518811D01*
Y522771D01*
G01X143922Y518810D02*
X144013Y518719D01*
Y515071D01*
X143922Y514980D01*
G01X332207Y1083692D02*
X322737D01*
X322736Y1083693D01*
X310101D01*
X270383Y1043975D01*
X250348D01*
X246968Y1047355D01*
X235876D01*
X234216Y1045695D01*
X219368D01*
X209668Y1035995D01*
X207856D01*
X203467Y1031606D01*
Y1015855D01*
X202957Y1015345D01*
X183167D01*
X164057Y996235D01*
X161747D01*
X157897Y992385D01*
Y764485D01*
X173520Y748862D01*
X196320D01*
X201220Y743962D01*
Y736662D01*
G01X144029Y761119D02*
X148029D01*
G01X255530Y1057940D02*
X250150D01*
X247302Y1055092D01*
X234879D01*
X231968Y1058003D01*
X219869D01*
X216958Y1055092D01*
X205700D01*
X202789Y1058003D01*
X200136D01*
X196707Y1054574D01*
Y1026205D01*
X190067Y1019565D01*
X182217D01*
X178657Y1016005D01*
X176007D01*
X169837Y1009835D01*
X155577D01*
X149509Y1003767D01*
Y780275D01*
X151757Y778027D01*
Y764847D01*
X148029Y761119D01*
G01X149400Y766798D02*
X146390D01*
X146367Y766775D01*
G01X164976Y1226342D02*
X159197Y1232121D01*
Y1234121D01*
G01X150927Y1237271D02*
X155319D01*
X159780Y1241732D01*
G01X147824Y1252964D02*
X148317Y1252471D01*
Y1241255D01*
X150927Y1238645D01*
Y1237271D01*
G01X159780Y1241732D02*
Y1237854D01*
X159197Y1237271D01*
G01X157610Y1246842D02*
Y1253366D01*
X157564Y1253412D01*
G01X162641Y1255381D02*
X159533D01*
X157564Y1253412D01*
G01X147824Y1252964D02*
X146888Y1253900D01*
Y1254916D01*
X143852Y1257952D01*
X143815D01*
G01X144359Y1246662D02*
Y1253125D01*
X143675Y1253809D01*
Y1255567D01*
G01X162641Y1258727D02*
X161245D01*
X160847Y1259125D01*
X158977D01*
G01X146499Y1262074D02*
Y1262082D01*
X145999Y1262582D01*
X143680D01*
G01X155100Y1717507D02*
Y1713562D01*
X155145Y1713517D01*
G01X178142Y1720652D02*
X177564D01*
X171440Y1714528D01*
X156156D01*
X155145Y1713517D01*
G01X172632Y454095D02*
X175035Y451692D01*
Y419031D01*
X177316Y416750D01*
X193119D01*
X198767Y411102D01*
Y391986D01*
X195970Y389189D01*
X189807D01*
X187798Y391198D01*
X182530D01*
X178375Y395353D01*
Y396571D01*
G01X276582Y1040899D02*
X267928Y1032245D01*
X247906D01*
X246836Y1033315D01*
X233437D01*
X232757Y1032635D01*
X221747D01*
X217292Y1028180D01*
Y1017649D01*
X209968Y1010325D01*
X185786D01*
X169217Y993756D01*
Y760315D01*
X175750Y753782D01*
X198350D01*
X207140Y744992D01*
Y738462D01*
G01X239657Y1035555D02*
X232466D01*
X230995Y1037026D01*
X221268D01*
X217560Y1033318D01*
Y1031172D01*
X210247Y1023859D01*
Y1016935D01*
X205197Y1011885D01*
X185067D01*
X167697Y994515D01*
Y759685D01*
X175120Y752262D01*
X197720D01*
X205220Y744762D01*
Y736562D01*
G01X266486Y1038775D02*
X248776D01*
X247116Y1040435D01*
X233048D01*
X231578Y1038965D01*
X219558D01*
X207807Y1027214D01*
Y1016745D01*
X204777Y1013715D01*
X184607D01*
X165702Y994810D01*
Y981070D01*
X159577Y974945D01*
Y765181D01*
X174216Y750542D01*
X197016D01*
X203300Y744258D01*
Y732162D01*
X203660Y731802D01*
G01X289406Y1049524D02*
X271919Y1032037D01*
Y981627D01*
X269447Y979155D01*
X245328D01*
X244698Y979785D01*
X233197D01*
X232447Y979035D01*
X227917D01*
X219627Y987325D01*
Y990824D01*
X202846Y1007605D01*
X186338D01*
X179572Y1000839D01*
Y775710D01*
X177307Y773445D01*
X174677D01*
X173717Y772485D01*
Y765855D01*
X177132Y762440D01*
X183602D01*
G01X175185Y959265D02*
X173466Y957546D01*
X171341D01*
G01X174881Y950660D02*
X171341Y954200D01*
G01X162641Y994357D02*
Y991759D01*
X160465Y989583D01*
Y985165D01*
G01X160130Y1251847D02*
X160285D01*
X163444Y1248688D01*
X164008D01*
X172445Y1240251D01*
X173865D01*
G01D02*
X174807D01*
X176358Y1238700D01*
X182251D01*
X183883Y1240332D01*
X189090D01*
X190505Y1241747D01*
X197485D01*
X199388Y1243650D01*
X204109D01*
X205624Y1245165D01*
X208615D01*
X208844Y1244936D01*
G01X165324Y1256964D02*
Y1258508D01*
X165105Y1258727D01*
X162641D01*
G01X168474Y1256964D02*
X169337Y1257827D01*
X174386D01*
X180451Y1251762D01*
X182000D01*
G01X162641Y1252034D02*
X165990D01*
G01X171341Y1248688D02*
Y1252037D01*
G01X171947Y1255837D02*
X174289Y1253495D01*
X174877D01*
X176560Y1251812D01*
G01D02*
X174289Y1249541D01*
Y1247154D01*
X173865Y1246730D01*
Y1243401D01*
G01X176199Y1262074D02*
X174317Y1260192D01*
X173770D01*
G01X272500Y447735D02*
X275650Y450885D01*
Y454712D01*
X273590Y456772D01*
X258290D01*
X228570Y427052D01*
Y423692D01*
X220320Y415442D01*
Y328339D01*
X211620Y319639D01*
Y96192D01*
X200720Y85292D01*
Y74282D01*
X202760Y72242D01*
Y54782D01*
X202740Y54762D01*
X193491D01*
X186620Y47891D01*
Y26518D01*
X186120Y26018D01*
Y24162D01*
G01X272500Y452862D02*
X271920Y453442D01*
X257440D01*
X233690Y429692D01*
Y422842D01*
X222920Y412072D01*
Y327262D01*
X215650Y319992D01*
Y75112D01*
X211160Y70622D01*
Y59302D01*
X204620Y52762D01*
X194320D01*
X188620Y47062D01*
Y45072D01*
X189130Y44562D01*
X191561D01*
X192071Y44052D01*
Y42562D01*
X191561Y42052D01*
X189130D01*
X188620Y41542D01*
Y40052D01*
X189130Y39542D01*
X191561D01*
X192071Y39032D01*
Y37542D01*
X191561Y37032D01*
X189130D01*
X188620Y36522D01*
Y35032D01*
X189130Y34522D01*
X191561D01*
X192071Y34012D01*
Y32522D01*
X191561Y32012D01*
X189130D01*
X188620Y31502D01*
Y24162D01*
G01X284103Y1037625D02*
X275298Y1028820D01*
Y978621D01*
X273382Y976705D01*
X249704D01*
X247504Y974505D01*
X233537D01*
X231457Y972425D01*
X221257D01*
X216897Y976785D01*
Y985835D01*
X203567Y999165D01*
X198507D01*
X187047Y987705D01*
Y766995D01*
X191602Y762440D01*
G01X287875Y1044423D02*
X273328Y1029876D01*
Y980135D01*
X271068Y977875D01*
X247608D01*
X245388Y975655D01*
X234127D01*
X233687Y976095D01*
X223607D01*
X219217Y980485D01*
Y984225D01*
X218487Y984955D01*
Y989755D01*
X207567Y1000675D01*
X197297D01*
X192947Y996325D01*
X183777D01*
X182317Y994865D01*
Y769595D01*
X184407Y767505D01*
Y765635D01*
X187602Y762440D01*
G01X176099Y766798D02*
X179100D01*
G01X294343Y1044589D02*
X276733Y1026979D01*
Y977072D01*
X272126Y972465D01*
X247727D01*
X247247Y972945D01*
X234487D01*
X231437Y969895D01*
X219777D01*
X217427Y972245D01*
X216487D01*
X210257Y978475D01*
Y990255D01*
X202737Y997775D01*
X199007D01*
X188437Y987205D01*
Y779895D01*
X195602Y772730D01*
Y762440D01*
G01X188493Y1251400D02*
Y1253501D01*
X189329Y1254337D01*
Y1255943D01*
G01X192341Y1255381D02*
X191495Y1254535D01*
X190737D01*
X189329Y1255943D01*
G01X188307Y1260475D02*
X190055Y1258727D01*
X192341D01*
G01X182000Y1251762D02*
X184640D01*
X187257Y1249145D01*
X196997D01*
X198067Y1250215D01*
Y1256857D01*
X198174Y1256964D01*
G01X381120Y1534102D02*
X378722Y1536500D01*
X366200D01*
X364400Y1538300D01*
Y1549930D01*
X362600Y1551730D01*
X193990D01*
X187845Y1557875D01*
X185895D01*
G01X195602Y762440D02*
X199602D01*
G01X207602D02*
X203602D01*
G01X290654Y1037501D02*
X277942Y1024789D01*
Y976209D01*
X272968Y971235D01*
X247316D01*
X245166Y969085D01*
X236997D01*
X232827Y964915D01*
X220797D01*
X218167Y967545D01*
X213777D01*
X209687Y971635D01*
X208657D01*
X203567Y976725D01*
Y994735D01*
X202027Y996275D01*
X199737D01*
X194377Y990915D01*
Y782275D01*
X198257Y778395D01*
X201917D01*
X203602Y776710D01*
Y762440D01*
G01X208787Y768035D02*
X207550Y766798D01*
X205799D01*
G01X269977Y965105D02*
X248836D01*
X246186Y962455D01*
X239807D01*
X235214Y957862D01*
X232420D01*
X223513Y948955D01*
X218977D01*
X207837Y937815D01*
Y780906D01*
X216687Y772056D01*
Y767805D01*
X214417Y765535D01*
Y755215D01*
X209120Y749918D01*
Y732462D01*
X209720Y731862D01*
G01X281759Y1010061D02*
Y976160D01*
X275514Y969915D01*
X247687D01*
X245687Y967915D01*
X241977D01*
X236437Y962375D01*
X232547D01*
X231667Y963255D01*
X218597D01*
X215577Y966275D01*
X212027D01*
X210847Y965095D01*
Y949175D01*
X203077Y941405D01*
Y782295D01*
X207907Y777465D01*
Y773815D01*
X211602Y770120D01*
Y762440D01*
G01X205627Y959575D02*
X203598Y957546D01*
X201041D01*
G01Y954200D02*
X204332Y950909D01*
G01X197317Y989785D02*
X199717Y992185D01*
Y993033D01*
X201041Y994357D01*
G01X192341Y1258727D02*
X194545D01*
X195024Y1258248D01*
Y1256964D01*
G01X227674Y1257520D02*
Y1250962D01*
X225684Y1248972D01*
X217380D01*
X212987Y1253365D01*
X207297D01*
X204591Y1256071D01*
X203892Y1257759D01*
X203669Y1258877D01*
Y1259142D01*
X202829Y1259982D01*
X199708D01*
X198174Y1258448D01*
Y1256964D01*
G01X192341Y1252034D02*
X195690D01*
G01X201041Y1248688D02*
Y1252037D01*
G01X201193Y1257900D02*
X201390Y1255912D01*
X201989Y1254646D01*
X206021Y1250614D01*
X209390D01*
G01X205899Y1262074D02*
X203040D01*
G01X216842Y756865D02*
Y760530D01*
X219272Y762960D01*
G01D02*
Y765120D01*
X219527Y765375D01*
Y775155D01*
X218159Y776523D01*
G01X340736Y1030155D02*
X310913D01*
X289820Y1009062D01*
Y973062D01*
X272520Y955762D01*
X259420D01*
X252520Y948862D01*
X248320D01*
X247620Y949562D01*
X242020D01*
X237720Y945262D01*
X234920D01*
X232270Y942612D01*
X229570D01*
X219970Y933012D01*
X215170D01*
X212920Y930762D01*
Y919582D01*
X212130Y918792D01*
Y791152D01*
X215050Y788232D01*
X217150D01*
X224810Y780572D01*
Y713383D01*
X224900Y713293D01*
G01X227430Y719772D02*
Y781452D01*
X219320Y789562D01*
Y928362D01*
X230820Y939862D01*
X232520D01*
X233420Y938962D01*
X238020D01*
X244450Y945392D01*
X246990D01*
X247760Y946162D01*
X253254D01*
X260254Y953162D01*
X275517D01*
X276717Y953659D01*
X292530Y969472D01*
Y1007172D01*
X308927Y1023569D01*
X310839D01*
G01X218159Y776523D02*
X210217Y784465D01*
Y932759D01*
X216427Y938969D01*
Y942485D01*
X220577Y946635D01*
X224520D01*
X226847Y948962D01*
X231520D01*
X234823Y952265D01*
X244847D01*
X246477Y953895D01*
Y958195D01*
X251027Y962745D01*
X253999D01*
X258691Y958053D01*
G01X218197Y959331D02*
X219982Y957546D01*
X222041D01*
G01Y954200D02*
X219916D01*
X218197Y952481D01*
G01X225057Y989205D02*
Y991341D01*
X222041Y994357D01*
G01X208844Y1244936D02*
X209229Y1244551D01*
Y1241018D01*
X211146Y1239101D01*
X217096D01*
X220278Y1242283D01*
X226305D01*
G01X222041Y1255381D02*
Y1254813D01*
X218590Y1251362D01*
G01D02*
Y1255321D01*
X219213Y1255944D01*
G01X219660Y1260492D02*
X222632Y1257520D01*
X224524D01*
G01X222041Y1252034D02*
X225390D01*
G01X209390Y1250614D02*
X210707D01*
X211991Y1249330D01*
Y1244939D01*
X211994Y1244936D01*
G01X246654Y1734212D02*
X245320D01*
X243400Y1732292D01*
Y1640202D01*
X234340Y1631142D01*
X209820D01*
G01X220142Y1640209D02*
X231250D01*
X233973Y1642932D01*
Y1667200D01*
X238780Y1672007D01*
G01X223590Y1635840D02*
X230329D01*
X235854Y1641365D01*
Y1664357D01*
X238780Y1667283D01*
G01X238063Y31178D02*
Y26232D01*
G01X238297Y129703D02*
X240328Y127672D01*
X279488D01*
X291874Y115286D01*
Y98686D01*
X295357Y95203D01*
Y88903D01*
G01X402962Y1012501D02*
X400148Y1010877D01*
G02X398337Y1010899I-886J1624D01*
G03X396487I-925J-1602D01*
G01X396449Y1010877D01*
G02X394636Y1010899I-887J1624D01*
G03X392786I-925J-1602D01*
G02X390936I-925J1602D01*
G03X389086I-925J-1602D01*
G01X389033Y1010868D01*
G02X387236Y1010899I-871J1633D01*
G03X385386I-925J-1602D01*
G02X383536I-925J1602D01*
G03X381686I-925J-1602D01*
G01X381633Y1010868D01*
G02X379836Y1010899I-871J1633D01*
G03X377986I-925J-1602D01*
G01X377933Y1010868D01*
G02X376136Y1010899I-871J1633D01*
G03X374286I-925J-1602D01*
G01X374248Y1010877D01*
G02X372437Y1010899I-886J1624D01*
G03X370587I-925J-1602D01*
G01X370549Y1010877D01*
G02X368736Y1010899I-887J1624D01*
G03X366886I-925J-1602D01*
G02X365036I-925J1602D01*
G03X363186I-925J-1602D01*
G01X363133Y1010868D01*
G02X361336Y1010899I-871J1633D01*
G03X359486I-925J-1602D01*
G02X357636I-925J1602D01*
G03X355786I-925J-1602D01*
G02X353936I-925J1602D01*
G03X352086I-925J-1602D01*
G02X350236I-925J1602D01*
G03X348386I-925J-1602D01*
G02X346536I-925J1602D01*
G01X346386Y1010986D01*
G03X344670Y1010899I-775J-1689D01*
G01X344635Y1010864D01*
X337872D01*
X336035Y1009027D01*
X322937D01*
X322936Y1009028D01*
X306703D01*
X296372Y998697D01*
Y966614D01*
X282216Y952458D01*
X273051Y948662D01*
X260294D01*
X253897Y942265D01*
X249697D01*
X246307Y938875D01*
X245527D01*
X242391Y935739D01*
X232781D01*
X225657Y928615D01*
Y787925D01*
X232947Y780635D01*
Y763615D01*
X231137Y761805D01*
Y731446D01*
X238940Y723643D01*
Y716652D01*
G01X401111Y1009297D02*
X398337Y1007695D01*
G02X396487I-925J1602D01*
G01X396449Y1007717D01*
G03X394636Y1007695I-887J-1624D01*
G02X392786I-925J1602D01*
G01X392733Y1007726D01*
G03X390936Y1007695I-871J-1633D01*
G02X389086I-925J1602D01*
G03X387236I-925J-1602D01*
G02X385386I-925J1602D01*
G01X385333Y1007726D01*
G03X383536Y1007695I-871J-1633D01*
G02X381686I-925J1602D01*
G01X381633Y1007726D01*
G03X379836Y1007695I-871J-1633D01*
G02X377986I-925J1602D01*
G01X377933Y1007726D01*
G03X376136Y1007695I-871J-1633D01*
G02X374286I-925J1602D01*
G01X374248Y1007717D01*
G03X372437Y1007695I-886J-1624D01*
G02X370587I-925J1602D01*
G01X370549Y1007717D01*
G03X368736Y1007695I-887J-1624D01*
G02X366886I-925J1602D01*
G01X366833Y1007726D01*
G03X365036Y1007695I-871J-1633D01*
G02X363186I-925J1602D01*
G03X361336I-925J-1602D01*
G02X359486I-925J1602D01*
G01X359433Y1007726D01*
G03X357636Y1007695I-871J-1633D01*
G02X355786I-925J1602D01*
G03X353936I-925J-1602D01*
G02X352086I-925J1602D01*
G01X352033Y1007726D01*
G03X350236Y1007695I-871J-1633D01*
G02X348386I-925J1602D01*
G03X346536I-925J-1602D01*
G02X344686I-925J1602D01*
G01X344587Y1007753D01*
G03X342829Y1007695I-825J-1660D01*
G01X340913Y1005779D01*
X336470D01*
X335117Y1004426D01*
X325223D01*
X322617Y1001820D01*
Y984884D01*
X286896Y949163D01*
X268218Y943497D01*
X264332D01*
X257638Y941466D01*
X252339Y936167D01*
X251225Y935705D01*
X246897D01*
X243721Y932529D01*
X234111D01*
X228867Y927285D01*
Y789285D01*
X230057Y788095D01*
X233967D01*
X240057Y782005D01*
Y763315D01*
X234657Y757915D01*
Y732905D01*
X242460Y725102D01*
Y716652D01*
G01X236267Y763585D02*
Y766030D01*
X235499Y766798D01*
G01X325182Y978814D02*
X321377D01*
X288991Y946428D01*
X267622Y939945D01*
X264340D01*
G01X258970Y938162D02*
X254287Y933479D01*
X251600Y932365D01*
X249367D01*
X246324Y929322D01*
X243724Y928245D01*
X241797D01*
X239577Y926025D01*
X234797D01*
X232887Y924115D01*
Y865685D01*
X233387Y865185D01*
Y860645D01*
X232887Y860145D01*
Y829005D01*
X233727Y828165D01*
Y824055D01*
X232817Y823145D01*
Y793264D01*
X234809Y791272D01*
X239180D01*
X248442Y782010D01*
Y772482D01*
G01X317202Y970250D02*
X315688D01*
X289034Y943596D01*
X267035Y936923D01*
X251276Y930394D01*
X248821Y927939D01*
X244080Y925975D01*
X243197D01*
X237390Y920168D01*
Y797022D01*
X257342Y777070D01*
Y771782D01*
G01X331214Y1079413D02*
X310910D01*
X267920Y1036423D01*
X250515D01*
X249647Y1035555D01*
X239657D01*
G01X226910Y1227939D02*
X266711D01*
X274693Y1235921D01*
Y1251911D01*
G01X233970Y1245182D02*
X231071Y1242283D01*
X229455D01*
G01X240240Y1252562D02*
Y1248987D01*
X241160Y1248067D01*
G01X250467Y1259175D02*
X250447Y1259155D01*
X248126Y1253546D01*
X246415Y1251835D01*
X240967D01*
X240240Y1252562D01*
G01X241160Y1244917D02*
X239495D01*
X238730Y1245682D01*
Y1247955D01*
X236214Y1254029D01*
X233444Y1256799D01*
X231703Y1257520D01*
X227674D01*
G01X230084Y1251546D02*
X230741Y1250889D01*
Y1248688D01*
G01X230864Y1254295D02*
X232113D01*
X233632Y1252776D01*
Y1245520D01*
X233970Y1245182D01*
G01X235599Y1262074D02*
X232877Y1259352D01*
X232820D01*
G01X266990Y41832D02*
X268720Y40102D01*
Y26361D01*
X262721Y20362D01*
X246510D01*
G01X263240Y38122D02*
X264960D01*
X265720Y37362D01*
Y29362D01*
X260720Y24362D01*
X248850D01*
X246360Y26852D01*
G01X249885Y69623D02*
Y67867D01*
X250859Y66893D01*
Y63671D01*
G01X245220Y67862D02*
X246859Y66223D01*
Y63661D01*
G01X248442Y769332D02*
Y765175D01*
X250457Y763160D01*
Y761160D01*
G01X245487Y755435D02*
Y756348D01*
X250299Y761160D01*
X250457D01*
G01X254477Y761270D02*
Y765767D01*
X257342Y768632D01*
G01X259510Y757822D02*
X256062Y761270D01*
X254477D01*
G01X344029Y926807D02*
X337765Y933071D01*
X330749D01*
X330081Y933739D01*
X303581D01*
X288937Y919095D01*
X261888D01*
X259559Y918131D01*
X255668Y915531D01*
X254640Y914503D01*
Y882186D01*
X253496Y881042D01*
Y806545D01*
X271342Y788699D01*
Y782150D01*
X273737Y779755D01*
G01X276147Y916225D02*
X260932D01*
X259312Y915554D01*
X256740Y912982D01*
Y879866D01*
X255356Y878482D01*
Y810273D01*
X259759Y805870D01*
X260953D01*
X262610Y804213D01*
Y800261D01*
X273202Y789669D01*
Y784050D01*
X277334Y779918D01*
Y758241D01*
X278937Y754372D01*
Y745430D01*
X277046Y743539D01*
G01X254160Y959342D02*
X253537D01*
X251741Y957546D01*
G01X254520Y953922D02*
X252019D01*
X251741Y954200D01*
G01Y994357D02*
Y991571D01*
X248575Y988405D01*
G01X260441Y1057940D02*
X255530D01*
G01X248047Y1259155D02*
X246321Y1254989D01*
X245638Y1254306D01*
X245066D01*
G01X241160Y1244917D02*
X243384D01*
X245002Y1246535D01*
X249263D01*
X254292Y1251564D01*
G01X251707Y1252034D02*
X250807D01*
X247973Y1249200D01*
G01X248047Y1261902D02*
Y1259155D01*
G01X262402Y1668070D02*
X257485Y1663153D01*
Y1643285D01*
X246867Y1632667D01*
G01X254625Y1632354D02*
Y1637371D01*
X259366Y1642112D01*
Y1660310D01*
X262402Y1663346D01*
G01X275797Y129592D02*
X271463D01*
X259933Y141122D01*
G01X283053Y139728D02*
Y144209D01*
X276059Y151203D01*
X264578D01*
G01X260100Y159562D02*
X262600Y157062D01*
X274500D01*
X291460Y140102D01*
Y124622D01*
X297117Y118965D01*
Y100902D01*
X297657Y100362D01*
G01X273046Y720094D02*
X277046D01*
G01X265043D02*
X269046D01*
G01X269600Y715792D02*
Y719540D01*
X269046Y720094D01*
G01X277046Y729889D02*
X273046D01*
G01X274247Y727165D02*
X273046Y728366D01*
Y729889D01*
G01X268331Y738029D02*
Y733754D01*
X269046Y733039D01*
G01X265997Y747535D02*
X264800Y741516D01*
Y729888D01*
X266294Y726279D01*
X269046Y723527D01*
Y723244D01*
G01X272208Y768516D02*
X273180Y767544D01*
Y758605D01*
X268870Y748198D01*
Y747143D01*
G01X277046Y740389D02*
X277006Y740429D01*
X273000D01*
G01X328819Y924439D02*
X308539D01*
X272117Y888017D01*
Y876363D01*
X266954Y871200D01*
Y812644D01*
X271360Y808238D01*
Y802761D01*
X280642Y793479D01*
Y788503D01*
X284223Y784922D01*
G01X263747Y885135D02*
Y878029D01*
X261090Y875372D01*
X259534D01*
X257216Y873054D01*
Y811045D01*
X260441Y807820D01*
X262201D01*
X265780Y804241D01*
Y799883D01*
X275062Y790601D01*
Y784870D01*
X279414Y780518D01*
Y758134D01*
X281046Y754195D01*
Y752539D01*
G01X279217Y902685D02*
X266177Y889645D01*
Y875687D01*
X263210Y872720D01*
Y860511D01*
X262700Y860001D01*
X260278D01*
X259768Y859491D01*
Y858001D01*
X260278Y857491D01*
X262700D01*
X263210Y856981D01*
Y831716D01*
X259110Y827616D01*
Y822743D01*
X259620Y822233D01*
X261033D01*
X261543Y821723D01*
Y820233D01*
X261033Y819723D01*
X259620D01*
X259110Y819213D01*
Y815107D01*
X267640Y806577D01*
Y800913D01*
X276922Y791631D01*
Y785680D01*
X281304Y781298D01*
Y758564D01*
X283037Y754381D01*
Y745530D01*
X281046Y743539D01*
G01X269117Y881535D02*
Y875995D01*
X265094Y871972D01*
Y811754D01*
X269500Y807348D01*
Y801863D01*
X278782Y792581D01*
Y786620D01*
X283396Y782006D01*
Y758820D01*
X285046Y754836D01*
Y752539D01*
G01X291215Y782792D02*
Y785196D01*
X285262Y791149D01*
Y795560D01*
X275980Y804842D01*
Y810704D01*
X271574Y815110D01*
Y869285D01*
X276767Y874478D01*
Y885999D01*
X307723Y916955D01*
X330127D01*
G01X331268Y920364D02*
X329503Y922129D01*
X309571D01*
X274447Y887005D01*
Y875425D01*
X269264Y870242D01*
Y814153D01*
X273670Y809747D01*
Y803881D01*
X282952Y794599D01*
Y790000D01*
X288901Y784051D01*
Y774093D01*
G01X326374Y926299D02*
X307599D01*
X269117Y887817D01*
Y881535D01*
G01X338772Y925701D02*
X334454Y930019D01*
X305311D01*
X286967Y911675D01*
X283207D01*
X263747Y892215D01*
Y885135D01*
G01X339114Y1052429D02*
X338300Y1051615D01*
X313477D01*
X289287Y1027425D01*
Y1021151D01*
X284639Y1016503D01*
Y975639D01*
X274105Y965105D01*
X269977D01*
G01X316808Y1033357D02*
X310500D01*
X287359Y1010216D01*
Y974152D01*
X271260Y958053D01*
X261841D01*
G01X334607Y1080766D02*
X333797D01*
X332828Y1081735D01*
X310916D01*
X267956Y1038775D01*
X266486D01*
G01X274693Y1255061D02*
X268597D01*
G01X257442Y1255756D02*
Y1251564D01*
G01X268597Y1255061D02*
X262170D01*
G01D02*
X258137D01*
X257442Y1255756D01*
G01X260441Y1248688D02*
X263790D01*
G01X269427Y1381893D02*
X316439Y1428905D01*
X379007D01*
X385030Y1422882D01*
X403801D01*
X406479Y1420204D01*
Y1418492D01*
G01X286720Y45937D02*
X290720D01*
G01X277046Y720094D02*
X277137Y720185D01*
X278786D01*
X279200Y719771D01*
Y718062D01*
X289710Y707552D01*
Y704830D01*
X289918Y704143D01*
X291028Y702482D01*
X294697Y700962D01*
X299900D01*
G01X277046Y723244D02*
Y725709D01*
G01Y733039D02*
Y735442D01*
G01X286046Y723244D02*
Y726535D01*
X285700Y726881D01*
Y731220D01*
X284358Y732562D01*
G01D02*
Y734346D01*
X287217Y737205D01*
Y740200D01*
X289314Y742297D01*
X290515D01*
X292160Y743942D01*
X292706Y745261D01*
Y749233D01*
G01X283350Y728483D02*
X283105Y728238D01*
Y725647D01*
X282120Y724662D01*
Y723142D01*
G01X290953Y717400D02*
X290358D01*
X289812Y717946D01*
Y734600D01*
X289137Y735275D01*
G01X285046Y740389D02*
Y737964D01*
G01D02*
X281046Y733964D01*
Y733039D01*
G01Y740389D02*
Y737938D01*
G01X275210Y738102D02*
X277046Y739938D01*
Y740389D01*
G01X273737Y779755D02*
X275246Y778246D01*
Y758082D01*
X277046Y753739D01*
Y752539D01*
G01Y746702D02*
Y749389D01*
G01D02*
X274250Y752185D01*
X273800D01*
X273246Y752739D01*
G01X284223Y784922D02*
X286557Y782588D01*
Y759366D01*
X290637Y755286D01*
Y748589D01*
X286973Y744925D01*
X286432D01*
X285046Y743539D01*
G01X281046Y749389D02*
Y746702D01*
G01X285046Y749389D02*
X288546D01*
X288646Y749289D01*
G01X285046Y746702D02*
Y749389D01*
G01X288901Y774093D02*
Y763292D01*
X296706Y755487D01*
Y752383D01*
G01X334407Y913241D02*
X332001D01*
X330597Y914645D01*
X309037D01*
X279107Y884715D01*
Y873550D01*
X273884Y868327D01*
Y816068D01*
X278290Y811662D01*
Y805822D01*
X287617Y796495D01*
Y793685D01*
X289797Y791505D01*
G01X282417Y880465D02*
Y873800D01*
X275639Y867022D01*
G01X330175Y913535D02*
X309727D01*
X282417Y886225D01*
Y880465D01*
G01X337331Y925110D02*
X334282Y928159D01*
X306330D01*
X286286Y908115D01*
X284647D01*
X279217Y902685D01*
G01X343296Y925714D02*
X337131Y931879D01*
X304451D01*
X288797Y916225D01*
X276147D01*
G01X340052Y1053781D02*
X339492Y1054341D01*
X312223D01*
X286810Y1028928D01*
Y1023227D01*
X281759Y1018176D01*
Y1010061D01*
G01X331174Y1077515D02*
X313198D01*
X276582Y1040899D01*
G01X344759Y1071759D02*
X344719Y1071719D01*
X322937D01*
X322936Y1071720D01*
X318198D01*
X284103Y1037625D01*
G01X344830Y1072860D02*
X344805Y1072835D01*
X322937D01*
X322936Y1072836D01*
X316288D01*
X287875Y1044423D01*
G01X343941Y1074659D02*
X331725D01*
X331210Y1075174D01*
X322937D01*
X322936Y1075175D01*
X315057D01*
X289406Y1049524D01*
G01X291520Y18312D02*
X295520D01*
G01D02*
Y26362D01*
G01X302720Y42787D02*
Y38182D01*
G01X293161Y50522D02*
X290720Y48081D01*
Y45937D01*
G01X298720D02*
X302720D01*
G01X306570Y50222D02*
X306130D01*
X302720Y46812D01*
Y45937D01*
G01X303715Y50857D02*
X300710Y47852D01*
X295710D01*
X294720Y46862D01*
Y45937D01*
G01X305247Y71567D02*
X299929D01*
X297657Y73839D01*
Y100362D01*
G01X400589Y575236D02*
X400377Y575448D01*
X399888D01*
X295962Y679374D01*
G01X523699Y571545D02*
X522313Y570159D01*
X423839D01*
X308668Y685330D01*
Y693204D01*
X300910Y700962D01*
X299900D01*
G01X294687Y707645D02*
X295507D01*
X298127Y705025D01*
X300611D01*
X311329Y694307D01*
Y685937D01*
X424574Y572692D01*
X470880D01*
G01X296706Y749233D02*
X295877Y748404D01*
Y746664D01*
X292122Y737596D01*
Y720323D01*
X293515Y718930D01*
Y713047D01*
X298781Y707781D01*
X301123D01*
X313639Y695265D01*
Y686894D01*
X425403Y575130D01*
X541820D01*
G01X556820Y570462D02*
X549920D01*
X538322Y582060D01*
X428274D01*
X320569Y689765D01*
Y698137D01*
X307677Y711029D01*
Y718955D01*
X304372Y722260D01*
Y724900D01*
X301797Y727475D01*
Y735671D01*
X306303Y746551D01*
Y768290D01*
X300507Y774086D01*
Y794075D01*
X292402Y802180D01*
Y883040D01*
X313886Y904524D01*
G01X291215Y782792D02*
Y764266D01*
X299107Y756374D01*
Y748170D01*
X294432Y736884D01*
Y721280D01*
X295825Y719887D01*
Y714168D01*
X299408Y710585D01*
X301587D01*
X315949Y696223D01*
Y687851D01*
X426360Y577440D01*
X537730D01*
G01X290953Y714250D02*
Y712593D01*
X291013Y712533D01*
Y711236D01*
X294604Y707645D01*
X294687D01*
G01X301038Y716760D02*
Y720749D01*
G01X531472Y579750D02*
X427317D01*
X318259Y688808D01*
Y697180D01*
X305047Y710392D01*
Y716740D01*
X301038Y720749D01*
G01X298197Y786070D02*
Y773086D01*
X303993Y767290D01*
Y747131D01*
X299437Y736127D01*
Y725500D01*
X301038Y723899D01*
G01X289797Y791505D02*
X293709Y787593D01*
Y765433D01*
X301417Y757725D01*
Y747627D01*
X297087Y737175D01*
Y726992D01*
G01X306579Y740759D02*
X304602Y735987D01*
Y733569D01*
G01X293027Y755985D02*
Y752704D01*
X292706Y752383D01*
G01X328995Y911015D02*
X316567D01*
X290092Y884540D01*
Y800329D01*
X298197Y792224D01*
Y786070D01*
G01X310694Y897810D02*
X294712Y881828D01*
Y803621D01*
X303077Y795256D01*
Y775054D01*
X308613Y769518D01*
Y745670D01*
X306579Y740759D01*
G01X303730Y887208D02*
X297022Y880500D01*
Y805010D01*
X305937Y796095D01*
Y775505D01*
X310923Y770519D01*
Y745076D01*
X307447Y736683D01*
Y729985D01*
X307967Y729465D01*
Y726419D01*
G01X330467Y901575D02*
X321689D01*
X299332Y879218D01*
Y806500D01*
X308557Y797275D01*
Y793945D01*
G01X330292Y899719D02*
X323217D01*
X301642Y878144D01*
Y809251D01*
X311417Y799476D01*
Y782375D01*
G01X328202Y898467D02*
X325467D01*
X303952Y876952D01*
Y810577D01*
X307030Y807499D01*
G01X330177Y904264D02*
X329798Y903885D01*
X320407D01*
X303730Y887208D01*
G01X338775Y1043335D02*
X334646Y1047464D01*
X322937D01*
X322936Y1047465D01*
X318297D01*
X294827Y1023995D01*
X291497D01*
G01X341555Y1044664D02*
X336955Y1049264D01*
X322081D01*
X322080Y1049265D01*
X316235D01*
X296604Y1029634D01*
G01X339847Y1039515D02*
X337323D01*
X336447Y1040391D01*
Y1042198D01*
X335720Y1042925D01*
X330467D01*
X329160Y1044232D01*
X317696D01*
X290878Y1017414D01*
X289404D01*
G01X341819Y1068824D02*
X322937D01*
X322936Y1068825D01*
X318579D01*
X294343Y1044589D01*
G01X341546Y1067364D02*
X322937D01*
X322936Y1067365D01*
X320518D01*
X290654Y1037501D01*
G01X297835Y1734212D02*
Y1734157D01*
X291050Y1727372D01*
Y1649350D01*
X295010Y1645390D01*
X367140D01*
G01X310400Y50362D02*
X306720Y46682D01*
Y45937D01*
G01X320270Y205049D02*
Y200462D01*
G01X323314Y210645D02*
X318791D01*
X316345Y208199D01*
G01Y205049D02*
X320270D01*
G01X319718Y223750D02*
X318158Y225310D01*
Y228412D01*
G01X320940Y238372D02*
Y234244D01*
X318258Y231562D01*
X318158D01*
G01X550320Y583362D02*
X543040D01*
X542032Y584370D01*
X429231D01*
X323104Y690497D01*
Y698869D01*
X310847Y711126D01*
X310848D01*
X310849Y711127D01*
X310847D01*
Y716105D01*
G01X557430Y583572D02*
X554070D01*
X551762Y585880D01*
X429857D01*
X324614Y691123D01*
Y699495D01*
X314137Y709972D01*
Y721732D01*
X312656Y723213D01*
G01X569050Y578292D02*
X561340Y586002D01*
X555280D01*
X553092Y588190D01*
X430814D01*
X326924Y692080D01*
Y700452D01*
X316658Y710718D01*
Y710722D01*
X316656D01*
Y723213D01*
G01X310847Y716105D02*
Y720389D01*
X307967Y723269D01*
G01X536626Y590500D02*
X431771D01*
X329234Y693037D01*
Y701409D01*
X320655Y709988D01*
X320656D01*
X320658Y709990D01*
X320657D01*
X320656Y709989D01*
Y723213D01*
G01X311417Y782375D02*
Y773115D01*
X313157Y771375D01*
Y744607D01*
X310957Y739295D01*
Y729786D01*
X312656Y728087D01*
Y726363D01*
G01X320656Y730213D02*
Y726363D01*
G01X315274Y803537D02*
X316621Y802190D01*
Y783172D01*
X320347Y779446D01*
Y741985D01*
X322497Y739835D01*
Y732054D01*
X320656Y730213D01*
G01X316656Y726363D02*
Y730213D01*
G01X307030Y807499D02*
X313971Y800558D01*
Y773830D01*
X315557Y772244D01*
Y743959D01*
X313507Y739009D01*
Y731034D01*
X314328Y730213D01*
X316656D01*
G01X317967Y752890D02*
Y771875D01*
G01Y743909D02*
Y746985D01*
G01D02*
Y749740D01*
G01X310049Y813653D02*
X318731Y804971D01*
Y784751D01*
X322423Y781059D01*
Y743139D01*
X324507Y741055D01*
Y735265D01*
X327107Y732665D01*
G01X316354Y812166D02*
X321036Y807484D01*
Y785350D01*
X324433Y781953D01*
Y744536D01*
X327096Y741873D01*
G01X331603Y891562D02*
X331092D01*
X312592Y873062D01*
Y821480D01*
X323576Y810496D01*
Y804265D01*
G01X327946Y895464D02*
X325766D01*
X306262Y875960D01*
Y812549D01*
X315274Y803537D01*
G01X328733Y885151D02*
X314902Y871320D01*
Y822610D01*
X326097Y811415D01*
Y796665D01*
G01X331746Y884264D02*
X317212Y869730D01*
Y823861D01*
X328578Y812495D01*
Y792548D01*
X331839Y789287D01*
G01X328524Y893848D02*
X327013D01*
X308272Y875107D01*
Y815430D01*
X310049Y813653D01*
G01X329440Y892602D02*
X328750D01*
X310282Y874134D01*
Y818238D01*
X316354Y812166D01*
G01X331318Y879711D02*
X329595Y877988D01*
Y874472D01*
X321517Y866394D01*
Y825205D01*
X332517Y814205D01*
Y797255D01*
X338667Y791105D01*
Y772452D01*
G01X331753Y882444D02*
X327961Y878652D01*
Y875620D01*
X319998Y867657D01*
Y824514D01*
X330987Y813525D01*
Y794645D01*
X335473Y790159D01*
Y782485D01*
G01X337571Y905564D02*
X329527D01*
X328696Y906395D01*
X319279D01*
X310694Y897810D01*
G01X313886Y904524D02*
X318067Y908705D01*
X328767D01*
X330008Y907464D01*
G01X329585Y912425D02*
X313597D01*
X310482Y909310D01*
G01X343761Y999684D02*
X337533Y993456D01*
Y982325D01*
X328572Y973364D01*
X320316D01*
X317202Y970250D01*
G01X342836Y1026920D02*
X341103D01*
X337752Y1023569D01*
X310839D01*
G01X346475Y1034543D02*
X334967D01*
X331345Y1038165D01*
X321078D01*
G01X346419Y1033356D02*
X322937D01*
X322936Y1033357D01*
X316808D01*
G01X331661Y1061896D02*
X327885D01*
X326794Y1062987D01*
X321528D01*
X319515Y1060974D01*
G01X329458Y1058917D02*
X323828D01*
X321739Y1056828D01*
G01X330800Y205049D02*
Y207611D01*
G01D02*
X330654D01*
X328588Y209677D01*
G01X547020Y590332D02*
X543415Y593937D01*
X527673D01*
X526518Y595092D01*
X476792D01*
X474510Y592810D01*
X432728D01*
X331544Y693994D01*
Y702366D01*
X324660Y709250D01*
Y709256D01*
X324656D01*
Y723213D01*
G01X729328Y583076D02*
X728739Y582487D01*
X717229D01*
X715564Y580822D01*
X702970D01*
X687545Y596247D01*
X529775D01*
X528220Y597802D01*
X475990D01*
X473340Y595152D01*
X433653D01*
X335488Y693317D01*
Y708087D01*
X330768Y712807D01*
Y721325D01*
X332656Y723213D01*
G01X467130Y600122D02*
X431951D01*
X337937Y694136D01*
Y709005D01*
X333438Y713504D01*
Y718945D01*
X337937Y723444D01*
Y731885D01*
X336287Y733535D01*
X335464D01*
X335126Y733873D01*
G01X340446Y749233D02*
X340407Y749194D01*
Y720611D01*
X338161Y718365D01*
G01X729295Y586113D02*
X726159D01*
X721847Y590425D01*
X715857D01*
X706230Y600052D01*
X474301D01*
X473669Y599420D01*
X471292D01*
X468251Y602461D01*
X432880D01*
X340407Y694934D01*
Y716119D01*
X338161Y718365D01*
G01X323576Y804265D02*
Y787300D01*
X326957Y783919D01*
Y745425D01*
X329907Y742475D01*
Y732666D01*
X327016Y729775D01*
X326107D01*
X324656Y728324D01*
Y726363D01*
G01X326097Y796665D02*
Y791235D01*
X329357Y787975D01*
Y746295D01*
X332217Y743435D01*
Y731705D01*
X328656Y728144D01*
Y726363D01*
G01Y723213D02*
X332656D01*
G01X334546Y738723D02*
X335097Y738172D01*
Y733902D01*
X335126Y733873D01*
G01X331839Y789287D02*
Y747083D01*
X334527Y744395D01*
Y744136D01*
X334546Y744117D01*
Y741873D01*
G01X335473Y782485D02*
Y753356D01*
X336446Y752383D01*
G01X334370Y876816D02*
X323017Y865463D01*
Y825925D01*
X333931Y815011D01*
Y799167D01*
X341527Y791571D01*
Y778362D01*
G01X344377Y785725D02*
Y790990D01*
X335471Y799896D01*
Y816431D01*
X325127Y826775D01*
Y864545D01*
X333915Y873333D01*
G01X344267Y867575D02*
X339507Y862815D01*
X337986D01*
X334037Y858866D01*
Y839624D01*
X341584Y832077D01*
G01X346122Y866730D02*
X337727Y858335D01*
Y856875D01*
X336225Y855373D01*
Y841368D01*
X354013Y823580D01*
X355769D01*
X362279Y817070D01*
Y803493D01*
X359007Y800221D01*
Y791355D01*
X358902Y791250D01*
Y773352D01*
G01X339959Y875487D02*
X333877Y869405D01*
G01X348907Y889705D02*
Y889225D01*
X347957Y888275D01*
X332977D01*
X332661Y887959D01*
X330963D01*
G01X334841Y918495D02*
X327507D01*
X326277Y919725D01*
G01X331284Y978814D02*
X325182D01*
G01X344025Y1014132D02*
X342812Y1012919D01*
X331733D01*
X327617Y1017035D01*
G01X342709Y1036385D02*
X335637D01*
X331123Y1040899D01*
X325637D01*
G01X331462Y1059943D02*
X330893Y1060512D01*
X326856D01*
X326122Y1061246D01*
X324787D01*
X324515Y1060974D01*
G01X329668Y1057027D02*
X327441D01*
X327108Y1056694D01*
G01X339004Y1064495D02*
X338167D01*
X336727Y1063055D01*
G01X339004Y1065497D02*
X332059D01*
X330667Y1064105D01*
G01X331693Y1087864D02*
X332889D01*
X334302Y1086451D01*
G01X332355Y1085622D02*
X327935D01*
X325693Y1087864D01*
G01X478510Y602942D02*
X476120D01*
X471190Y607872D01*
X432900D01*
X344360Y696412D01*
Y736172D01*
X346950Y738762D01*
Y747682D01*
X345399Y749233D01*
X344446D01*
G01X472960Y602152D02*
X471241Y603871D01*
X433465D01*
X341818Y695518D01*
Y737554D01*
X342477Y738213D01*
Y743384D01*
X344440Y745347D01*
G01X482780Y607012D02*
X476100D01*
X470810Y612302D01*
X430551D01*
X345920Y696933D01*
Y735641D01*
X348446Y738167D01*
Y749233D01*
X346417Y751262D01*
Y753385D01*
X344377Y755425D01*
Y785725D01*
G01X351422Y705965D02*
Y700972D01*
G01X355946Y722900D02*
X356470Y722376D01*
Y718512D01*
X356070Y718112D01*
X354305D01*
G01X351746Y710632D02*
Y706289D01*
X351422Y705965D01*
G01X351746Y710632D02*
X351695Y710683D01*
Y712397D01*
X351317Y712775D01*
X349608D01*
X349187Y712354D01*
Y710632D01*
G01X351746Y718112D02*
Y719191D01*
X348037Y722900D01*
G01X354100Y720743D02*
X351946Y722897D01*
G01X352879Y728657D02*
Y726980D01*
X351946Y726047D01*
G01X348037Y722900D02*
X351943D01*
X351946Y722897D01*
G01X341527Y778362D02*
Y755302D01*
X344446Y752383D01*
G01X338667Y772452D02*
Y754162D01*
X340446Y752383D01*
G01X344440Y745347D02*
X344446Y745353D01*
Y749233D01*
G01X341584Y832077D02*
X352140Y821521D01*
X354916D01*
X360220Y816217D01*
Y804346D01*
X355543Y799669D01*
Y759299D01*
X356072Y758770D01*
Y732390D01*
X357850Y730612D01*
Y724804D01*
X355946Y722900D01*
G01X338546Y848131D02*
Y843247D01*
X355158Y826635D01*
X356751D01*
X365372Y818014D01*
Y799217D01*
X363359Y797204D01*
G01X340423Y847693D02*
Y845188D01*
X356294Y829317D01*
X357837D01*
X367996Y819158D01*
Y797367D01*
X365547Y794918D01*
Y787015D01*
G01X343703Y846354D02*
X345243Y844814D01*
Y843978D01*
X350157Y839064D01*
X350172D01*
X355402Y833834D01*
X360412D01*
X372117Y822129D01*
Y778576D01*
G01X342603Y847887D02*
Y845080D01*
X356488Y831195D01*
X359909D01*
X370683Y820421D01*
Y794332D01*
X368830Y792479D01*
G01X343761Y1046394D02*
X343554D01*
X341027Y1048921D01*
G01X342231Y1055058D02*
X346780D01*
G01X650705Y270947D02*
X604070Y224312D01*
X590910D01*
X583390Y216792D01*
Y189382D01*
X574870Y180862D01*
X501910D01*
X485020Y163972D01*
X475570D01*
X447840Y136242D01*
X374293D01*
X371915Y133864D01*
Y128167D01*
X366270Y122522D01*
X361800D01*
G01X559927Y548457D02*
X553940Y542470D01*
Y500486D01*
X568456Y485970D01*
Y464584D01*
X585745Y447295D01*
Y429279D01*
X591178Y423846D01*
Y364649D01*
X585678Y359149D01*
X551612D01*
X548546Y356083D01*
X547490D01*
X545235Y353828D01*
X486655D01*
X477121Y363362D01*
X468140D01*
X465340Y366162D01*
Y375932D01*
X466890Y377482D01*
Y385342D01*
X464370Y387862D01*
X455200D01*
X450400Y383062D01*
Y372763D01*
X438499Y360862D01*
X369543D01*
X364014Y366391D01*
G01X358902Y736225D02*
X369327D01*
X374902Y741800D01*
Y749233D01*
G01X358902Y743035D02*
X364223D01*
X366902Y745714D01*
Y749233D01*
G01X362902Y752383D02*
X366902D01*
G01X363359Y797204D02*
X361967Y795812D01*
Y768626D01*
X365580Y765013D01*
Y755061D01*
X362902Y752383D01*
G01X358902Y754945D02*
Y752383D01*
G01X365547Y787015D02*
Y768985D01*
X370902Y763630D01*
Y752383D01*
G01X358902Y773352D02*
Y754945D01*
G01X368830Y792479D02*
Y770882D01*
X378902Y760810D01*
Y752383D01*
G01X368600Y1543200D02*
Y1554400D01*
X375000Y1560800D01*
X384000D01*
X401500Y1578300D01*
X412600D01*
X424200Y1589900D01*
X460200D01*
G01X613220Y654662D02*
X401200D01*
X371970Y683892D01*
G01X381010Y734732D02*
X383608Y737330D01*
X385802D01*
X390077Y741605D01*
Y750864D01*
X388558Y752383D01*
X386902D01*
G01X374902D02*
X370902D01*
G01X372117Y778576D02*
Y772935D01*
X382902Y762150D01*
Y752383D01*
G01Y749233D02*
X384454Y750785D01*
X385304D01*
X386902Y752383D01*
G01X374800Y1546400D02*
Y1553700D01*
X376640Y1555540D01*
X383660D01*
X401440Y1573320D01*
X427161D01*
X433350Y1579509D01*
G01X666700Y1595500D02*
X667999D01*
X673300Y1590199D01*
Y1573600D01*
X663900Y1564200D01*
X480100D01*
X467800Y1551900D01*
X459024D01*
X456024Y1548900D01*
X444199D01*
X440499Y1545200D01*
X390600D01*
X385100Y1539700D01*
G01X666700Y1591900D02*
X667656D01*
X671300Y1588256D01*
Y1574429D01*
X663071Y1566200D01*
X476500D01*
X471100Y1560800D01*
X467300D01*
X460200Y1553700D01*
X449300D01*
X447800Y1552200D01*
X444301D01*
X439563Y1547462D01*
X389662D01*
X381800Y1539600D01*
G01X666600Y1584900D02*
X663700Y1582000D01*
Y1571780D01*
X661620Y1569700D01*
X474600D01*
X469300Y1564400D01*
X465200D01*
X458642Y1557842D01*
X446158D01*
X443500Y1560500D01*
X420100D01*
X414221Y1554621D01*
X389121D01*
X381000Y1546500D01*
G01X666700Y1588500D02*
X669300Y1585900D01*
Y1575258D01*
X662242Y1568200D01*
X475671D01*
X470271Y1562800D01*
X466471D01*
X459371Y1555700D01*
X448700D01*
X446600Y1553600D01*
X442400D01*
X440500Y1555500D01*
X424800D01*
X418200Y1548900D01*
X402300D01*
X398700Y1552500D01*
X390000D01*
X384000Y1546500D01*
G01X387810Y1660457D02*
X383790D01*
X383740Y1660407D01*
G01X375430Y1676462D02*
Y1671442D01*
X380160Y1666712D01*
Y1663302D01*
X383055Y1660407D01*
X383740D01*
G01X396380Y62742D02*
Y67479D01*
X411691Y82790D01*
X424978D01*
X442295Y100107D01*
Y116352D01*
X504140Y178197D01*
X576556D01*
X587030Y188671D01*
Y209202D01*
X592130Y214302D01*
X605850D01*
X618160Y226612D01*
X640391D01*
X646150Y232371D01*
X654386Y252249D01*
X654110Y252915D01*
X650896Y254247D01*
X650620Y254913D01*
X651191Y256290D01*
X651857Y256566D01*
X655071Y255234D01*
X655737Y255510D01*
X656308Y256887D01*
X656032Y257553D01*
X652818Y258885D01*
X652542Y259551D01*
X653113Y260928D01*
X653779Y261204D01*
X656993Y259872D01*
X657659Y260148D01*
X658230Y261525D01*
X657954Y262191D01*
X654740Y263523D01*
X654464Y264189D01*
X655035Y265566D01*
X655701Y265842D01*
X658915Y264510D01*
X659581Y264786D01*
X660152Y266163D01*
X659876Y266829D01*
X656662Y268161D01*
X656386Y268827D01*
X656957Y270204D01*
X657623Y270480D01*
X660837Y269148D01*
X661503Y269424D01*
X662074Y270801D01*
X661798Y271467D01*
X658584Y272799D01*
X658308Y273465D01*
X658879Y274842D01*
X659545Y275118D01*
X662759Y273786D01*
X663425Y274062D01*
X663996Y275439D01*
X663720Y276105D01*
X660506Y277437D01*
X660230Y278103D01*
X660801Y279480D01*
X661467Y279756D01*
X664681Y278424D01*
X665347Y278700D01*
X665918Y280077D01*
X665642Y280743D01*
X662428Y282075D01*
X662152Y282741D01*
X662723Y284118D01*
X663389Y284394D01*
X666603Y283062D01*
X667269Y283338D01*
X667840Y284715D01*
X667564Y285381D01*
X664350Y286713D01*
X664074Y287379D01*
X664645Y288756D01*
X665311Y289032D01*
X668525Y287700D01*
X669191Y287976D01*
X669762Y289353D01*
X669486Y290019D01*
X666272Y291351D01*
X665996Y292017D01*
X666567Y293394D01*
X667233Y293670D01*
X670447Y292338D01*
X671113Y292614D01*
X671684Y293991D01*
X671408Y294657D01*
X668194Y295989D01*
X667918Y296655D01*
X668489Y298032D01*
X669155Y298308D01*
X672369Y296976D01*
X673035Y297252D01*
X673606Y298629D01*
X673330Y299295D01*
X670116Y300627D01*
X669840Y301293D01*
X670411Y302670D01*
X671077Y302946D01*
X674292Y301614D01*
X674956Y301890D01*
X677526Y308115D01*
X692162Y322751D01*
X718202D01*
X747501Y293452D01*
X805230D01*
X808289Y296511D01*
X812499D01*
G01X402100Y62632D02*
Y67512D01*
X413358Y78770D01*
X428058D01*
X464475Y115187D01*
Y132597D01*
X506055Y174177D01*
X578379D01*
X601774Y197572D01*
X618870D01*
X650670Y229372D01*
X683278Y308096D01*
X693853Y318671D01*
X716511D01*
X745810Y289372D01*
X807590D01*
X808770Y290552D01*
X817080D01*
X825598Y299070D01*
X835499D01*
G01X399240Y62722D02*
Y67495D01*
X412525Y80780D01*
X426848D01*
X444305Y98237D01*
Y115519D01*
X504973Y176187D01*
X577546D01*
X589690Y188331D01*
Y204202D01*
X591120Y205632D01*
X604880D01*
X606510Y207262D01*
X617220D01*
X621716Y211758D01*
X630213D01*
X648102Y229647D01*
X680712Y308373D01*
X693020Y320681D01*
X717344D01*
X746643Y291382D01*
X806757D01*
X809876Y294501D01*
X815759D01*
X828005Y306747D01*
X835499D01*
G01X410996Y218834D02*
X392732D01*
X388965Y215067D01*
G01X402700Y234167D02*
Y232342D01*
X388720Y218362D01*
G01X390220Y392062D02*
X397920Y384362D01*
X433925D01*
X437425Y380862D01*
G01X400926Y1404707D02*
X397106D01*
X396484Y1404085D01*
G01X393334Y1412991D02*
X390914D01*
G01X396484D02*
Y1416491D01*
G01X405946Y1408955D02*
X398410Y1416491D01*
X396484D01*
G01X400924Y1408227D02*
X397106D01*
X396484Y1407605D01*
G01X394360Y1616380D02*
X395170Y1617190D01*
Y1623880D01*
X391920Y1627130D01*
Y1637390D01*
X395170Y1640640D01*
Y1658650D01*
X393403Y1660417D01*
X391880D01*
G01Y1663567D02*
X401045D01*
X402020Y1662592D01*
X418640D01*
X425980Y1655252D01*
X454600D01*
X469580Y1640272D01*
G01X792895Y274028D02*
X798364D01*
X799940Y272452D01*
Y268322D01*
X793990Y262372D01*
X771980D01*
X768020Y258412D01*
X749456D01*
X722486Y231442D01*
X661482D01*
X621096Y191056D01*
X609524D01*
X608450Y189982D01*
Y179062D01*
X597950Y168562D01*
X592800D01*
X583220Y158982D01*
X579775D01*
X573390Y152597D01*
X499305D01*
X471885Y125177D01*
Y113487D01*
X430988Y72590D01*
X418300D01*
X410290Y64580D01*
Y61932D01*
X407970Y59612D01*
G01X407790Y62652D02*
Y67403D01*
X415137Y74750D01*
X430258D01*
X469585Y114077D01*
Y127317D01*
X498190Y155922D01*
X549080D01*
X550395Y154607D01*
X572116D01*
X579039Y161530D01*
X582868D01*
X595600Y174262D01*
X597238D01*
X605900Y182924D01*
Y191912D01*
X607356Y193368D01*
X620353D01*
X660587Y233602D01*
X721803D01*
X748803Y260602D01*
X767150D01*
X771080Y264532D01*
X785680D01*
X787750Y266602D01*
Y279682D01*
X789773Y281705D01*
X792895D01*
G01X769895Y271469D02*
X756827D01*
X720970Y235612D01*
X659754D01*
X619672Y195530D01*
X605388D01*
X603760Y193902D01*
Y183628D01*
X596574Y176442D01*
X593588D01*
X585584Y173126D01*
X577375Y164917D01*
Y162867D01*
X572825Y158317D01*
X497665D01*
X466485Y127137D01*
Y114327D01*
X428918Y76760D01*
X414192D01*
X404910Y67478D01*
Y62562D01*
G01X420865Y215067D02*
X408100Y227832D01*
Y236947D01*
X405139Y239908D01*
G01X416127Y1408090D02*
Y1404945D01*
X427110Y1393962D01*
X438600D01*
X440022Y1392540D01*
Y1387880D01*
X442740Y1385162D01*
X446408D01*
X452500Y1391254D01*
X462292D01*
X467867Y1396829D01*
Y1401865D01*
X462490Y1407242D01*
Y1446392D01*
X466900Y1450802D01*
Y1498598D01*
X478177Y1509875D01*
X688387D01*
X797461Y1400801D01*
Y1348719D01*
X823681Y1322499D01*
X862181D01*
X872857Y1311823D01*
Y972223D01*
X904757Y940323D01*
Y800452D01*
X871450Y767145D01*
Y742892D01*
X866820Y738262D01*
Y736562D01*
G01X408968Y1410427D02*
X407496Y1408955D01*
X405946D01*
G01X411162Y1414126D02*
X410698Y1413662D01*
X408095D01*
G01X404945D02*
Y1414517D01*
X406479Y1416051D01*
Y1418492D01*
G01X409140Y1566892D02*
X429930D01*
X431942Y1564880D01*
X448750D01*
X450950Y1562680D01*
X453840D01*
X461480Y1570320D01*
X468920D01*
X471700Y1573100D01*
X564070D01*
X564570Y1573600D01*
Y1593722D01*
X558200Y1600092D01*
Y1664004D01*
X550197Y1672007D01*
G01X405000Y1566670D02*
X409020Y1562650D01*
X444040D01*
X446740Y1559950D01*
X453890D01*
X459880Y1565940D01*
X468240D01*
X473900Y1571600D01*
X660900D01*
X661400Y1572100D01*
Y1595000D01*
X666930Y1600530D01*
Y1616920D01*
X664560Y1619290D01*
Y1631590D01*
X664590Y1631620D01*
G01X531258Y505473D02*
Y529224D01*
X524720Y535762D01*
X434620D01*
G01X434320Y540153D02*
X434329Y540162D01*
X494320D01*
X503020Y548862D01*
X535816D01*
X540640Y553686D01*
X559985D01*
X563612Y550059D01*
Y546673D01*
X558413Y541474D01*
Y501032D01*
X574434Y485011D01*
Y463648D01*
X589520Y448562D01*
Y439880D01*
X598338Y431062D01*
X600638D01*
X600800Y430900D01*
G01X427317Y923349D02*
X426747D01*
X425550Y924546D01*
G01X495079Y1734212D02*
X485929Y1725062D01*
X485630D01*
X485120Y1724552D01*
Y1647262D01*
X456750Y1618892D01*
Y1618812D01*
X444120Y1606182D01*
X433078D01*
X432200Y1607060D01*
G01X479736Y308598D02*
X477190Y306052D01*
Y299246D01*
X463826Y285882D01*
X452470D01*
X449992Y283404D01*
Y278551D01*
X450000Y278543D01*
G01X450500Y358862D02*
X451030Y358332D01*
Y345467D01*
X448925Y343362D01*
Y341362D01*
G01X443770Y371042D02*
Y377567D01*
X440575Y380762D01*
Y380862D01*
G01X541337Y920147D02*
X542649D01*
X543927Y921425D01*
X570067D01*
G01X542797Y922105D02*
Y922104D01*
X543678Y922985D01*
X553947D01*
X554847Y923885D01*
X579066D01*
X600850Y902101D01*
G01X561157Y1029735D02*
X548062D01*
X544899Y1032898D01*
G01X592307Y1031185D02*
X573607D01*
X570163Y1034629D01*
X554446D01*
X550458Y1036281D01*
X550040Y1036699D01*
G01X547001Y1050594D02*
X548220Y1049375D01*
X608192D01*
X609954Y1047613D01*
G01X548163Y1051735D02*
X613580D01*
X614678Y1050637D01*
G01X453805Y1401282D02*
X452148D01*
X451808Y1401622D01*
X448029D01*
X447110Y1402541D01*
Y1403812D01*
G01X438049Y1407789D02*
X439006Y1406832D01*
X442970D01*
G01D02*
X445340D01*
X446230Y1407722D01*
G01D02*
X448206D01*
X448699Y1407229D01*
G01X456660Y359172D02*
X458425Y357407D01*
Y341362D01*
G01X465000Y340362D02*
X464000Y341362D01*
X461575D01*
G01X455000Y340362D02*
X454000Y341362D01*
X452075D01*
G01X460800Y375362D02*
Y358962D01*
G01Y379987D02*
Y375362D01*
G01Y383137D02*
X463075D01*
X463500Y383562D01*
G01X539532Y890730D02*
X541967Y888295D01*
X546277D01*
X552317Y882255D01*
X557947D01*
G01X551046Y878964D02*
X550021Y879989D01*
Y882511D01*
X547517Y885015D01*
X540377D01*
X539566Y885826D01*
Y888824D01*
X539136Y889254D01*
G01X600406Y882536D02*
X590597Y892345D01*
Y901870D01*
X575762Y916705D01*
X553257D01*
X551767Y918195D01*
X545117D01*
X543277Y916355D01*
X540307D01*
G01X580302Y908535D02*
X574515Y914322D01*
X552060D01*
X550567Y915815D01*
X544887D01*
X543834Y914762D01*
X542467D01*
G01X549757Y894025D02*
X544267D01*
X541597Y896695D01*
X538057D01*
G01X574007Y911355D02*
X572900Y912462D01*
X551510D01*
X549717Y914255D01*
X545507D01*
X544791Y913539D01*
X542197D01*
G01X539198Y918275D02*
X539588Y918665D01*
X543537D01*
X544647Y919775D01*
X553087D01*
X553777Y919085D01*
X577197D01*
X593967Y902315D01*
Y894795D01*
X595572Y893190D01*
G01X543026Y1043998D02*
X547146D01*
X549325Y1041819D01*
X567343D01*
G01X454762Y1038136D02*
X456345D01*
X457368Y1039159D01*
X467814D01*
X468724Y1038249D01*
X473647D01*
X477018Y1034878D01*
Y1033819D01*
X477756Y1033081D01*
X478811D01*
G03X479736Y1033329I0J1849D01*
G02X481549Y1033351I926J-1602D01*
G01X481587Y1033329D01*
G03X483398Y1033307I925J1602D01*
G01X483436Y1033329D01*
G02X485286I925J-1602D01*
G03X487136I925J1602D01*
G02X488933Y1033360I926J-1602D01*
G01X488986Y1033329D01*
G03X490836I925J1602D01*
G02X492649Y1033351I926J-1602D01*
G01X492687Y1033329D01*
G03X494498Y1033307I925J1602D01*
G01X494536Y1033329D01*
G02X496386I925J-1602D01*
G03X498236I925J1602D01*
G02X500033Y1033360I926J-1602D01*
G01X500086Y1033329D01*
G03X501936I925J1602D01*
G02X503733Y1033360I926J-1602D01*
G01X503786Y1033329D01*
G03X505636I925J1602D01*
G02X507433Y1033360I926J-1602D01*
G01X507486Y1033329D01*
G03X509336I925J1602D01*
G02X511133Y1033360I926J-1602D01*
G01X511186Y1033329D01*
G03X513036I925J1602D01*
G02X514833Y1033360I926J-1602D01*
G01X514886Y1033329D01*
G03X516736I925J1602D01*
G02X518549Y1033351I926J-1602D01*
G01X518587Y1033329D01*
G03X520398Y1033307I925J1602D01*
G01X520436Y1033329D01*
G02X522286I925J-1602D01*
G03X524136I925J1602D01*
G02X525933Y1033360I926J-1602D01*
G01X525986Y1033329D01*
G03X527836I925J1602D01*
G02X529633Y1033360I926J-1602D01*
G01X529686Y1033329D01*
G03X531536I925J1602D01*
G02X533386I925J-1602D01*
G03X535236I925J1602D01*
G02X537086I925J-1602D01*
G02X537469Y1033035I-925J-1602D01*
G01X544039Y1026465D01*
X553332D01*
G01X612317Y1068895D02*
X603357D01*
X598477Y1064015D01*
X552187D01*
X551247Y1063075D01*
X540347D01*
X539457Y1062185D01*
X459467D01*
X457847Y1060565D01*
X456611D01*
G01X599924Y1058989D02*
X545088D01*
G01Y1055913D02*
X576597D01*
X577434Y1055076D01*
X586079D01*
G01X545088Y1057377D02*
X587647D01*
X588414Y1056610D01*
X591675D01*
G01X605050Y1065867D02*
X600462Y1061279D01*
X542128D01*
X541387Y1060538D01*
G01X482511Y1394447D02*
Y1393373D01*
X481200Y1392062D01*
X475450D01*
X472397Y1395115D01*
Y1399713D01*
X464147Y1407963D01*
Y1445479D01*
X468510Y1449842D01*
Y1497663D01*
X476182Y1505335D01*
X690329D01*
X795624Y1400040D01*
Y1347958D01*
X822920Y1320662D01*
X861420D01*
X871020Y1311062D01*
Y971462D01*
X902920Y939562D01*
Y802648D01*
X869151Y768879D01*
Y745413D01*
X863925Y740187D01*
Y737697D01*
G01X453805Y1396730D02*
Y1401282D01*
G01X482400Y1558320D02*
X480220D01*
X472900Y1551000D01*
Y1546000D01*
X458515Y1531615D01*
Y1449727D01*
X460670Y1447572D01*
Y1406042D01*
X463737Y1402975D01*
Y1400565D01*
X465947Y1398355D01*
G01X534449Y1672007D02*
X529484D01*
X472080Y1614603D01*
Y1607122D01*
X468520Y1603562D01*
Y1577142D01*
X469490Y1576172D01*
Y1573652D01*
X468278Y1572440D01*
X464850D01*
X462760Y1574530D01*
X459270D01*
X452520Y1567780D01*
Y1564862D01*
G01X518701Y1672007D02*
X518700Y1672006D01*
Y1665783D01*
X473479Y1620562D01*
X470500D01*
X466520Y1616582D01*
Y1574862D01*
G01X539177Y897835D02*
X542576D01*
X544046Y896365D01*
X552017D01*
X552497Y895885D01*
X561514D01*
X593227Y864172D01*
Y774207D01*
X598503Y768931D01*
G01X540919Y892748D02*
X543862Y889805D01*
X547187D01*
X551827Y885165D01*
X563777D01*
X566762Y882180D01*
G01X541674Y893983D02*
X544102Y891555D01*
X558697D01*
G01X540447Y899995D02*
X542497D01*
X544231Y898261D01*
X562953D01*
X581147Y880067D01*
G01X541044Y901372D02*
X542740D01*
X544123Y899989D01*
X564601D01*
X575374Y889216D01*
G01X577622Y896854D02*
X573538D01*
X566267Y904125D01*
X538171D01*
G01X550703Y908079D02*
X551030Y907752D01*
X570456D01*
X604057Y874151D01*
Y780822D01*
X605555Y779324D01*
G01X543897Y902589D02*
X544371Y902115D01*
X565434D01*
X599417Y868132D01*
Y778395D01*
X608709Y769103D01*
G01X587617Y895115D02*
X585127D01*
X571020Y909222D01*
X551961D01*
G01X583377Y901635D02*
X580757D01*
X571640Y910752D01*
X552580D01*
X552360Y910972D01*
G01X570657Y903335D02*
X568040Y905952D01*
X552860D01*
G01X472829Y921875D02*
X474703Y923749D01*
Y925819D01*
G01X556697Y943475D02*
X554303Y945869D01*
X542179D01*
X541400Y946648D01*
Y947671D01*
X540936Y948792D01*
X539476Y950976D01*
X535768Y954684D01*
Y957629D01*
X534678Y958719D01*
X497610D01*
X496728Y959601D01*
Y961372D01*
X496187Y961913D01*
X479995D01*
X478378Y963530D01*
G01X545778Y948495D02*
Y950670D01*
X541438Y955010D01*
Y962001D01*
X538289Y965150D01*
G01X541378Y951944D02*
X539138Y954184D01*
Y959418D01*
X536570Y961986D01*
G01X522598Y981028D02*
X523969Y982399D01*
X535408D01*
X536628Y981179D01*
X553513D01*
X565937Y968755D01*
G01X523816Y984664D02*
X538082D01*
X540047Y982699D01*
X560873D01*
X579229Y964343D01*
G01X673617Y744735D02*
Y747235D01*
X668277Y752575D01*
X662278D01*
X657777Y757076D01*
Y766795D01*
X656987Y767585D01*
Y788075D01*
X653387Y791675D01*
Y853885D01*
X655967Y856465D01*
Y897805D01*
X653187Y900585D01*
Y934425D01*
X647127Y940485D01*
X634817D01*
X631577Y943725D01*
X609797D01*
X602237Y951285D01*
X578407D01*
X573628Y956064D01*
X552946D01*
X538146Y970864D01*
X535481D01*
X534804Y971541D01*
G03X532954I-925J-1602D01*
G02X531104I-925J1602D01*
G03X529254I-925J-1602D01*
G02X527404I-925J1602D01*
G03X525554I-925J-1602D01*
G02X523741Y971519I-926J1602D01*
G01X523703Y971541D01*
G03X521892Y971563I-925J-1602D01*
G01X521854Y971541D01*
G02X520004I-925J1602D01*
G03X518191Y971563I-926J-1602D01*
G01X518153Y971541D01*
G02X516303I-925J1602D01*
G03X514492Y971563I-925J-1602D01*
G01X514454Y971541D01*
G02X512604I-925J1602D01*
G03X510807Y971572I-926J-1602D01*
G01X510754Y971541D01*
G02X508904I-925J1602D01*
G03X507054I-925J-1602D01*
G02X505204I-925J1602D01*
G03X503407Y971572I-926J-1602D01*
G01X503354Y971541D01*
G02X501504I-925J1602D01*
G03X499691Y971563I-926J-1602D01*
G01X499653Y971541D01*
G02X497803I-925J1602D01*
G03X495992Y971563I-925J-1602D01*
G01X495954Y971541D01*
G02X494104I-925J1602D01*
G03X492307Y971572I-926J-1602D01*
G01X492254Y971541D01*
G02X490404I-925J1602D01*
G03X488607Y971572I-926J-1602D01*
G01X488554Y971541D01*
G02X486704I-925J1602D01*
G03X484907Y971572I-926J-1602D01*
G01X484854Y971541D01*
G02X483004I-925J1602D01*
G01X480229Y973143D01*
G01X541477Y976940D02*
X541453Y976964D01*
X535646D01*
X534446Y978164D01*
X531142D01*
X528346Y975368D01*
G01X536552Y1028898D02*
X538209Y1027241D01*
G01X482511Y1015705D02*
G02X485068Y1014406I-528J-4205D01*
G03X487135Y1014103I1225J1154D01*
G02X488932Y1014134I926J-1602D01*
G01X488985Y1014103D01*
G03X490835I925J1602D01*
G02X492632Y1014134I926J-1602D01*
G01X492685Y1014103D01*
G03X494535I925J1602D01*
G02X496332Y1014134I926J-1602D01*
G01X496385Y1014103D01*
G03X498235I925J1602D01*
G02X500032Y1014134I926J-1602D01*
G01X500085Y1014103D01*
G03X501935I925J1602D01*
G02X503732Y1014134I926J-1602D01*
G01X503785Y1014103D01*
G03X505635I925J1602D01*
G02X507432Y1014134I926J-1602D01*
G01X507485Y1014103D01*
G03X509335I925J1602D01*
G02X511132Y1014134I926J-1602D01*
G01X511185Y1014103D01*
G03X513035I925J1602D01*
G02X514832Y1014134I926J-1602D01*
G01X514885Y1014103D01*
G03X516735I925J1602D01*
G02X518532Y1014134I926J-1602D01*
G01X518585Y1014103D01*
G03X520435I925J1602D01*
G02X522232Y1014134I926J-1602D01*
G01X522285Y1014103D01*
G03X524135I925J1602D01*
G02X525932Y1014134I926J-1602D01*
G01X525985Y1014103D01*
G03X527835I925J1602D01*
G02X529632Y1014134I926J-1602D01*
G01X529685Y1014103D01*
G03X531535I925J1602D01*
G02X533332Y1014134I926J-1602D01*
G01X533385Y1014103D01*
G03X534912Y1013955I926J1602D01*
G02X535513Y1014056I603J-1749D01*
G01X546046D01*
X549177Y1010925D01*
G01X562700Y1022464D02*
X544046D01*
X542841Y1023669D01*
X533664D01*
G03X533063Y1023568I2J-1850D01*
G02X531536Y1023716I-601J1750D01*
G01X531483Y1023747D01*
G03X529686Y1023716I-871J-1633D01*
G02X527836I-925J1602D01*
G01X527783Y1023747D01*
G03X525986Y1023716I-871J-1633D01*
G02X524136I-925J1602D01*
G01X524083Y1023747D01*
G03X522286Y1023716I-871J-1633D01*
G02X520436I-925J1602D01*
G01X520383Y1023747D01*
G03X518586Y1023716I-871J-1633D01*
G02X516736I-925J1602D01*
G01X516683Y1023747D01*
G03X514886Y1023716I-871J-1633D01*
G02X513036I-925J1602D01*
G01X512983Y1023747D01*
G03X511186Y1023716I-871J-1633D01*
G02X509336I-925J1602D01*
G01X509283Y1023747D01*
G03X507486Y1023716I-871J-1633D01*
G02X505636I-925J1602D01*
G01X505583Y1023747D01*
G03X503786Y1023716I-871J-1633D01*
G02X501936I-925J1602D01*
G01X501883Y1023747D01*
G03X500086Y1023716I-871J-1633D01*
G02X498236I-925J1602D01*
G01X498183Y1023747D01*
G03X496386Y1023716I-871J-1633D01*
G02X494536I-925J1602D01*
G01X494483Y1023747D01*
G03X492686Y1023716I-871J-1633D01*
G02X490836I-925J1602D01*
G01X490783Y1023747D01*
G03X488986Y1023716I-871J-1633D01*
G02X487136I-925J1602D01*
G01X487083Y1023747D01*
G03X485286Y1023716I-871J-1633D01*
G02X483219Y1024019I-842J1457D01*
G03X480662Y1025318I-3085J-2906D01*
G01X543101Y1042365D02*
X544877D01*
X545371Y1041871D01*
G01X542070Y1039527D02*
X543278Y1038319D01*
X551718D01*
X552572Y1037465D01*
X556151D01*
G01X538118Y1040629D02*
X542917D01*
X543933Y1039613D01*
X575272D01*
X575785Y1039100D01*
X580027D01*
G01X545454Y1046259D02*
X590544D01*
X594081Y1042722D01*
G01X545454Y1047479D02*
X601925D01*
X603592Y1045812D01*
G01X482511Y1394447D02*
X481032Y1395926D01*
Y1398402D01*
G01X480998Y1402364D02*
Y1398436D01*
X481032Y1398402D01*
G01X483560Y1401712D02*
X482908Y1402364D01*
X480998D01*
G01X806323Y1343076D02*
Y1395394D01*
X685376Y1516341D01*
X500543D01*
X475110Y1541774D01*
Y1548112D01*
G01X790380Y1432132D02*
X781388D01*
X687918Y1525602D01*
X502340D01*
X483348Y1544594D01*
Y1548062D01*
G01X809210Y1343062D02*
Y1396043D01*
X686412Y1518841D01*
X501579D01*
X477968Y1542452D01*
Y1548122D01*
G01X812130Y1343022D02*
Y1396659D01*
X687448Y1521341D01*
X502615D01*
X480848Y1543108D01*
Y1548120D01*
G01X494112Y88040D02*
Y85733D01*
X495648Y84197D01*
X499510D01*
G01X501932Y98629D02*
Y93659D01*
X499590Y91317D01*
G01D02*
X495082D01*
X494112Y90347D01*
Y88040D01*
G01X498330Y96112D02*
X498990D01*
X500554Y97676D01*
Y98629D01*
G01X498730Y122547D02*
X497800Y121617D01*
Y113562D01*
G01D02*
Y112162D01*
X500554Y109408D01*
Y108275D01*
G01X501932D02*
Y110230D01*
X500500Y111662D01*
Y117962D01*
G01D02*
Y119787D01*
X503270Y122557D01*
G01X498630Y146307D02*
X497625D01*
X495910Y144592D01*
Y125367D01*
X498730Y122547D01*
G01X503290Y146297D02*
X502365D01*
X500930Y144862D01*
Y136177D01*
X501000Y136107D01*
Y124827D01*
X503270Y122557D01*
G01X1469777Y418396D02*
X1464903Y413522D01*
X1448980D01*
X1422320Y386862D01*
X1123226D01*
X1082306Y345942D01*
X1017683D01*
X1005264Y351086D01*
X979227Y356265D01*
X945934D01*
X939953Y358742D01*
X888070D01*
X855075Y325747D01*
X693225D01*
X673633Y317632D01*
X643480D01*
X642245Y316397D01*
Y313186D01*
X633351Y304292D01*
X622514D01*
X620474Y306332D01*
X578830D01*
X573190Y311972D01*
X525110D01*
X509500Y296362D01*
X505770D01*
X503000Y299132D01*
X497870D01*
X492525Y293787D01*
X489091D01*
G01X488570Y1413246D02*
X488920Y1412896D01*
Y1408742D01*
G01D02*
X486187Y1411475D01*
Y1411980D01*
X484921Y1413246D01*
G01X486210Y1547960D02*
X485847Y1547597D01*
Y1545525D01*
X502050Y1529322D01*
X687068D01*
X781368Y1435022D01*
X796078D01*
X800000Y1431100D01*
G01X507310Y74567D02*
X507315Y74562D01*
X510500D01*
X512300Y76362D01*
Y82162D01*
X510225Y84237D01*
X507310D01*
G01D02*
X507335Y84262D01*
Y88862D01*
G01X503150Y74547D02*
X505240Y76637D01*
Y83362D01*
X504335Y84267D01*
X503100D01*
G01X504700Y93862D02*
Y86461D01*
X503100Y84861D01*
Y84267D01*
G01X510600Y92782D02*
X506066Y97316D01*
Y98629D01*
G01X507335Y88862D02*
Y94326D01*
X504688Y96973D01*
Y98629D01*
G01X503310D02*
Y96553D01*
X504700Y95163D01*
Y93862D01*
G01X513700Y117862D02*
X510600Y114762D01*
X508000D01*
X504688Y111450D01*
Y108275D01*
G01X503310D02*
Y113262D01*
G01D02*
X507335Y117287D01*
Y122592D01*
X507320Y122607D01*
G01X510900Y111962D02*
X507710D01*
X506066Y110318D01*
Y108275D01*
G01X509035Y106387D02*
X508856Y106208D01*
X508133D01*
G01X509035Y107407D02*
X508856Y107586D01*
X508133D01*
G01X507360Y146267D02*
X506205D01*
X505300Y145362D01*
Y135837D01*
X510260Y130877D01*
Y125547D01*
X507320Y122607D01*
G01X1465836Y408668D02*
Y410354D01*
X1469293Y413811D01*
X1472621D01*
X1475988Y417178D01*
Y420299D01*
X1474225Y422062D01*
X1442180D01*
X1408460Y388342D01*
X1122612D01*
X1081692Y347422D01*
X1019736D01*
X1007918Y352317D01*
X979250Y358019D01*
X945521D01*
X940202Y360222D01*
X887456D01*
X854461Y327227D01*
X692611D01*
X673273Y319217D01*
X642971D01*
X632426Y308672D01*
X630830D01*
X628320Y306162D01*
X622827D01*
X621177Y307812D01*
X579444D01*
X573874Y313382D01*
X523071D01*
X508502Y298813D01*
G01X508136Y309398D02*
X513830Y315092D01*
X574243D01*
X580053Y309282D01*
X611120D01*
X616040Y314202D01*
X626471D01*
X628268Y312405D01*
X634080D01*
X642302Y320627D01*
X672519D01*
X692002Y328697D01*
X853852D01*
X886847Y361692D01*
X940930D01*
X945981Y359600D01*
X980953D01*
X1007335Y354352D01*
X1020514Y348892D01*
X1081083D01*
X1122003Y389812D01*
X1400910D01*
X1442810Y431712D01*
X1492660D01*
X1501040Y423332D01*
Y397062D01*
X1483960Y379982D01*
Y364164D01*
X1481484Y361688D01*
G01X529720Y35287D02*
Y30792D01*
G01Y38437D02*
Y43054D01*
G01X524920Y539819D02*
X524977Y539762D01*
X533920D01*
X538320Y535362D01*
Y493442D01*
X561920Y469842D01*
Y436288D01*
X583685Y414523D01*
Y378246D01*
X583175Y377736D01*
X582067D01*
X581557Y377226D01*
Y375736D01*
X582067Y375226D01*
X583175D01*
X583685Y374716D01*
Y373226D01*
X583175Y372716D01*
X582067D01*
X581557Y372206D01*
Y370716D01*
X582067Y370206D01*
X583175D01*
X583685Y369696D01*
Y363271D01*
G01X586185D02*
Y414561D01*
X563854Y436892D01*
Y470464D01*
X540820Y493498D01*
Y537162D01*
X532620Y545362D01*
X524863D01*
X524820Y545319D01*
G01X539720Y38437D02*
Y42862D01*
G01Y35287D02*
Y30792D01*
G01X534720Y35287D02*
Y30792D01*
G01Y38437D02*
Y42922D01*
G01X548609Y38437D02*
Y48082D01*
G01X550700Y112714D02*
X545052D01*
X544700Y112362D01*
G01D02*
X539630D01*
X539400Y112592D01*
G01X546100Y106162D02*
X549503Y109565D01*
X550700D01*
G01X536420Y309422D02*
X547484D01*
X551234Y305672D01*
X575630D01*
X577480Y303822D01*
G01X549177Y1010925D02*
X574663D01*
X617503Y968085D01*
X631257D01*
X634597Y964745D01*
X647966D01*
X653154Y969933D01*
Y973428D01*
G01X563482Y40826D02*
X565871Y38437D01*
X568500D01*
G01X550971Y42902D02*
X554720Y39153D01*
Y38437D01*
G01Y35287D02*
Y32862D01*
G01X565184Y47982D02*
Y50523D01*
X563100Y52607D01*
G01X579930Y72052D02*
X574717D01*
X563100Y60435D01*
Y55757D01*
G01X557000Y109565D02*
X557897D01*
X562500Y104962D01*
G01D02*
Y106462D01*
X565660Y109622D01*
X567330D01*
G01X557000Y111140D02*
X561122D01*
X562300Y109962D01*
G01D02*
X566470Y114132D01*
X567390D01*
G01X562200Y114962D02*
X559952Y112714D01*
X557000D01*
G01X558900Y118962D02*
Y114862D01*
X558327Y114289D01*
X557000D01*
G01X561324Y301149D02*
X557857Y297682D01*
Y223093D01*
X552489Y217725D01*
Y212022D01*
G01X560640Y540613D02*
X611636D01*
X621613Y550590D01*
X671062D01*
X687018Y534634D01*
Y529278D01*
X692777Y523519D01*
Y505977D01*
X690330Y503530D01*
G01X563281Y543113D02*
X612566D01*
X621153Y551700D01*
X671522D01*
X692274Y530948D01*
Y527935D01*
X695220Y524989D01*
Y519662D01*
G01X557947Y882255D02*
X561902D01*
X584167Y859990D01*
Y766142D01*
X588581Y761728D01*
Y747887D01*
G01X558697Y891555D02*
X561700D01*
X590487Y862768D01*
Y771004D01*
X599763Y761728D01*
Y751021D01*
G01X611783Y939877D02*
X603215D01*
X599617Y943475D01*
X556697D01*
G01X565937Y968755D02*
X579977Y954715D01*
X604117D01*
X609487Y949345D01*
X632127D01*
X635417Y946055D01*
X646357D01*
X649367Y943045D01*
X651387D01*
X656477Y937955D01*
Y902305D01*
X662267Y896515D01*
Y856625D01*
X656937Y851295D01*
Y792685D01*
X661847Y787775D01*
Y780862D01*
X664342Y778367D01*
Y777682D01*
G01X553332Y1026465D02*
X570907D01*
X617687Y979685D01*
X630337D01*
X632837Y977185D01*
X647067D01*
X650227Y980345D01*
X651662D01*
X656638Y985321D01*
G01X683457Y745175D02*
Y764164D01*
X682227Y765394D01*
Y771065D01*
X681377Y771915D01*
X679597D01*
X678507Y773005D01*
Y976305D01*
X676977Y977835D01*
X665684D01*
X663254Y980265D01*
X656297D01*
X648317Y972285D01*
X634307D01*
X633877Y972715D01*
X617966D01*
X568217Y1022464D01*
X562700D01*
G01X700500Y745862D02*
Y745972D01*
X694127Y752345D01*
X691026D01*
X686687Y756684D01*
Y767485D01*
X685477Y768695D01*
Y774185D01*
X682577Y777085D01*
Y982045D01*
X682067Y982555D01*
X677307D01*
X675447Y984415D01*
X673327D01*
X663477Y994265D01*
X658177D01*
X654907Y997535D01*
Y1012495D01*
X652887Y1014515D01*
Y1025305D01*
X645937Y1032255D01*
X636077D01*
X632187Y1028365D01*
X565027D01*
X563657Y1029735D01*
X561157D01*
G01X556151Y1037465D02*
X575321D01*
X578111Y1034675D01*
X632128D01*
X635558Y1038105D01*
X647497D01*
X650287Y1035315D01*
X652617D01*
X656407Y1031525D01*
Y1016085D01*
X666921Y1005571D01*
X681174Y996038D01*
X682388Y993764D01*
Y991213D01*
X686846Y986755D01*
Y781608D01*
X688477Y779977D01*
G01X572500Y38437D02*
X568500D01*
G01X581500Y41862D02*
X578075Y38437D01*
X574331D01*
X574240Y38346D01*
X572591D01*
X572500Y38437D01*
G01Y35287D02*
Y32862D01*
G01X584950Y54842D02*
X582795Y52687D01*
X581520D01*
G01X573190Y42912D02*
Y50997D01*
X571580Y52607D01*
G01X575330Y47672D02*
X576200Y48542D01*
Y52647D01*
G01X577300Y66682D02*
X575140D01*
X571580Y63122D01*
Y55757D01*
G01X581520Y55837D02*
Y57742D01*
X578900Y60362D01*
G01D02*
X576200Y57662D01*
Y55797D01*
G01X578920Y466462D02*
Y463262D01*
X591520Y450662D01*
Y440581D01*
X598001Y434100D01*
X600400D01*
X604175Y430325D01*
Y427617D01*
X599320Y422762D01*
Y402362D01*
X614430Y387252D01*
X672110D01*
X673220Y388362D01*
G01X566140Y554972D02*
X567147Y555979D01*
X701619D01*
X720700Y536898D01*
Y497442D01*
X718970Y495712D01*
Y483112D01*
X714000Y478142D01*
Y466832D01*
X715574Y465258D01*
G01X566140Y551472D02*
X569057Y554389D01*
X695133D01*
X719460Y530062D01*
Y499312D01*
X717360Y497212D01*
Y483872D01*
X710860Y477372D01*
Y464442D01*
X711630Y463672D01*
X713080D01*
X714644Y462108D01*
X715574D01*
G01X566762Y882180D02*
X587487Y861455D01*
Y769924D01*
X595597Y761814D01*
Y751005D01*
G01X575374Y889216D02*
X597357Y867233D01*
Y777358D01*
X612250Y762465D01*
Y752890D01*
X614750Y750390D01*
G01X581147Y880067D02*
X595537Y865677D01*
Y776678D01*
X610750Y761465D01*
Y748055D01*
X611760Y747045D01*
G01X593147Y740955D02*
Y737635D01*
X594480Y736302D01*
X618700D01*
X620830Y738432D01*
Y741782D01*
X618910Y743702D01*
Y752152D01*
X623300Y756542D01*
Y763422D01*
X614270Y772452D01*
X608370D01*
X601860Y778962D01*
Y872616D01*
X577622Y896854D01*
G01X570067Y921425D02*
X578757D01*
X596697Y903485D01*
Y900222D01*
X605555Y891364D01*
G01X579229Y964343D02*
X584487Y959085D01*
X604207D01*
X611617Y951675D01*
X632886D01*
X636276Y948285D01*
X646987D01*
X650117Y945155D01*
X652471D01*
X670037Y927589D01*
Y793162D01*
X671942Y791257D01*
Y773282D01*
G01X567343Y1041819D02*
X585046D01*
X587573Y1039292D01*
Y1039291D01*
X589227Y1037637D01*
X589228Y1037638D01*
X613423D01*
X615750Y1039965D01*
X631706D01*
X635656Y1043915D01*
X648236D01*
X650222Y1041929D01*
X658374D01*
X661477Y1038826D01*
Y1015101D01*
X669801Y1006777D01*
X690463Y992970D01*
X693310Y990123D01*
Y788113D01*
X693997Y787426D01*
Y760923D01*
X693310Y760236D01*
G01X580027Y1039100D02*
X585976D01*
X589291Y1035785D01*
X630486D01*
X634016Y1039315D01*
X647358D01*
X647888Y1039845D01*
X652057D01*
X657517Y1034385D01*
Y1016805D01*
X667397Y1006925D01*
X682300Y996976D01*
X684578Y992716D01*
Y991834D01*
X687587Y988825D01*
X688777D01*
X691867Y985735D01*
Y793467D01*
X688967Y790567D01*
G01X590100Y56787D02*
Y44362D01*
X594800Y39662D01*
X607630D01*
G01X597955Y48047D02*
X598405Y48497D01*
Y52607D01*
G01X593369Y45682D02*
X595870Y48183D01*
Y50834D01*
X594097Y52607D01*
G01X597220Y88287D02*
X597120D01*
X595685Y86852D01*
Y65197D01*
X598405Y62477D01*
Y55757D01*
G01X592220Y88287D02*
X593070Y87437D01*
Y62513D01*
X594097Y61486D01*
Y55757D01*
G01X590100Y59937D02*
X587265D01*
X586600Y60602D01*
G01X600220Y96862D02*
Y88862D01*
X599645Y88287D01*
X597220D01*
G01X594720Y97220D02*
Y89362D01*
X593645Y88287D01*
X592220D01*
G01X600800Y430900D02*
X602320Y429380D01*
Y428040D01*
X597710Y423430D01*
Y399954D01*
X612022Y385642D01*
X644540D01*
X651520Y378662D01*
G01X601220Y486922D02*
Y485762D01*
X599058Y483600D01*
X593500D01*
X589000Y479100D01*
Y456700D01*
X593220Y452480D01*
Y444686D01*
X597375Y440531D01*
Y439625D01*
X607638Y429362D01*
X623420D01*
X626420Y426362D01*
X629220D01*
G01X687227Y433761D02*
X685666Y435322D01*
X667060D01*
X665850Y436532D01*
X635430D01*
X632165Y433267D01*
X625001D01*
X622806Y431072D01*
X608347D01*
X602900Y436519D01*
Y448300D01*
X600000Y451200D01*
Y455900D01*
X604800Y460700D01*
Y462900D01*
X602200Y465500D01*
Y472138D01*
X612255Y482193D01*
Y505793D01*
X617030Y510568D01*
Y522262D01*
X604480Y534812D01*
X596880D01*
G01X592340Y744624D02*
Y747626D01*
X592076Y747890D01*
G01Y751040D02*
X592111Y751005D01*
X595597D01*
G01X589287Y740985D02*
X593117D01*
X593147Y740955D01*
G01X598503Y768931D02*
X606829Y760605D01*
X608225D01*
G01X595572Y893190D02*
X602090Y886672D01*
X607340D01*
G01X594081Y1042722D02*
X595508Y1041295D01*
X630048D01*
X634578Y1045825D01*
X647466D01*
X648106Y1046465D01*
X660018D01*
X662587Y1043896D01*
Y1015561D01*
X670070Y1008078D01*
X689274Y995244D01*
X692578D01*
X695227Y992595D01*
X697586D01*
X698600Y991581D01*
Y985139D01*
X701697Y982042D01*
Y767397D01*
X697336Y763036D01*
Y760236D01*
G01X703545Y745907D02*
X695325Y754127D01*
X691705D01*
X688447Y757385D01*
Y768185D01*
X687237Y769395D01*
Y774855D01*
X684557Y777535D01*
Y986395D01*
X681707Y989245D01*
X677357D01*
X676677Y989925D01*
X670417D01*
X663697Y996645D01*
X659277D01*
X656627Y999295D01*
Y1013445D01*
X654697Y1015375D01*
Y1030396D01*
X651978Y1033115D01*
X649917D01*
X646707Y1036325D01*
X636227D01*
X632852Y1032950D01*
X616237D01*
X614472Y1031185D01*
X592307D01*
G01X586079Y1055076D02*
X587390Y1053765D01*
X621710D01*
X628910Y1060965D01*
X632377D01*
X634257Y1059085D01*
X647787D01*
X649607Y1060905D01*
X660387D01*
X663967Y1057325D01*
X666847D01*
X671157Y1053015D01*
Y1017109D01*
X673103Y1013969D01*
X681985Y1009577D01*
X699736D01*
X705795Y1003518D01*
Y998656D01*
X713798Y990653D01*
Y764946D01*
X710688Y761836D01*
Y760236D01*
G01X591675Y1056610D02*
X592720Y1055565D01*
X621410D01*
X628410Y1062565D01*
X631066D01*
X633432Y1064931D01*
X647681D01*
X649797Y1062815D01*
X661127D01*
X664997Y1058945D01*
X667056D01*
X672356Y1053645D01*
Y1017338D01*
X673783Y1014979D01*
X681653Y1010980D01*
X701393D01*
X707437Y1004936D01*
Y999133D01*
X715282Y991288D01*
Y760830D01*
X714688Y760236D01*
G01X585630Y1672007D02*
Y1670650D01*
X594520Y1661760D01*
X639990D01*
X657150Y1678920D01*
X673080D01*
X680080Y1671920D01*
Y1623202D01*
X683960Y1619322D01*
Y1561090D01*
X681760Y1558890D01*
Y1551064D01*
X682234Y1550590D01*
X684220D01*
X685547Y1549263D01*
Y1547277D01*
X747514Y1485310D01*
X1036640D01*
X1062070Y1510740D01*
Y1524040D01*
X1064450Y1526420D01*
X1095540D01*
X1112563Y1543443D01*
Y1555600D01*
X1117200Y1560237D01*
Y1608563D01*
X1113263Y1612500D01*
Y1615913D01*
X1115800Y1618450D01*
X1130520D01*
X1135060Y1622990D01*
Y1628020D01*
X1153000Y1645960D01*
Y1658950D01*
X1157570Y1663520D01*
X1184720D01*
X1189660Y1658580D01*
Y1644145D01*
X1190895Y1642910D01*
G01X611810Y34400D02*
Y34762D01*
X615750Y38702D01*
X616645D01*
G01X607630Y39662D02*
X609252D01*
X612822Y43232D01*
G01X614400Y46012D02*
X610970Y49442D01*
Y52617D01*
G01X603063Y48023D02*
X606330Y51290D01*
Y52607D01*
G01X599800Y43152D02*
X600873Y44225D01*
Y51130D01*
X602350Y52607D01*
G01X615170Y73812D02*
X617589Y71393D01*
Y66278D01*
X617079Y65768D01*
X615254D01*
X614744Y65258D01*
Y63768D01*
X615254Y63258D01*
X617079D01*
X617589Y62748D01*
Y59382D01*
X616799Y58592D01*
X611950D01*
X610970Y57612D01*
Y55767D01*
G01X601220Y73862D02*
X602520D01*
X606330Y70052D01*
Y62346D01*
X606840Y61836D01*
X607637D01*
X608147Y61326D01*
Y59836D01*
X607637Y59326D01*
X606840D01*
X606330Y58816D01*
Y55757D01*
G01X601220Y76862D02*
X598920Y74562D01*
Y67422D01*
X602350Y63992D01*
Y55757D01*
G01X609690Y402812D02*
X611057Y404179D01*
X614882D01*
G01X605220Y416362D02*
X608250Y419392D01*
X630730D01*
X631645Y420307D01*
Y421362D01*
G01X610720Y442862D02*
Y441462D01*
X611420Y440762D01*
X615920D01*
X616645Y441487D01*
Y442862D01*
G01X607328Y537481D02*
Y535010D01*
X619089Y523249D01*
Y509451D01*
X614689Y505051D01*
Y482208D01*
X606489Y474008D01*
Y470149D01*
X608089Y468549D01*
Y466151D01*
X606700Y464762D01*
Y435138D01*
X609056Y432782D01*
X621682D01*
X624000Y435100D01*
X631400D01*
X638000Y441700D01*
X667613D01*
X667677Y441636D01*
G01X610797Y537528D02*
Y534103D01*
X620900Y524000D01*
Y508700D01*
X616500Y504300D01*
Y476932D01*
X615368Y475800D01*
X610710D01*
X608665Y473755D01*
Y470535D01*
X609900Y469300D01*
Y465400D01*
X608511Y464011D01*
Y435889D01*
X609908Y434492D01*
X620973D01*
X623291Y436810D01*
X629066Y439200D01*
X630637D01*
X635037Y443600D01*
X659225D01*
X660325Y444700D01*
X669990D01*
X671479Y443211D01*
G01X610720Y462862D02*
Y461462D01*
X611420Y460762D01*
X615920D01*
X616645Y461487D01*
Y462862D01*
G01X610720Y457862D02*
Y456462D01*
X611420Y455762D01*
X615920D01*
X616645Y456487D01*
Y457862D01*
G01X610720Y452862D02*
Y451462D01*
X611420Y450762D01*
X615920D01*
X616645Y451487D01*
Y452862D01*
G01X617252Y739354D02*
X616394Y740212D01*
Y748746D01*
X614750Y750390D01*
G01X602768Y758385D02*
X608113Y753040D01*
X608250D01*
G01X608225Y757455D02*
Y753065D01*
X608250Y753040D01*
G01X603276Y747890D02*
Y741375D01*
G01Y751040D02*
X603257Y751021D01*
X599763D01*
G01X608709Y769103D02*
X613422Y764390D01*
X614750D01*
G01X617940Y763552D02*
X616767Y762379D01*
Y759407D01*
X614750Y757390D01*
G01X607340Y883522D02*
X609670Y881192D01*
Y866032D01*
X610380Y865322D01*
Y789863D01*
X623237Y777006D01*
Y774745D01*
X625027Y772955D01*
Y768355D01*
X628070Y765312D01*
Y760251D01*
G01X626017Y745083D02*
X625876Y744942D01*
X622830D01*
X621220Y746552D01*
Y749792D01*
X625750Y754322D01*
Y764322D01*
X622687Y767385D01*
Y771985D01*
X617547Y777125D01*
X615367D01*
X607340Y785152D01*
Y875602D01*
X600406Y882536D01*
G01X605555Y779324D02*
X610063Y774816D01*
Y774712D01*
G01X608705Y891364D02*
X611987Y888082D01*
Y872267D01*
X614800Y869454D01*
Y793314D01*
X625640Y782474D01*
Y775682D01*
X628497Y772825D01*
X630247D01*
X633320Y769752D01*
Y761884D01*
X630417Y758981D01*
Y757135D01*
G01X633147Y758595D02*
X635276Y760724D01*
Y771096D01*
X631407Y774965D01*
X628897D01*
X627597Y776265D01*
Y783285D01*
X616757Y794125D01*
Y870265D01*
X613790Y873232D01*
Y890299D01*
X608705Y895384D01*
G01X600850Y902101D02*
X602841Y900110D01*
Y898098D01*
X605555Y895384D01*
G01X603592Y1045812D02*
X606759Y1042645D01*
X623727D01*
X631327Y1050245D01*
X647807D01*
X650007Y1048045D01*
X660305D01*
X663787Y1044563D01*
Y1015932D01*
X670774Y1008945D01*
X689177Y996645D01*
X698577D01*
X703287Y991935D01*
Y762161D01*
X701362Y760236D01*
G01X718688D02*
Y763910D01*
X716837Y765761D01*
Y991726D01*
X712309Y996254D01*
Y1004868D01*
X704812Y1012365D01*
X681380D01*
X674412Y1016085D01*
X673686Y1017296D01*
Y1057125D01*
X663636Y1067175D01*
X650977D01*
X648005Y1070147D01*
X633827D01*
X630145Y1066465D01*
X619158D01*
X611682Y1058989D01*
X599924D01*
G01X609954Y1047613D02*
X610202Y1047365D01*
X622697D01*
X628977Y1053645D01*
X633867D01*
X635317Y1052195D01*
X646196D01*
X647016Y1053015D01*
X661226D01*
X664947Y1049294D01*
Y1016343D01*
X670542Y1010748D01*
X682187Y1004975D01*
X696588D01*
X701257Y1000306D01*
Y996905D01*
X705712Y992450D01*
Y989840D01*
X706947Y988605D01*
Y986975D01*
X707460Y986462D01*
Y764476D01*
X705388Y762404D01*
Y760236D01*
G01X720697Y765862D02*
Y992175D01*
X714957Y997915D01*
Y1007775D01*
X706737Y1015995D01*
X679487D01*
X678127Y1017355D01*
Y1061295D01*
X675877Y1063545D01*
X673817D01*
X663517Y1073845D01*
X649647D01*
X648267Y1072465D01*
X634357D01*
X632147Y1074675D01*
X620167D01*
X614387Y1068895D01*
X612317D01*
G01X1212305Y1688700D02*
X1205201D01*
X1202141Y1685640D01*
X1171960D01*
X1151301Y1664981D01*
Y1646666D01*
X1133988Y1629353D01*
X1131924D01*
X1122721Y1620150D01*
X1115030D01*
X1111723Y1616843D01*
Y1611400D01*
X1115800Y1607323D01*
Y1560701D01*
X1111023Y1555924D01*
Y1544081D01*
X1094902Y1527960D01*
X1063812D01*
X1059870Y1524018D01*
Y1511430D01*
X1035290Y1486850D01*
X748238D01*
X687490Y1547598D01*
Y1550210D01*
X685920Y1551780D01*
Y1583430D01*
X693100Y1590610D01*
Y1627430D01*
X691560Y1628970D01*
X685950D01*
X681700Y1633220D01*
Y1674010D01*
X674930Y1680780D01*
X655600D01*
X642150Y1667330D01*
X605500D01*
X601378Y1671452D01*
Y1672007D01*
G01X619795Y38702D02*
X619825Y38672D01*
Y34652D01*
G01X631060Y51867D02*
Y53523D01*
X631130Y53593D01*
Y55690D01*
G01X624633Y49193D02*
X626490Y51050D01*
Y51572D01*
G01D02*
X627012D01*
X631130Y55690D01*
G01X624860Y56712D02*
Y56102D01*
X622270Y53512D01*
Y48832D01*
X619305Y45867D01*
X619090D01*
G01X629820Y42562D02*
X626390D01*
X625000Y43952D01*
G01D02*
X619795Y38747D01*
Y38702D01*
G01X635800Y45762D02*
X630520D01*
X629820Y45062D01*
G01X615530Y52792D02*
X619912D01*
X620097Y52607D01*
G01X619562Y49193D02*
X619129D01*
X615530Y52792D01*
G01X624140Y46672D02*
X627940D01*
X630076Y48808D01*
X630969D01*
X631060Y48717D01*
G01X622271Y44782D02*
X620206Y42717D01*
X619090D01*
G01X622271Y57952D02*
Y59828D01*
X623715Y61272D01*
G01D02*
X624860Y60127D01*
Y56712D01*
G01X615220Y76862D02*
X620097Y71985D01*
Y55757D01*
G01X618032Y404179D02*
Y400149D01*
G01X622490Y402162D02*
X620473Y404179D01*
X618032D01*
G01X625620Y442862D02*
X623620Y440862D01*
X620520D01*
X619795Y441587D01*
Y442862D01*
G01X617220Y436362D02*
X620358Y439500D01*
X625144D01*
X626303Y439980D01*
X627355Y440415D01*
X627356D01*
X628787Y441007D01*
X629989D01*
X630842Y441860D01*
X630903Y441885D01*
X631645Y442627D01*
Y457862D01*
G01X625620Y447862D02*
Y446562D01*
X624920Y445862D01*
X620520D01*
X619795Y446587D01*
Y447862D01*
G01X626400Y462812D02*
X624450Y460862D01*
X620520D01*
X619795Y461587D01*
Y462862D01*
G01X625620Y457862D02*
Y456562D01*
X624920Y455862D01*
X620520D01*
X619795Y456587D01*
Y457862D01*
G01X625620Y452862D02*
Y451562D01*
X624920Y450862D01*
X620520D01*
X619795Y451587D01*
Y452862D01*
G01X626390Y467882D02*
X628870Y470362D01*
X631021D01*
X631645Y469738D01*
Y467862D01*
G01X626310Y472902D02*
X628280Y474872D01*
X630811D01*
X631645Y474038D01*
Y472862D01*
G01X619795Y467862D02*
X622520D01*
G01X631645Y487862D02*
X629772D01*
X629220Y487310D01*
G01X626210Y478002D02*
X628050Y479842D01*
X630641D01*
X631645Y478838D01*
Y477862D01*
G01X695257Y503847D02*
X690380Y498970D01*
X675530D01*
X672580Y501920D01*
Y511970D01*
X668740Y515810D01*
Y520300D01*
X667140Y521900D01*
Y529930D01*
X664430Y532640D01*
X632650D01*
X626720Y526710D01*
Y482880D01*
G01X714320Y597462D02*
X711820D01*
X706120Y603162D01*
X634020D01*
X625820Y611362D01*
Y642562D01*
X626720Y643462D01*
G01X628070Y760251D02*
Y752808D01*
X623497Y748235D01*
G01X614750Y760540D02*
Y764390D01*
G01X629658Y766478D02*
X630654D01*
X631231Y765901D01*
Y764219D01*
G01X614933Y939877D02*
X616195Y938615D01*
X628219D01*
X646720Y930952D01*
X648527Y929145D01*
Y872745D01*
X651957Y869315D01*
Y863955D01*
X648527Y860525D01*
Y855925D01*
X649587Y854865D01*
Y852835D01*
X648527Y851775D01*
Y818985D01*
X649287Y818225D01*
Y816025D01*
X648527Y815265D01*
Y812285D01*
X649797Y811015D01*
Y809595D01*
X648527Y808325D01*
Y791465D01*
X653490Y786502D01*
Y766302D01*
X654327Y765465D01*
Y755896D01*
X660948Y749275D01*
X666627D01*
X669276Y746626D01*
X669700D01*
G01X654196Y1244852D02*
X653947Y1245101D01*
X649951D01*
X647298Y1242448D01*
X635400D01*
X632166Y1245682D01*
X625907D01*
X623217Y1248372D01*
Y1253293D01*
G01X626367D02*
X626260Y1253186D01*
Y1248762D01*
G01X629699Y1255381D02*
X629262Y1254944D01*
Y1251254D01*
X626770Y1248762D01*
X626260D01*
G01X649047Y36685D02*
X649043Y36681D01*
X645083D01*
G01X643880Y42142D02*
X645083Y40939D01*
Y36681D01*
G01Y33531D02*
X643681D01*
X639525Y37687D01*
Y44337D01*
X638100Y45762D01*
X635800D01*
G01X639000Y54437D02*
X638500Y54937D01*
Y57362D01*
G01X635000Y54437D02*
Y57362D01*
G01X647447Y46322D02*
X645536D01*
X644858Y47000D01*
Y47722D01*
X646253Y49117D01*
Y49839D01*
X644563Y51529D01*
X643841D01*
X642446Y50134D01*
X641724D01*
X640571Y51287D01*
X639000D01*
G01X641200Y46762D02*
X639525D01*
X635000Y51287D01*
G01X631130Y55690D02*
Y55707D01*
G01X638500Y57362D02*
Y59787D01*
X639000Y60287D01*
G01X635000Y57362D02*
Y60287D01*
G01X646645Y416362D02*
X645270D01*
X641350Y412442D01*
Y399712D01*
X646625Y394437D01*
X694865D01*
X696760Y392542D01*
X761300D01*
X763990Y395232D01*
X774840D01*
X785600Y405992D01*
X788870D01*
X795490Y412612D01*
Y421012D01*
X793660Y422842D01*
G01X791040Y422892D02*
X791805Y422127D01*
Y420735D01*
X793670Y418870D01*
Y415172D01*
X789130Y410632D01*
X785710D01*
X775510Y400432D01*
X764415D01*
X757780Y393797D01*
X698244D01*
X696349Y395692D01*
X654770D01*
X643940Y406522D01*
Y411482D01*
G01X640720Y431362D02*
Y429862D01*
X639820Y428962D01*
X636811D01*
X634795Y430978D01*
Y431062D01*
G01X640720Y418862D02*
X645420D01*
X646645Y420087D01*
Y421362D01*
G01X634795D02*
X637195D01*
G01X646645Y431362D02*
X644220D01*
G01X640920Y447862D02*
Y446462D01*
X642020Y445362D01*
X645420D01*
X646645Y446587D01*
Y447862D01*
G01X634795Y462862D02*
Y461586D01*
X636119Y460262D01*
X647195D01*
X649795Y462862D01*
G01X634795Y457862D02*
Y457106D01*
X636389Y455512D01*
X638430D01*
X640820Y457902D01*
G01X646645Y457862D02*
Y456747D01*
X644982Y455084D01*
X642436D01*
X640820Y456700D01*
Y457902D01*
G01X637220Y452862D02*
X639520Y450562D01*
X645720D01*
X646645Y451487D01*
Y452862D01*
G01X649795Y467862D02*
Y466638D01*
X648319Y465162D01*
X635719D01*
X634795Y466086D01*
Y467862D01*
G01Y477862D02*
Y476486D01*
X636039Y475242D01*
X648699D01*
X649795Y476338D01*
Y477862D01*
G01Y472862D02*
Y471738D01*
X648419Y470362D01*
X636019D01*
X634795Y471586D01*
Y472862D01*
G01Y487862D02*
Y482862D01*
G01X665610Y482662D02*
X654919D01*
X652029Y485552D01*
X639229D01*
X636539Y482862D01*
X634795D01*
G01X640130Y517870D02*
Y516014D01*
X640700Y515444D01*
Y513700D01*
X644070Y510330D01*
X664580D01*
X665910Y509000D01*
Y498783D01*
X679370Y485323D01*
Y476840D01*
X678810Y476280D01*
X673050D01*
X671479Y474709D01*
Y474707D01*
G01X642630Y517870D02*
Y514500D01*
X644870Y512260D01*
X665380D01*
X667840Y509800D01*
Y501280D01*
X682500Y486620D01*
Y470400D01*
X682070Y469970D01*
X676456D01*
X675466Y468980D01*
X669050D01*
X667350Y470680D01*
G01X640785Y959265D02*
X639066Y957546D01*
X636941D01*
G01Y954200D02*
X639000D01*
X640785Y952415D01*
G01X647689Y997251D02*
X647167Y997773D01*
X646809D01*
X644257Y1000325D01*
G01X633673Y1253173D02*
Y1253273D01*
X634275Y1253875D01*
X637234D01*
X638281Y1254922D01*
G01D02*
Y1257079D01*
X636946Y1258414D01*
G01X647690Y1260812D02*
X644335Y1257457D01*
Y1256368D01*
G01Y1253218D02*
Y1253259D01*
X644376Y1253300D01*
Y1253399D01*
X646941Y1255964D01*
X650362D01*
X653431Y1252895D01*
X656213D01*
G01X637041Y1252034D02*
Y1248685D01*
G01X645897Y1248785D02*
X642548D01*
G01X725740Y69580D02*
X723057Y66897D01*
X654697D01*
X648925Y72669D01*
Y91757D01*
X655100Y97932D01*
Y126892D01*
X670290Y142082D01*
Y147732D01*
X677795Y155237D01*
X683960D01*
X711856Y166792D01*
X714951Y169887D01*
X720715D01*
X722380Y171552D01*
Y175067D01*
X733192Y185879D01*
X776863D01*
X781970Y180772D01*
X812105D01*
X842149Y193217D01*
X907814Y258882D01*
X920153Y263992D01*
X949260D01*
X952950Y267682D01*
X976900D01*
X980590Y263992D01*
X998247D01*
X1016899Y245340D01*
X1024354Y242252D01*
X1075081D01*
X1123330Y194003D01*
X1150130Y129303D01*
X1195041Y84392D01*
X1256889D01*
X1258428Y85931D01*
X1267982D01*
X1269521Y84392D01*
X1280230D01*
X1286020Y90182D01*
X1301530D01*
X1308020Y96672D01*
Y99572D01*
X1313590Y105142D01*
Y109962D01*
X1310000Y113552D01*
G01X1310150Y129029D02*
Y127977D01*
X1311884Y126243D01*
Y120008D01*
X1312190Y119702D01*
Y115818D01*
X1317170Y110838D01*
Y96272D01*
X1319233Y94209D01*
Y91725D01*
X1317670Y90162D01*
X1304610D01*
X1301760Y87312D01*
X1289200D01*
X1280365Y78477D01*
X1237105D01*
X1233720Y81862D01*
X1191506D01*
X1149858Y123510D01*
X1134508Y160579D01*
X1133842Y160855D01*
X1132266Y160203D01*
X1131600Y160479D01*
X1131029Y161856D01*
X1131305Y162522D01*
X1132881Y163175D01*
X1133157Y163839D01*
X1132586Y165217D01*
X1131920Y165493D01*
X1130344Y164841D01*
X1129678Y165117D01*
X1129107Y166494D01*
X1129383Y167160D01*
X1130959Y167813D01*
X1131235Y168477D01*
X1130664Y169855D01*
X1129998Y170131D01*
X1128422Y169479D01*
X1127756Y169755D01*
X1127185Y171132D01*
X1127461Y171798D01*
X1129037Y172451D01*
X1129313Y173115D01*
X1128742Y174493D01*
X1128076Y174769D01*
X1126500Y174117D01*
X1125834Y174393D01*
X1125263Y175770D01*
X1125539Y176436D01*
X1127115Y177089D01*
X1127391Y177753D01*
X1126820Y179131D01*
X1126154Y179407D01*
X1124578Y178755D01*
X1123912Y179031D01*
X1123341Y180408D01*
X1123617Y181074D01*
X1125193Y181727D01*
X1125469Y182391D01*
X1124898Y183769D01*
X1124232Y184045D01*
X1122656Y183393D01*
X1121990Y183669D01*
X1121419Y185046D01*
X1121695Y185712D01*
X1123271Y186365D01*
X1123547Y187030D01*
X1121050Y193058D01*
X1073866Y240242D01*
X1023953D01*
X1015761Y243635D01*
X997684Y261712D01*
X919902D01*
X908951Y257176D01*
X830257Y178482D01*
X781021D01*
X775914Y183589D01*
X734141D01*
X724670Y174118D01*
Y170263D01*
X722099Y167692D01*
X715599D01*
X701691Y153784D01*
X693889Y150552D01*
X689333D01*
X677943Y139162D01*
X671670D01*
X657400Y124892D01*
Y93962D01*
X656200Y92762D01*
Y85362D01*
X669820Y71742D01*
X675380D01*
X676840Y73202D01*
Y78352D01*
X674540Y80652D01*
G01X1314269Y122038D02*
Y120857D01*
X1314760Y120366D01*
Y116732D01*
X1319580Y111912D01*
Y103822D01*
X1322842Y100560D01*
Y99381D01*
X1326520Y95703D01*
Y94020D01*
X1323901Y91401D01*
X1322027D01*
X1318658Y88032D01*
X1306090D01*
X1294525Y76467D01*
X1287380D01*
X1286870Y76977D01*
Y78113D01*
X1286360Y78623D01*
X1284870D01*
X1284360Y78113D01*
Y76977D01*
X1283850Y76467D01*
X1234615D01*
X1231720Y79362D01*
X1190555D01*
X1138960Y130957D01*
Y131679D01*
X1141173Y133892D01*
Y134614D01*
X1140120Y135667D01*
X1139398D01*
X1137185Y133454D01*
X1136463D01*
X1135410Y134507D01*
Y135229D01*
X1137623Y137442D01*
Y138164D01*
X1136570Y139217D01*
X1135848D01*
X1133635Y137004D01*
X1132913D01*
X1131860Y138057D01*
Y138779D01*
X1134423Y141342D01*
Y142064D01*
X1133370Y143117D01*
X1132648D01*
X1130085Y140554D01*
X1129363D01*
X1128310Y141607D01*
Y142329D01*
X1130873Y144892D01*
Y145614D01*
X1129820Y146667D01*
X1129098D01*
X1126535Y144104D01*
X1125813D01*
X1124760Y145157D01*
Y145879D01*
X1127323Y148442D01*
Y149164D01*
X1126270Y150217D01*
X1125548D01*
X1122985Y147654D01*
X1122263D01*
X1118610Y151307D01*
Y192047D01*
X1072425Y238232D01*
X1023551D01*
X1014623Y241930D01*
X997281Y259272D01*
X919264D01*
X910089Y255471D01*
X830660Y176042D01*
X780010D01*
X774903Y181149D01*
X735152D01*
X727110Y173107D01*
Y169252D01*
X723110Y165252D01*
X716610D01*
X699790Y148432D01*
X690056D01*
X661200Y119576D01*
Y83262D01*
X669940Y74522D01*
X674035D01*
G01X667940Y80142D02*
X663300Y84782D01*
Y118832D01*
X690400Y145932D01*
X710189D01*
X723520Y159263D01*
Y162727D01*
X739194Y178401D01*
X774758D01*
X779425Y173734D01*
X831195D01*
X845396Y187935D01*
X846032D01*
X848008Y185958D01*
X848644D01*
X849812Y187126D01*
Y187762D01*
X847836Y189739D01*
Y190375D01*
X911225Y253764D01*
X918269Y256682D01*
X997028D01*
X1013484Y240226D01*
X1023151Y236222D01*
X1070772D01*
X1116020Y190974D01*
Y187042D01*
X1115510Y186532D01*
X1113814D01*
X1113304Y186022D01*
Y184532D01*
X1113814Y184022D01*
X1115510D01*
X1116020Y183512D01*
Y182022D01*
X1115510Y181512D01*
X1113814D01*
X1113304Y181002D01*
Y179512D01*
X1113814Y179002D01*
X1115510D01*
X1116020Y178492D01*
Y177002D01*
X1115510Y176492D01*
X1113814D01*
X1113304Y175982D01*
Y174492D01*
X1113814Y173982D01*
X1115510D01*
X1116020Y173472D01*
Y171982D01*
X1115510Y171472D01*
X1113814D01*
X1113304Y170962D01*
Y169472D01*
X1113814Y168962D01*
X1115510D01*
X1116020Y168452D01*
Y166962D01*
X1115510Y166452D01*
X1113814D01*
X1113304Y165942D01*
Y164452D01*
X1113814Y163942D01*
X1115510D01*
X1116020Y163432D01*
Y161942D01*
X1115510Y161432D01*
X1113814D01*
X1113304Y160922D01*
Y159432D01*
X1113814Y158922D01*
X1115510D01*
X1116020Y158412D01*
Y156922D01*
X1115510Y156412D01*
X1113814D01*
X1113304Y155902D01*
Y154412D01*
X1113814Y153902D01*
X1115510D01*
X1116020Y153392D01*
Y150234D01*
X1189392Y76862D01*
X1229220D01*
X1231625Y74457D01*
X1295755D01*
X1307110Y85812D01*
X1319428D01*
X1322992Y89376D01*
X1324720D01*
X1328995Y93651D01*
Y96250D01*
X1325744Y99501D01*
Y107602D01*
X1327014Y108872D01*
Y112697D01*
X1325013Y114698D01*
X1320675D01*
X1316780Y118593D01*
Y127917D01*
X1317891Y129028D01*
G01X801940Y485932D02*
X805510Y482362D01*
X811120D01*
X813340Y480142D01*
Y463932D01*
X816270Y461002D01*
Y451082D01*
X811590Y446402D01*
Y398985D01*
X797066Y384461D01*
X762023D01*
X744417Y366855D01*
X741048D01*
X736193Y362000D01*
X726800D01*
X723307Y358507D01*
X676285D01*
X672140Y354362D01*
X662680D01*
G01X654780Y422722D02*
X652579D01*
X651219Y421362D01*
X649795D01*
G01X677778Y424313D02*
X676187Y422722D01*
X654780D01*
G01X684077Y430612D02*
X682507Y429042D01*
X673210D01*
X671640Y427472D01*
X662229D01*
X658339Y431362D01*
X654510D01*
G01X659970Y419602D02*
X655459D01*
X652219Y416362D01*
X649795D01*
G01X680928Y427462D02*
X679370Y425904D01*
Y420402D01*
X678570Y419602D01*
X659970D01*
G01X798370Y439932D02*
X800500Y437802D01*
Y433055D01*
X801313Y432242D01*
Y430448D01*
X800778Y429913D01*
Y427440D01*
X798690Y425352D01*
X786910D01*
X785430Y423872D01*
Y421732D01*
X788035Y419127D01*
Y417547D01*
X785430Y414942D01*
Y414132D01*
X777060Y405762D01*
X752620D01*
X750870Y407512D01*
Y410850D01*
X738978Y422742D01*
X723870D01*
X723430Y423182D01*
Y428627D01*
X723038Y429019D01*
X686134D01*
X685643Y429510D01*
Y431339D01*
X684800Y432182D01*
X676690D01*
X674870Y434002D01*
X668870D01*
X666690Y431822D01*
X660830D01*
X658490Y434162D01*
X647420D01*
G01X649795Y438862D02*
X651451D01*
X651541Y438772D01*
X671879D01*
X673740Y436911D01*
X674628D01*
G01X654510Y431362D02*
X649795D01*
G01X680928Y455809D02*
X679365Y457372D01*
X655990D01*
X652600Y460762D01*
X650719D01*
X649795Y461686D01*
Y462862D01*
G01X664990Y454252D02*
X657240D01*
X656210Y455282D01*
X651191D01*
X649795Y456678D01*
Y457862D01*
G01X662480Y449782D02*
X654799D01*
X651719Y452862D01*
X649795D01*
G01X662480Y449782D02*
X663798Y451100D01*
X678639D01*
X679330Y450409D01*
Y445830D01*
X677778Y444278D01*
Y443210D01*
G01X649795Y447862D02*
X650655Y447002D01*
X654300D01*
G01D02*
X672398D01*
X673031Y446369D01*
Y439381D01*
X673910Y438502D01*
X678810D01*
X679350Y439042D01*
Y441632D01*
X680928Y443210D01*
G01X649795Y467862D02*
X651719D01*
X653919Y470062D01*
X659468D01*
X662500Y467030D01*
G01D02*
X663340D01*
X666668Y463702D01*
X685633D01*
X687227Y462108D01*
G01X664140Y475362D02*
X654220D01*
X651720Y477862D01*
X649795D01*
G01X657740Y473132D02*
X650065D01*
X649795Y472862D01*
G01X657740Y473132D02*
X667388D01*
X669730Y470790D01*
X674470D01*
X676812Y473132D01*
X679353D01*
X680928Y474707D01*
G01X674628Y484006D02*
Y481006D01*
X672584Y478962D01*
X655619D01*
X651719Y482862D01*
X649795D01*
G01X667347Y761460D02*
Y763589D01*
X669020Y765262D01*
Y769162D01*
X668220Y769962D01*
X662349D01*
X662020Y770291D01*
Y774062D01*
X662490Y774532D01*
X664342D01*
G01X677887Y742121D02*
Y747886D01*
X669928Y755845D01*
X664058D01*
X663547Y756356D01*
Y758310D01*
X666697Y761460D01*
X667347D01*
G01X656638Y989241D02*
Y985321D01*
G01X684705Y1248385D02*
X682310Y1250780D01*
X679839D01*
X677890Y1248831D01*
Y1243525D01*
X676647Y1242282D01*
X664086D01*
X661516Y1244852D01*
X654196D01*
G01X659363Y1252895D02*
X663921Y1257453D01*
Y1257838D01*
X664630Y1258547D01*
Y1259442D01*
G01X678683Y1254408D02*
X678160D01*
X674787Y1251035D01*
X669577D01*
X666397Y1247855D01*
X662787D01*
X659752Y1250890D01*
X658317D01*
X656312Y1252895D01*
X656213D01*
G01X647877Y1254076D02*
Y1252596D01*
X649197Y1251276D01*
G01D02*
X651320D01*
X654196Y1248400D01*
Y1248002D01*
G01X755420Y1426262D02*
X754630Y1425472D01*
X750094D01*
X745820Y1429746D01*
Y1433974D01*
X729541Y1450253D01*
X670791D01*
X658266Y1437728D01*
Y1428859D01*
X656489Y1427082D01*
X655063D01*
X654540Y1427605D01*
G01X755420Y1422862D02*
X754520Y1423762D01*
X749384D01*
X744110Y1429036D01*
Y1433264D01*
X728831Y1448543D01*
X671501D01*
X659976Y1437018D01*
Y1427528D01*
X657440Y1424992D01*
X655327D01*
X654540Y1424205D01*
G01X677940Y1670110D02*
Y1663800D01*
X674700Y1660560D01*
Y1655930D01*
X677650Y1652980D01*
Y1623120D01*
X682120Y1618650D01*
Y1570780D01*
X680150Y1568810D01*
X675715D01*
X675215Y1568310D01*
Y1559335D01*
X667899Y1552019D01*
X666334D01*
X662660Y1548345D01*
Y1548120D01*
G01X680200Y39062D02*
X676953Y35815D01*
Y35067D01*
G01X677560Y40572D02*
Y43093D01*
X679610Y48041D01*
Y50889D01*
X681328Y52607D01*
X681980D01*
G01X672250Y40812D02*
X672980D01*
X675665Y43497D01*
X677780Y48603D01*
Y52337D01*
X678050Y52607D01*
G01Y55757D02*
Y58157D01*
G01X682588Y87262D02*
X677076D01*
X675622Y88716D01*
Y108460D01*
X673720Y110362D01*
G01X1319288Y122027D02*
X1319415D01*
X1323780Y117662D01*
X1329820D01*
X1340120Y107362D01*
Y92054D01*
X1327195Y79129D01*
X1320001D01*
X1316159Y75287D01*
X1300805D01*
X1297465Y71947D01*
X1229135D01*
X1227220Y73862D01*
X1188757D01*
X1109819Y152800D01*
Y159601D01*
X1109309Y160111D01*
X1108682D01*
X1108172Y160621D01*
Y162111D01*
X1108682Y162621D01*
X1109309D01*
X1109819Y163131D01*
Y164621D01*
X1109309Y165131D01*
X1108682D01*
X1108172Y165641D01*
Y167131D01*
X1108682Y167641D01*
X1109309D01*
X1109819Y168151D01*
Y169641D01*
X1109309Y170151D01*
X1108682D01*
X1108172Y170661D01*
Y172151D01*
X1108682Y172661D01*
X1109309D01*
X1109819Y173171D01*
Y174661D01*
X1109309Y175171D01*
X1108682D01*
X1108172Y175681D01*
Y177171D01*
X1108682Y177681D01*
X1109309D01*
X1109819Y178191D01*
Y179681D01*
X1109309Y180191D01*
X1108682D01*
X1108172Y180701D01*
Y182191D01*
X1108682Y182701D01*
X1109309D01*
X1109819Y183211D01*
Y184701D01*
X1109309Y185211D01*
X1108682D01*
X1108172Y185721D01*
Y187211D01*
X1108682Y187721D01*
X1109309D01*
X1109819Y188231D01*
Y193540D01*
X1069647Y233712D01*
X1022650D01*
X1012061Y238098D01*
X996047Y254112D01*
X918628D01*
X912647Y251635D01*
X853080Y192068D01*
Y182622D01*
X845749Y175291D01*
X845027D01*
X842344Y177974D01*
X841622D01*
X840569Y176921D01*
Y176199D01*
X843252Y173516D01*
Y172794D01*
X841650Y171192D01*
X768788D01*
X764089Y175891D01*
X744149D01*
X711490Y143232D01*
X691250D01*
X665900Y117882D01*
Y85962D01*
X669350Y82512D01*
X672160D01*
X673550Y83902D01*
X675980D01*
X680101Y79781D01*
X680578Y78629D01*
Y75992D01*
G01X670800Y85932D02*
Y88112D01*
X668510Y90402D01*
Y116941D01*
X692291Y140722D01*
X714716D01*
X738756Y164762D01*
X770421D01*
X770422Y164763D01*
X774820D01*
X778739Y168682D01*
X842740D01*
X855590Y181532D01*
Y191028D01*
X914066Y249504D01*
X918645Y251402D01*
X995060D01*
X1010390Y236072D01*
X1022148Y231202D01*
X1068324D01*
X1105043Y194483D01*
Y189859D01*
X1104533Y189349D01*
X1102173D01*
X1101663Y188839D01*
Y187349D01*
X1102173Y186839D01*
X1104533D01*
X1105043Y186329D01*
Y184839D01*
X1104533Y184329D01*
X1102173D01*
X1101663Y183819D01*
Y182329D01*
X1102173Y181819D01*
X1104533D01*
X1105043Y181309D01*
Y179819D01*
X1104533Y179309D01*
X1102173D01*
X1101663Y178799D01*
Y177309D01*
X1102173Y176799D01*
X1104533D01*
X1105043Y176289D01*
Y174799D01*
X1104533Y174289D01*
X1102173D01*
X1101663Y173779D01*
Y172289D01*
X1102173Y171779D01*
X1104533D01*
X1105043Y171269D01*
Y169779D01*
X1104533Y169269D01*
X1102173D01*
X1101663Y168759D01*
Y167269D01*
X1102173Y166759D01*
X1104533D01*
X1105043Y166249D01*
Y164759D01*
X1104533Y164249D01*
X1102173D01*
X1101663Y163739D01*
Y162249D01*
X1102173Y161739D01*
X1104533D01*
X1105043Y161229D01*
Y153743D01*
X1187924Y70862D01*
X1224720D01*
X1226145Y69437D01*
X1299685D01*
X1302570Y72322D01*
X1324680D01*
X1342720Y90362D01*
Y108762D01*
X1331063Y120419D01*
X1325227D01*
X1323493Y122153D01*
Y129155D01*
G01X671320Y91192D02*
Y114270D01*
X673184Y118772D01*
X688892Y134480D01*
X697491Y138042D01*
X715758D01*
X734345Y156629D01*
X747944Y162262D01*
X775162D01*
X779572Y166672D01*
X843828D01*
X857820Y180664D01*
Y190414D01*
X915207Y247801D01*
X919320Y249172D01*
X994360D01*
X1009103Y234429D01*
X1021795Y229172D01*
X1067510D01*
X1099622Y197060D01*
Y174047D01*
X1099112Y173537D01*
X1098418D01*
X1097908Y173027D01*
Y171537D01*
X1098418Y171027D01*
X1099112D01*
X1099622Y170517D01*
Y169027D01*
X1099112Y168517D01*
X1098418D01*
X1097908Y168007D01*
Y166517D01*
X1098418Y166007D01*
X1099112D01*
X1099622Y165497D01*
Y164007D01*
X1099112Y163497D01*
X1098418D01*
X1097908Y162987D01*
Y161497D01*
X1098418Y160987D01*
X1099112D01*
X1099622Y160477D01*
Y156010D01*
X1187270Y68362D01*
X1221220D01*
X1222155Y67427D01*
X1287295D01*
X1302609Y64381D01*
X1341439D01*
X1352380Y75322D01*
Y78302D01*
X1349790Y80892D01*
X1345860D01*
X1344340Y82412D01*
Y85412D01*
X1347423Y88495D01*
X1352470Y100680D01*
Y105431D01*
X1349212Y108689D01*
X1344401Y110682D01*
X1331881Y123202D01*
X1327428D01*
G01X677790Y104880D02*
Y106620D01*
X682440Y111270D01*
Y115795D01*
G01X687227Y449510D02*
X685669Y447952D01*
X683300D01*
X682510Y448742D01*
Y453622D01*
X681880Y454252D01*
X664990D01*
G01X677778Y477856D02*
X676690Y478944D01*
Y484850D01*
X675330Y486210D01*
X669158D01*
X665610Y482662D01*
G01X664140Y475362D02*
X667808D01*
X670570Y472600D01*
X673770D01*
X675940Y474770D01*
X677715D01*
X677778Y474707D01*
G01X680299Y766798D02*
X678187D01*
X677677Y767308D01*
Y768670D01*
X676535Y769812D01*
G01X672537Y761520D02*
X671942Y762115D01*
Y770132D01*
G01X826497Y739255D02*
X820787Y733545D01*
X689627D01*
X680068Y743104D01*
Y754752D01*
X673300Y761520D01*
X672537D01*
G01X670485Y959265D02*
X668766Y957546D01*
X666641D01*
G01Y954200D02*
X668700D01*
X670485Y952415D01*
G01X676309Y994386D02*
X672063Y998632D01*
G01X666741Y1255381D02*
X668603D01*
X669154Y1255932D01*
X670810D01*
G01X702062Y1254419D02*
Y1252350D01*
X700187Y1250475D01*
X697114D01*
X695997Y1250938D01*
X694891Y1252044D01*
Y1252812D01*
X693141Y1254562D01*
X690500D01*
X690346Y1254408D01*
X678683D01*
G01X664709Y1249918D02*
Y1250715D01*
X665209Y1251215D01*
X665922D01*
X666741Y1252034D01*
G01X675537Y1248885D02*
X672188D01*
G01X678877Y1566798D02*
X677530D01*
X677030Y1566298D01*
Y1558731D01*
X668608Y1550309D01*
X667043D01*
X665410Y1548676D01*
Y1548180D01*
G01X675710Y1620320D02*
X671830Y1624200D01*
Y1635850D01*
X675570Y1639590D01*
Y1651220D01*
X672920Y1653870D01*
Y1662290D01*
X674320Y1663690D01*
Y1671082D01*
X671610Y1673792D01*
G01X683440Y42832D02*
X684720Y41552D01*
Y35670D01*
X684107Y35057D01*
G01X680103Y35067D02*
X682080Y37044D01*
Y40282D01*
X680820Y41542D01*
Y43890D01*
X681854Y46386D01*
X682289Y46821D01*
G01X692289Y40633D02*
X697240Y35682D01*
X704399D01*
X711867Y43150D01*
Y52647D01*
G01X689940Y38952D02*
Y37740D01*
X687257Y35057D01*
G01X683440Y42832D02*
X685120Y44512D01*
Y48541D01*
X689186Y52607D01*
X690220D01*
G01X685968D02*
X685356D01*
X682240Y49491D01*
Y46841D01*
X682260Y46821D01*
X682289D01*
G01X682290Y46822D02*
X682289Y46821D01*
G01X698597Y52607D02*
Y50895D01*
X692912Y48540D01*
X692059D01*
X691174Y48173D01*
X690110Y47109D01*
Y41602D01*
X689440Y40932D01*
X688420D01*
X687120Y39632D01*
G01X687344Y46940D02*
X689604Y49200D01*
X690295Y49662D01*
X693842Y51131D01*
X694400Y51689D01*
Y52607D01*
G01X692389Y46439D02*
X694590Y44238D01*
Y41192D01*
X697190Y38592D01*
X704130D01*
X708740Y43202D01*
Y51464D01*
X707597Y52607D01*
G01X685780Y70022D02*
Y74762D01*
X689070Y78052D01*
Y80792D01*
X686588Y83274D01*
Y87262D01*
G01X694400Y55757D02*
Y58157D01*
G01X681980Y55757D02*
Y58157D01*
G01X686588Y87262D02*
X682588D01*
G01X687030Y113090D02*
X685145D01*
X682440Y115795D01*
G01Y118945D02*
X683985D01*
X687034Y115896D01*
G01X696760Y128157D02*
X692083D01*
G01X700600Y125309D02*
X699256D01*
X698408Y126157D01*
X694083D01*
X692083Y128157D01*
G01X692247Y381580D02*
X688247D01*
G01X685210Y388852D02*
Y384472D01*
X688102Y381580D01*
X688247D01*
G01X692330Y388751D02*
Y384813D01*
X692247Y384730D01*
G01X692402Y391250D02*
X763692D01*
X764090Y390852D01*
X781460D01*
X784490Y393882D01*
Y399622D01*
X793257Y408389D01*
X800352D01*
G01X699688Y412255D02*
X694880D01*
G01X687227Y414864D02*
X689663Y412428D01*
Y407474D01*
G01X694880Y412255D02*
Y410431D01*
X691923Y407474D01*
X689663D01*
G01X692400Y404682D02*
X692042Y404324D01*
X689663D01*
G01X690376Y421163D02*
X693177Y418362D01*
X693300D01*
G01D02*
X695078Y420140D01*
Y422159D01*
X695634Y422715D01*
X698235D01*
X699410Y421540D01*
G01X690376Y418013D02*
X689299D01*
X688800Y418512D01*
Y425262D01*
X689448Y425910D01*
X708590D01*
X712781Y421719D01*
Y420381D01*
G01X687227Y443210D02*
X686532D01*
X683680Y446062D01*
X681610D01*
G01X714427Y1247500D02*
X713048D01*
X711750Y1246202D01*
X707715D01*
X706495Y1247422D01*
X704131D01*
X700271Y1243562D01*
X694975D01*
X693643Y1244894D01*
X688295D01*
X684804Y1248385D01*
X684705D01*
G01X694375Y1257062D02*
X697536D01*
X698230Y1256368D01*
Y1253238D01*
X697533Y1252541D01*
G01X692233Y1252480D02*
X691288Y1251535D01*
X684705D01*
G01X702062Y1257569D02*
X700395Y1259236D01*
X696426D01*
X694100Y1261562D01*
G01X692280Y1302532D02*
X695910Y1306162D01*
X701145D01*
X701645Y1305662D01*
Y1301993D01*
X701699Y1301939D01*
Y1301216D01*
X701645Y1301162D01*
G01X692100Y1567190D02*
X692560Y1566730D01*
Y1547130D01*
X744297Y1495393D01*
X1035576D01*
X1056220Y1516037D01*
Y1525824D01*
X1062086Y1531690D01*
X1093656D01*
X1107643Y1545677D01*
Y1557144D01*
X1112300Y1561801D01*
Y1605499D01*
X1108343Y1609456D01*
Y1627287D01*
X1112426Y1631370D01*
X1113990D01*
G01X1113325Y1627975D02*
X1111535D01*
X1110113Y1626553D01*
Y1610100D01*
X1114000Y1606213D01*
Y1561200D01*
X1109413Y1556613D01*
Y1544943D01*
X1094390Y1529920D01*
X1062820D01*
X1057990Y1525090D01*
Y1513960D01*
X1036703Y1492673D01*
X744707D01*
X689100Y1548280D01*
Y1550877D01*
X687671Y1552306D01*
Y1581021D01*
X696080Y1589430D01*
Y1627790D01*
X699610Y1631320D01*
Y1652300D01*
X694810Y1657100D01*
Y1664077D01*
X697595Y1666862D01*
G01X702790Y55747D02*
X698607D01*
X698597Y55757D01*
G01X697720Y58162D02*
X698597Y57285D01*
Y55757D01*
G01X710200Y69662D02*
Y72687D01*
X707600Y75287D01*
X707500D01*
G01X706867Y58197D02*
X706922Y58252D01*
X710090D01*
X711867Y56475D01*
Y55797D01*
G01X703100Y58157D02*
X703644D01*
X706044Y55757D01*
X707597D01*
G01X708110Y82537D02*
X712100D01*
G01X715925Y82562D02*
X712125D01*
X712100Y82537D01*
G01X712000Y75237D02*
Y76181D01*
X710486Y77695D01*
G01D02*
Y80923D01*
X712100Y82537D01*
G01X713000Y69662D02*
Y71087D01*
X712000Y72087D01*
G01X700500Y74862D02*
X700925Y75287D01*
X703500D01*
G01X965884Y242051D02*
Y225433D01*
X961908Y221457D01*
X931618D01*
X911242Y201081D01*
X907106D01*
X901950Y195925D01*
X882582D01*
X880688Y194031D01*
X875982D01*
X839019Y157068D01*
X780492D01*
X772824Y149400D01*
X767425D01*
X764024Y152801D01*
X733449D01*
X726307Y145659D01*
Y137385D01*
X722126Y133204D01*
X720575D01*
X707866Y120495D01*
Y102382D01*
X709540Y100708D01*
Y98583D01*
X708110Y97153D01*
Y85687D01*
G01X705390Y85792D02*
Y80547D01*
X707500Y78437D01*
G01X703000Y84862D02*
X702640Y84502D01*
Y79297D01*
X703500Y78437D01*
G01X728000Y81437D02*
Y87662D01*
X725750Y89912D01*
X719050D01*
X717190Y91772D01*
Y106354D01*
X709642Y113902D01*
Y119645D01*
X721425Y131428D01*
X722862D01*
X728758Y137324D01*
Y145410D01*
X734373Y151025D01*
X763288D01*
X766689Y147624D01*
X773560D01*
X781228Y155292D01*
X839755D01*
X874310Y189847D01*
X880026D01*
X884026Y193847D01*
X902811D01*
X907967Y199003D01*
X912103D01*
X932479Y219379D01*
X962769D01*
X968384Y224994D01*
Y242051D01*
G01X700960Y131277D02*
Y133722D01*
X698900Y135782D01*
G01D02*
X696760Y133642D01*
Y131307D01*
G01X702600Y417500D02*
X703282D01*
X706060Y414722D01*
Y411302D01*
X705780Y411022D01*
G01X712770Y406822D02*
X710433Y409159D01*
Y412284D01*
G01X699450Y417500D02*
Y421500D01*
X699410Y421540D01*
G01X710433Y415434D02*
X710745Y415122D01*
X713680D01*
X714472Y414330D01*
Y412269D01*
G01X712781Y420381D02*
Y419381D01*
X710290Y416890D01*
Y415577D01*
X710433Y415434D01*
G01X701757Y521324D02*
X699220Y518787D01*
Y485061D01*
X702448Y481833D01*
Y477984D01*
X707690Y472742D01*
Y463692D01*
X709274Y462108D01*
G01X712060Y638542D02*
X713360Y639842D01*
Y641872D01*
X711610Y643622D01*
X707680D01*
X706320Y644982D01*
Y652105D01*
X716987Y662772D01*
X886987D01*
X914387Y690172D01*
X960487D01*
X1000017Y729702D01*
Y1190092D01*
X996770Y1193339D01*
Y1264421D01*
X1005527Y1273178D01*
Y1278905D01*
X1008267Y1281645D01*
X1021397D01*
X1025037Y1285285D01*
Y1291604D01*
X1085193Y1351760D01*
Y1445955D01*
X1133347Y1494109D01*
X1336306D01*
X1370041Y1460374D01*
G01X708310Y646032D02*
X710545D01*
X711720Y647207D01*
Y654662D01*
X717820Y660762D01*
X887820D01*
X915220Y688162D01*
X961320D01*
X1001627Y728469D01*
Y1192232D01*
X999010Y1194849D01*
Y1263818D01*
X1007537Y1272345D01*
Y1277375D01*
X1009787Y1279625D01*
X1022907D01*
X1027157Y1283875D01*
Y1290315D01*
X1087567Y1350725D01*
Y1445485D01*
X1133817Y1491735D01*
X1334367D01*
X1368980Y1457122D01*
G01X1444997Y1392885D02*
X1442977Y1394905D01*
Y1407755D01*
X1440797Y1409935D01*
Y1411725D01*
X1445270Y1416198D01*
Y1419392D01*
X1436024Y1428638D01*
Y1440458D01*
X1380363Y1496119D01*
X1132513D01*
X1083137Y1446743D01*
Y1351981D01*
X1022807Y1291651D01*
Y1286035D01*
X1020537Y1283765D01*
X1007107D01*
X1003517Y1280175D01*
Y1274011D01*
X994820Y1265314D01*
Y1192282D01*
X998407Y1188695D01*
Y730935D01*
X959654Y692182D01*
X913554D01*
X886154Y664782D01*
X716154D01*
X704320Y652948D01*
Y645262D01*
G01X709899Y766798D02*
X711447D01*
X711957Y767308D01*
Y772145D01*
X710417Y773685D01*
G01X698920Y959252D02*
X698147D01*
X696441Y957546D01*
G01Y954200D02*
X698049Y952592D01*
X699040D01*
G01X701087Y988721D02*
Y992035D01*
X698765Y994357D01*
X696441D01*
G01X697533Y1252541D02*
X696947Y1253127D01*
Y1254875D01*
X696441Y1255381D01*
G01X702062Y1254419D02*
X703273D01*
X703773Y1254919D01*
Y1257876D01*
X704947Y1259050D01*
X706598D01*
X711552Y1254096D01*
X714287D01*
X717368Y1251015D01*
X726837D01*
X730245Y1254423D01*
X730328D01*
G01X705037Y1252034D02*
X703790Y1250787D01*
Y1249622D01*
G01X699186Y1246192D02*
X698766D01*
X696441Y1248517D01*
Y1248688D01*
G01X706493Y1256563D02*
Y1255259D01*
X709748Y1252004D01*
G01D02*
X711102Y1250650D01*
X714427D01*
G01X713795Y1297162D02*
Y1296022D01*
X712655Y1294882D01*
Y1287097D01*
X711720Y1286162D01*
G01X710645Y1297162D02*
Y1294650D01*
X710177Y1294182D01*
X709646D01*
X709136Y1293672D01*
Y1292682D01*
X709646Y1292172D01*
X710416D01*
X710826Y1291762D01*
Y1290772D01*
X710216Y1290162D01*
X707720D01*
G01X710645Y1301162D02*
X707697Y1298214D01*
Y1294731D01*
X705720Y1292754D01*
Y1286662D01*
G01X701645Y1297162D02*
X699810D01*
X696810Y1300162D01*
G01X704795Y1294559D02*
Y1297162D01*
G01X707320Y1301162D02*
X704795D01*
G01X707687Y1587683D02*
X712103D01*
X714380Y1589960D01*
G01X712512Y1596338D02*
X708342D01*
X708087Y1596083D01*
Y1595623D01*
G01X713102Y1601307D02*
X709963D01*
X709287Y1601983D01*
G01X712298Y1605727D02*
Y1604755D01*
X715775Y1601278D01*
Y1599024D01*
G01X706103Y1617107D02*
X706761Y1616449D01*
X713296D01*
X713800Y1615945D01*
Y1612470D01*
X714348Y1611922D01*
Y1606025D01*
X716202Y1604171D01*
G01X708175Y1608886D02*
X712289D01*
X712298Y1608877D01*
G01X708857Y1613462D02*
X709186Y1613133D01*
Y1609897D01*
X708175Y1608886D01*
G01X705516Y1620296D02*
X703542Y1618322D01*
Y1608277D01*
X706083Y1605736D01*
X708175D01*
G01X710570Y1629890D02*
X709490Y1630970D01*
X708025D01*
X704219Y1634776D01*
G01X708219Y1637926D02*
Y1641776D01*
X708294Y1641851D01*
G01D02*
Y1646057D01*
X708999Y1646762D01*
G01X704219Y1637926D02*
X708219D01*
G01X703719Y1646768D02*
X705144Y1645343D01*
Y1641851D01*
G01X700460Y1660918D02*
X705083D01*
G01X708521Y1667828D02*
X706781D01*
X705083Y1666130D01*
Y1664068D01*
G01X708521Y1663842D02*
Y1667828D01*
G01Y1663842D02*
Y1659642D01*
X709678Y1658485D01*
G01X708521Y1667828D02*
X708534Y1667841D01*
G01X704759Y1677001D02*
X711684Y1670076D01*
Y1667841D01*
G01X724620Y40062D02*
X724644Y40086D01*
Y51970D01*
G01X719820Y45862D02*
X719949Y45991D01*
Y51970D01*
G01X724644Y55120D02*
Y58362D01*
G01X719949Y55120D02*
Y58862D01*
G01X715990Y72087D02*
Y69662D01*
G01X721990Y69762D02*
X723957Y71729D01*
Y72087D01*
G01X718900Y69662D02*
X719967Y70729D01*
Y72087D01*
G01X723400Y82487D02*
X726950D01*
X728000Y81437D01*
G01X715990Y75237D02*
Y78352D01*
X717500Y79862D01*
X722199D01*
X723400Y81063D01*
Y82487D01*
G01X722415Y77862D02*
Y76479D01*
X723657Y75237D01*
X723957D01*
G01X718425Y77882D02*
Y76479D01*
X719667Y75237D01*
X719967D01*
G01X728090Y75132D02*
Y78197D01*
X728000Y78287D01*
G01X719100Y85262D02*
X719075Y85237D01*
Y82562D01*
G01X805470Y510522D02*
Y499542D01*
X829420Y475592D01*
Y465400D01*
X824324Y460304D01*
Y454575D01*
X813300Y443551D01*
Y398276D01*
X813100Y398076D01*
Y397257D01*
X797923Y382080D01*
X764349D01*
X742269Y360000D01*
X734000D01*
X727887Y353887D01*
X724897D01*
G01X807640Y506672D02*
Y499972D01*
X832000Y475612D01*
Y464700D01*
X827449Y460149D01*
Y454051D01*
X817500Y444102D01*
Y413451D01*
X817165Y413116D01*
Y411412D01*
X817500Y411077D01*
Y398568D01*
X817365Y398433D01*
Y397873D01*
X798992Y379500D01*
X764188D01*
X742888Y358200D01*
X735599D01*
X729099Y351700D01*
X722455D01*
X721989Y351234D01*
G01X728885Y411382D02*
X722870D01*
X721873Y412379D01*
Y421132D01*
G01X725022Y427462D02*
X726592Y425892D01*
X743829D01*
X760645Y409076D01*
Y408212D01*
G01X728172Y433761D02*
X726590Y432179D01*
Y429572D01*
X727110Y429052D01*
X748380D01*
G01X721873Y421132D02*
Y424313D01*
G01X738670Y417482D02*
X736560Y419592D01*
X726593D01*
X725022Y421163D01*
G01X718723Y440061D02*
X720292Y438492D01*
X736640D01*
X740790Y434342D01*
X749515D01*
X760645Y423212D01*
G01X725022Y433761D02*
X726603Y435342D01*
X735220D01*
X739090Y431472D01*
X742450D01*
G01X728172Y440061D02*
X729752Y441641D01*
X735071D01*
X740050Y436662D01*
X742360D01*
G01X768720Y459862D02*
X766490Y457632D01*
X743999D01*
X737469Y451102D01*
X729729D01*
X728172Y452659D01*
G01X725022Y458959D02*
X726579Y457402D01*
X738660D01*
X748660Y467402D01*
X752761D01*
X755221Y469862D01*
X759765D01*
G01X721873Y455809D02*
X723460Y454222D01*
X737980D01*
X748620Y464862D01*
X759765D01*
G01X751220Y522362D02*
X748320Y525262D01*
X734820D01*
X732190Y522632D01*
Y498552D01*
X722765Y489127D01*
Y482336D01*
X720290Y479861D01*
Y467512D01*
X719610Y466832D01*
X717870D01*
X717150Y466112D01*
Y464482D01*
X716360Y463692D01*
X714640D01*
X713074Y465258D01*
X712424D01*
G01X733922Y531712D02*
X725880Y523670D01*
Y497432D01*
X720740Y492292D01*
Y482442D01*
X717140Y478842D01*
Y469973D01*
X715574Y468407D01*
G01X725132Y481116D02*
Y483650D01*
X737590Y496108D01*
Y516352D01*
X737080Y516862D01*
X735430D01*
G01X728272Y481006D02*
X728172Y481106D01*
Y483846D01*
X740680Y496354D01*
Y521822D01*
X740840Y521982D01*
G01X719190Y646642D02*
X727120D01*
X735655Y655177D01*
X890533D01*
X916983Y681627D01*
X967599D01*
X1056087Y770115D01*
Y997645D01*
X1067657Y1009215D01*
X1083987D01*
X1090787Y1016015D01*
Y1018955D01*
X1092127Y1020295D01*
X1097497D01*
X1098237Y1019555D01*
X1107597D01*
X1111437Y1023395D01*
Y1061345D01*
X1113147Y1063055D01*
X1119917D01*
X1120467Y1063605D01*
Y1081055D01*
X1133947Y1094535D01*
X1138287D01*
X1143757Y1100005D01*
X1149027D01*
X1150767Y1098265D01*
X1153687D01*
X1155107Y1099685D01*
X1164317D01*
X1164517Y1099885D01*
X1178297D01*
X1179897Y1098285D01*
X1192977D01*
X1195807Y1101115D01*
X1207907D01*
X1211237Y1104445D01*
X1222397D01*
X1223793Y1105841D01*
Y1236811D01*
G01X730889Y746834D02*
Y749483D01*
X726237Y754135D01*
Y763175D01*
X723037Y766375D01*
Y967715D01*
X729117Y973795D01*
Y1007945D01*
X723037Y1014025D01*
Y1045285D01*
G01X729885Y959265D02*
X728166Y957546D01*
X726041D01*
G01Y954200D02*
X728100D01*
X729885Y952415D01*
G01X726041Y994357D02*
X723975Y992291D01*
Y984675D01*
G01X723037Y1045285D02*
Y1061435D01*
X730977Y1069375D01*
Y1230549D01*
X731069Y1230641D01*
G01X726141Y1057940D02*
X729082D01*
X731467Y1055555D01*
Y1045015D01*
G01X732107Y1249625D02*
X729500Y1247018D01*
Y1243278D01*
X728185Y1241963D01*
X725073D01*
G01D02*
X723850Y1240740D01*
Y1235892D01*
G01D02*
X725951Y1233791D01*
X731069D01*
G01X723460Y1245632D02*
X723140Y1245312D01*
X719110D01*
X716922Y1247500D01*
X714427D01*
G01X726141Y1255381D02*
X724116Y1253356D01*
X722094D01*
G01X723700Y1258727D02*
X727108D01*
X728262Y1257573D01*
X728496D01*
X728588Y1257481D01*
X730236D01*
X730328Y1257573D01*
G01X726141Y1248688D02*
X722792D01*
G01X714720Y1286162D02*
Y1289022D01*
X716507Y1290809D01*
Y1292097D01*
X716006Y1292598D01*
X714981D01*
X714480Y1293099D01*
Y1293807D01*
X714981Y1294308D01*
X716006D01*
X716507Y1294809D01*
Y1296061D01*
X717008Y1296562D01*
X717829D01*
X718330Y1297063D01*
Y1297771D01*
X717829Y1298272D01*
X717008D01*
X716507Y1298773D01*
Y1300107D01*
X715452Y1301162D01*
X713795D01*
G01X723542Y1612702D02*
Y1610303D01*
X722282Y1609043D01*
Y1602533D01*
X723062Y1601753D01*
Y1594298D01*
X722677Y1593913D01*
G01X726092Y1598483D02*
X725827Y1598218D01*
Y1593913D01*
G01X720112Y1604158D02*
X720352Y1603918D01*
Y1600203D01*
X720987Y1599568D01*
G01X720112Y1607308D02*
X719339D01*
X716202Y1604171D01*
G01Y1607321D02*
Y1609569D01*
X716688Y1610055D01*
G01X719168Y1612016D02*
X717760Y1613424D01*
Y1628480D01*
X724550Y1635270D01*
Y1648190D01*
X722630Y1650110D01*
Y1655740D01*
G01X745900Y40362D02*
X743120Y43142D01*
Y49579D01*
X743532Y50574D01*
X744928Y51970D01*
X745474D01*
G01X733314Y40862D02*
Y42568D01*
X733642Y42896D01*
Y51970D01*
G01X728720Y43562D02*
X729293Y44135D01*
Y51970D01*
G01X740100Y41162D02*
X740420Y41482D01*
Y51461D01*
X740929Y51970D01*
X741377D01*
G01X736620Y45262D02*
X737595Y46237D01*
Y51970D01*
G01X733642Y55120D02*
Y58062D01*
G01X729293Y55120D02*
Y58062D01*
G01X741377Y55120D02*
Y57932D01*
G01X737595Y55120D02*
Y57932D01*
G01X742960Y76142D02*
X745865D01*
X747445Y74562D01*
G01X747487Y71429D02*
X742960Y75956D01*
Y76142D01*
G01X742160Y396452D02*
X747570D01*
X749650Y398532D01*
G01X735220Y410842D02*
X735150Y410912D01*
X732505D01*
X732035Y411382D01*
G01X748178Y407994D02*
Y408079D01*
X743565Y412692D01*
G01D02*
X742840Y413417D01*
Y416602D01*
X741960Y417482D01*
X738670D01*
G01X742450Y431472D02*
X749360D01*
X760300Y420532D01*
X774449D01*
X775645Y419336D01*
Y418212D01*
G01X742360Y436662D02*
X749130D01*
X759930Y425862D01*
X772995D01*
X775645Y423212D01*
G01X731322Y465258D02*
X740510D01*
G01D02*
X750114Y474862D01*
X759765D01*
G01X777883Y484802D02*
X774798Y481717D01*
X752264D01*
X742104Y471557D01*
X737621D01*
G01X734471Y468407D02*
X735350Y469286D01*
Y472355D01*
X749095Y486100D01*
X765578D01*
X771990Y492512D01*
Y503593D01*
X769241Y506342D01*
X765810D01*
G01X731322Y468407D02*
X733670Y470755D01*
Y473419D01*
X749073Y488822D01*
X757503D01*
X759453Y490772D01*
X768144D01*
X769157Y491785D01*
Y495788D01*
X767287Y497658D01*
X762932D01*
G01X745220Y522362D02*
X743110Y520252D01*
Y511713D01*
X743536Y511287D01*
X745220D01*
G01X730690Y655532D02*
X733225Y658067D01*
X889335D01*
X915785Y684517D01*
X966401D01*
X1024520Y742636D01*
Y765128D01*
X1025816Y766424D01*
Y995705D01*
X1042466Y1012355D01*
X1079947D01*
X1082627Y1015035D01*
Y1024492D01*
X1084157Y1026022D01*
X1089050D01*
X1089280Y1026252D01*
X1102910D01*
X1105420Y1028762D01*
Y1062102D01*
X1107630Y1064312D01*
X1109280D01*
X1114530Y1069562D01*
Y1082412D01*
X1115060Y1082942D01*
X1119080D01*
X1120060Y1083922D01*
Y1228742D01*
X1122163Y1230845D01*
X1132477D01*
X1135339Y1233707D01*
Y1234121D01*
G01X820613Y744641D02*
Y742675D01*
X817005Y739067D01*
X747555D01*
X741374Y745248D01*
Y745965D01*
X740909Y746430D01*
Y754975D01*
G01X728909Y763779D02*
X732909D01*
G01X731467Y1045015D02*
Y1011125D01*
X733567Y1009025D01*
Y993475D01*
X732407Y992315D01*
Y767277D01*
X728909Y763779D01*
G01X751957Y1041755D02*
Y1012565D01*
X744057Y1004665D01*
Y764791D01*
X745009Y763839D01*
G01X740909Y760629D02*
X740372Y760092D01*
X737446D01*
X736909Y760629D01*
G01D02*
X736312Y760032D01*
X733506D01*
X732909Y760629D01*
G01X740909Y754975D02*
Y760629D01*
G01X736425Y770072D02*
X737702Y768795D01*
X738665Y768396D01*
X739699Y767362D01*
Y766798D01*
G01X744022Y1245932D02*
X748322D01*
X750890Y1248500D01*
G01X730328Y1254423D02*
Y1252644D01*
X729049Y1251365D01*
Y1249717D01*
X728957Y1249625D01*
G01X734111Y1254444D02*
X734090Y1254423D01*
X733480D01*
X732107Y1253050D01*
Y1249625D01*
G01X734967Y1252034D02*
X736474Y1253541D01*
X738638D01*
G01X744022Y1249082D02*
X745920D01*
X748630Y1251792D01*
G01X746100Y46262D02*
X748100D01*
X749477Y47639D01*
Y51970D01*
G01Y55120D02*
Y57932D01*
G01X745474Y55120D02*
Y57932D01*
G01X748820Y284562D02*
X754302Y279080D01*
Y275230D01*
X754393Y275139D01*
Y273490D01*
X754302Y273399D01*
G01X762590Y274028D02*
X758081D01*
X757452Y273399D01*
G01X764977Y298790D02*
X758412D01*
G01X755305Y298847D02*
Y305050D01*
X753835Y306520D01*
G01X748498Y309640D02*
X750655D01*
X753835Y312820D01*
G01X764977Y303908D02*
X757936D01*
G01X764977Y306467D02*
X761825D01*
X761020Y307272D01*
X758390D01*
G01D02*
X755992Y309670D01*
X753835D01*
G01X749650Y398532D02*
X748178Y400004D01*
Y404844D01*
G01X760645Y413212D02*
Y418212D01*
G01X748380Y429052D02*
X759220Y418212D01*
X760645D01*
G01X751220Y522362D02*
X748270Y519412D01*
Y512533D01*
X749516Y511287D01*
X751220D01*
G01X797720Y428412D02*
X796817Y429315D01*
Y435395D01*
X791600Y440612D01*
Y491182D01*
X780210Y502572D01*
Y509152D01*
X768000Y521362D01*
X757220D01*
X754220Y524362D01*
Y530462D01*
G01X838220Y459562D02*
Y486662D01*
X833620Y491262D01*
X827820D01*
X823620Y495462D01*
Y501262D01*
X792020Y532862D01*
X762220D01*
X759820Y530462D01*
G01X762562Y746444D02*
Y749247D01*
X760427Y751382D01*
Y1005845D01*
X766577Y1011995D01*
X837507D01*
X840851Y1015339D01*
Y1229802D01*
G01X823589Y746924D02*
X821663Y748850D01*
X768920D01*
X764262Y744192D01*
X760201D01*
X759269Y745124D01*
Y747493D01*
X757009Y749753D01*
Y760689D01*
G01X749009Y763839D02*
X745009D01*
G01X753009Y760689D02*
X752402Y760082D01*
X749616D01*
X749009Y760689D01*
G01X757009D02*
X756392Y760072D01*
X753626D01*
X753009Y760689D01*
G01X755841Y957546D02*
X753782D01*
X751997Y959331D01*
G01X755841Y954200D02*
X753716D01*
X751997Y952481D01*
G01X755841Y994357D02*
X751505Y990021D01*
Y987865D01*
G01X755541Y1057940D02*
X753402D01*
X751957Y1056495D01*
Y1041755D01*
G01X772570Y1245937D02*
X768420D01*
X766715Y1247642D01*
X763578D01*
X759518Y1243582D01*
X754047D01*
X752984Y1244645D01*
Y1246406D01*
X750890Y1248500D01*
G01X759237Y1253019D02*
X758252D01*
X755890Y1255381D01*
G01X759237Y1253019D02*
Y1255039D01*
X756953Y1257323D01*
X754296D01*
X753735Y1256762D01*
G01X753000Y1261352D02*
X754898Y1259454D01*
X758360D01*
X760242Y1257572D01*
G01X755841Y1252034D02*
X759149Y1248726D01*
Y1247626D01*
G01X755841Y1248688D02*
X755249D01*
X753656Y1250281D01*
G01X748630Y1251792D02*
Y1252769D01*
X750040Y1254179D01*
G01X757687Y1581783D02*
Y1584758D01*
X760112Y1587183D01*
G01X761716Y1661194D02*
X759829D01*
X758720Y1662303D01*
Y1664672D01*
X758758Y1664710D01*
Y1666366D01*
G01X763994Y1674691D02*
X762259D01*
X758758Y1671190D01*
Y1669516D01*
G01X774059Y68912D02*
X778259Y64712D01*
X810270D01*
X834165Y88607D01*
Y105461D01*
X842850Y114146D01*
Y138892D01*
X853297Y149339D01*
X870847D01*
X874847Y153339D01*
X905897D01*
X916228Y163670D01*
X930452Y169562D01*
X951020D01*
X953320Y171862D01*
X973064D01*
X981628Y163298D01*
X1006621D01*
X1007685Y164362D01*
X1018848D01*
X1028929Y154281D01*
Y144795D01*
X1044892Y128832D01*
X1066556D01*
X1080239Y115149D01*
X1106274D01*
X1133542Y87881D01*
X1163263D01*
X1186958Y64186D01*
X1281826D01*
X1289850Y56162D01*
X1344620D01*
X1359326Y70868D01*
Y109097D01*
X1349017Y119406D01*
Y120618D01*
G01X769895Y284264D02*
X766423D01*
X765320Y283161D01*
Y277462D01*
X766195Y276587D01*
X769895D01*
G01Y274028D02*
X762590D01*
G01X777420Y277962D02*
X776236Y279146D01*
X769895D01*
G01X780820Y278262D02*
X777377Y281705D01*
X769895D01*
G01X764977Y296231D02*
X769789D01*
G01X769895Y284264D02*
X784722D01*
X785220Y284762D01*
G01X764977Y301349D02*
X765110Y301482D01*
X769350D01*
X769860Y301992D01*
Y302462D01*
G01D02*
Y308122D01*
X768956Y309026D01*
X764977D01*
G01X775738Y432665D02*
Y433490D01*
X777170Y434922D01*
X782490D01*
X784730Y432682D01*
G01X774765Y474862D02*
X774565Y475062D01*
X772375D01*
G01D02*
X769675Y472362D01*
X764140D01*
X762915Y473587D01*
Y474862D01*
G01X772364Y475062D02*
X772375D01*
G01X762920Y501662D02*
X764759D01*
X765810Y502713D01*
Y506342D01*
G01X769745Y502600D02*
X767098Y499953D01*
X765227D01*
X762932Y497658D01*
G01X765521Y525364D02*
X796637D01*
X814334Y507667D01*
Y499532D01*
X814305Y499503D01*
G01X762570Y756052D02*
X765443Y753179D01*
X767112D01*
G01X826930Y752352D02*
X771089D01*
X770262Y753179D01*
G01X771724Y758337D02*
X771707Y758354D01*
X764872D01*
X762570Y756052D01*
G01X766125Y770072D02*
X769399Y766798D01*
G01X803116Y1244042D02*
X802856Y1243782D01*
X797906D01*
X796779Y1242655D01*
X783804D01*
X780522Y1245937D01*
X772570D01*
G01X791685Y1254319D02*
X791594Y1254410D01*
X789945D01*
X789854Y1254319D01*
X788729D01*
X785342Y1250932D01*
X775956D01*
X772596Y1254292D01*
X770970D01*
X767440Y1257822D01*
X765299D01*
X765049Y1257572D01*
X763392D01*
G01X766148Y1255882D02*
Y1252385D01*
X767053Y1251480D01*
G01D02*
X770177D01*
X772570Y1249087D01*
G01X768714Y1666366D02*
Y1664710D01*
X768676Y1664672D01*
Y1663591D01*
X766811Y1661726D01*
G01D02*
X764018D01*
X762632Y1663112D01*
Y1664719D01*
X762670Y1664757D01*
Y1666414D01*
G01X763994Y1674691D02*
Y1672544D01*
X762670Y1671220D01*
Y1669564D01*
G01X792895Y279146D02*
X798204D01*
G01X792895Y276587D02*
X801840D01*
G01X794220Y296062D02*
X792920D01*
X790192Y298790D01*
X787977D01*
G01X785220Y284762D02*
X787281Y286823D01*
X792895D01*
G01Y284264D02*
X793067Y284092D01*
X802070D01*
G01X787977Y311585D02*
X783663D01*
X782640Y310562D01*
Y304642D01*
X783490Y303792D01*
X787861D01*
X787977Y303908D01*
G01X845500Y281507D02*
X839135D01*
X837140Y283502D01*
Y287422D01*
X844440Y294722D01*
X854922D01*
X858925Y298725D01*
Y303440D01*
X863157Y307672D01*
Y311985D01*
X859390Y315752D01*
X796053D01*
X792943Y312642D01*
G01D02*
X791886Y311585D01*
X787977D01*
G01X794057Y301569D02*
X793837Y301349D01*
X787977D01*
G01Y309026D02*
X793896D01*
G01X793820Y304962D02*
X792315Y306467D01*
X787977D01*
G01X785560Y417902D02*
X783330Y415672D01*
X779650D01*
X778795Y416527D01*
Y418212D01*
G01X785720Y427862D02*
X783580Y425722D01*
X779520D01*
X778795Y424997D01*
Y423212D01*
G01X784730Y432682D02*
X784857Y432555D01*
X788432D01*
G01X791582D02*
Y435352D01*
G01X777915Y488862D02*
X782690D01*
G01X1253557Y1086495D02*
X1246667D01*
X1245157Y1088005D01*
X1226007D01*
X1222957Y1091055D01*
X1211327D01*
X1209727Y1089455D01*
X1196567D01*
X1192329Y1085217D01*
X1180195D01*
X1178927Y1086485D01*
X1174214D01*
X1173674Y1087025D01*
X1164310D01*
X1163580Y1086295D01*
X1156007D01*
X1152147Y1082435D01*
X1143947D01*
X1136277Y1074765D01*
Y1071175D01*
X1132987Y1067885D01*
X1131587D01*
X1128607Y1064905D01*
Y1048896D01*
X1127826Y1048115D01*
Y1016139D01*
X1120345Y1008658D01*
X1099807D01*
X1090957Y999808D01*
Y790525D01*
X1084307Y783875D01*
X1080591D01*
X1075307Y778591D01*
Y755931D01*
X941523Y622147D01*
X810651D01*
X789480Y600976D01*
Y590102D01*
X789720Y589862D01*
G01X1271087Y1093050D02*
X1268031D01*
X1267516Y1093565D01*
X1228897D01*
X1224937Y1097525D01*
X1209497D01*
X1207987Y1096015D01*
X1194617D01*
X1190917Y1092315D01*
X1179376D01*
X1178496Y1093195D01*
X1175072D01*
X1173802Y1094465D01*
X1164102D01*
X1162632Y1092995D01*
X1158222D01*
X1157842Y1092615D01*
X1149777D01*
X1148277Y1094115D01*
X1144467D01*
X1124587Y1074235D01*
Y1017231D01*
X1119034Y1011678D01*
X1098555D01*
X1086889Y1000012D01*
X1083857Y992691D01*
Y974865D01*
X1077437Y968445D01*
Y784993D01*
X1069867Y777423D01*
Y755041D01*
X986588Y671762D01*
X958220D01*
X953820Y667362D01*
Y638716D01*
X940351Y625247D01*
X809478D01*
X785220Y600989D01*
Y581362D01*
G01X1248000Y1089723D02*
X1240745D01*
X1240597Y1089575D01*
X1226677D01*
X1223387Y1092865D01*
X1210957D01*
X1210157Y1093665D01*
X1195067D01*
X1191557Y1090155D01*
X1179237D01*
X1178727Y1089645D01*
X1175589D01*
X1174919Y1088975D01*
X1163785D01*
X1162925Y1089835D01*
X1157795D01*
X1157045Y1090585D01*
X1150650D01*
X1144960Y1084895D01*
X1142427D01*
X1127097Y1069565D01*
Y1050605D01*
X1126227Y1049735D01*
Y1016735D01*
X1119660Y1010168D01*
X1099181D01*
X1088834Y999821D01*
X1085367Y991452D01*
Y973145D01*
X1081457Y969235D01*
Y786877D01*
X1073777Y779197D01*
Y756815D01*
X986824Y669862D01*
X958920D01*
X956320Y667262D01*
Y639080D01*
X940977Y623737D01*
X810104D01*
X787375Y601008D01*
Y589207D01*
X789220Y587362D01*
X789720D01*
G01X1265387Y1083345D02*
X1246717D01*
X1243567Y1086495D01*
X1225177D01*
X1224527Y1085845D01*
X1209597D01*
X1208347Y1087095D01*
X1197017D01*
X1192357Y1082435D01*
X1188647D01*
X1182087Y1075875D01*
X1179927D01*
X1179357Y1076445D01*
X1175244D01*
X1173614Y1078075D01*
X1164947D01*
X1163127Y1076255D01*
X1158257D01*
X1157897Y1075895D01*
X1150134D01*
X1149104Y1076925D01*
X1145397D01*
X1140797Y1072325D01*
Y1071020D01*
X1139511Y1069734D01*
X1138055D01*
X1134297Y1065976D01*
Y1049045D01*
X1132577Y1047325D01*
X1129867D01*
X1129336Y1046794D01*
Y1015513D01*
X1120971Y1007148D01*
X1100433D01*
X1095027Y1001742D01*
Y791618D01*
X1076817Y773408D01*
Y755305D01*
X942149Y620637D01*
X811277D01*
X791645Y601005D01*
Y593937D01*
X791720Y593862D01*
G01X1267471Y1060464D02*
X1242088D01*
X1239237Y1063315D01*
X1226487D01*
X1223347Y1066455D01*
X1210257D01*
X1207017Y1063215D01*
X1196887D01*
X1193607Y1059935D01*
X1189257D01*
X1185287Y1055965D01*
X1183027D01*
X1179877Y1052815D01*
X1173857D01*
X1170487Y1049445D01*
Y1044855D01*
X1169177Y1043545D01*
X1166377D01*
X1165517Y1042685D01*
Y1037485D01*
X1164117Y1036085D01*
X1157431D01*
X1155876Y1034530D01*
X1151292D01*
X1149807Y1033045D01*
Y1017535D01*
X1141417Y1009145D01*
Y999015D01*
X1138557Y996155D01*
X1130767D01*
X1124897Y990285D01*
Y879965D01*
X1120407Y875475D01*
Y773015D01*
X1119117Y771725D01*
X1116755D01*
X1113497Y768467D01*
Y757945D01*
X1116012Y755430D01*
Y742650D01*
X1113417Y740055D01*
X1063703D01*
X942755Y619107D01*
X811883D01*
X793720Y600944D01*
Y595862D01*
G01X793552Y758455D02*
X792612Y757515D01*
X788092D01*
X785952Y759655D01*
G01D02*
X783732Y761875D01*
X783507D01*
G01D02*
X782087D01*
X781108Y760896D01*
X778724D01*
G01X785952Y763855D02*
X788802Y766705D01*
X790840D01*
X793549Y763996D01*
G01X785952Y763855D02*
X784246D01*
X783735Y764366D01*
Y765482D01*
X782515Y766702D01*
G01D02*
X781347Y765534D01*
Y764804D01*
X779998Y763455D01*
X778724D01*
G01X785541Y957546D02*
X787666D01*
X789385Y959265D01*
G01X785541Y954200D02*
X787600D01*
X789385Y952415D01*
G01X785541Y994357D02*
X789877Y990021D01*
Y987865D01*
G01X785541Y1255381D02*
X783437Y1253277D01*
X781443D01*
G01X791685Y1257469D02*
X788943D01*
X787685Y1258727D01*
X783775D01*
X783130Y1259372D01*
G01X791685Y1254319D02*
X795028Y1257662D01*
X796488D01*
X801935Y1252215D01*
G01X785541Y1248688D02*
X788890D01*
G01X833120Y743392D02*
Y747092D01*
X835460Y749432D01*
X845770D01*
X852450Y756112D01*
X864670D01*
X867300Y758742D01*
Y771112D01*
X901000Y804812D01*
Y937872D01*
X867170Y971702D01*
Y1309192D01*
X859210Y1317152D01*
X822540D01*
X791260Y1348432D01*
Y1388662D01*
G01X802095Y139262D02*
X807495D01*
X808220Y139987D01*
G01X814570Y145952D02*
X817120Y143402D01*
Y138662D01*
X815820Y137362D01*
X810845D01*
X808220Y139987D01*
G01X802095Y144262D02*
X807095D01*
X808220Y143137D01*
G01X814531Y139851D02*
X814231D01*
X810920Y143162D01*
X808245D01*
X808220Y143137D01*
G01X801840Y276587D02*
X809856D01*
X810089Y276820D01*
G01X797924Y295488D02*
Y298358D01*
G01X812499Y299070D02*
X807838D01*
X805775Y297007D01*
G01D02*
X804256Y295488D01*
X801074D01*
G01X802070Y284092D02*
X809924D01*
X810143Y284311D01*
G01X803620Y302962D02*
X804953Y301629D01*
X812499D01*
G01X805870Y304812D02*
X806494Y304188D01*
X812499D01*
G01X799720Y300462D02*
X797824Y302358D01*
Y303188D01*
G01X800974D02*
Y308053D01*
G01D02*
X800965Y308062D01*
G01X800974Y308053D02*
X805139D01*
X805570Y307622D01*
G01D02*
X806445Y306747D01*
X812499D01*
G01X795920Y312662D02*
Y311262D01*
X797815Y309367D01*
Y308062D01*
G01X808797Y433350D02*
X808843Y433304D01*
Y428704D01*
G01X802790Y433832D02*
Y433042D01*
X807128Y428704D01*
X808843D01*
G01X805720Y432902D02*
Y435722D01*
X806498Y436500D01*
X808797D01*
G01X805445Y587582D02*
Y596600D01*
X817392Y608547D01*
X946113D01*
X1068181Y730615D01*
X1121406D01*
X1128443Y737652D01*
X1139930D01*
X1142017Y739739D01*
Y784185D01*
X1144657Y786825D01*
Y974295D01*
X1149967Y979605D01*
Y991125D01*
X1153267Y994425D01*
Y1003629D01*
X1160100Y1010462D01*
X1173984D01*
X1179697Y1016175D01*
Y1034095D01*
X1181257Y1035655D01*
X1182377D01*
X1184007Y1037285D01*
Y1040355D01*
X1190427Y1046775D01*
X1192637D01*
X1195767Y1049905D01*
X1210187D01*
X1210797Y1049295D01*
X1223807D01*
X1224587Y1050075D01*
X1241127D01*
X1245277Y1045925D01*
X1268680D01*
X1272741Y1041864D01*
X1277461D01*
G01X1284922Y1038464D02*
X1271141D01*
X1267948Y1041657D01*
X1242925D01*
X1241220Y1043362D01*
X1224920D01*
X1224300Y1042742D01*
X1210310D01*
X1210087Y1042965D01*
X1197172D01*
X1194409Y1040202D01*
X1190540D01*
X1187550Y1037212D01*
Y1034912D01*
X1185760Y1033122D01*
Y1016073D01*
X1177649Y1007962D01*
X1160941D01*
X1157580Y1004601D01*
Y791723D01*
X1148482Y782625D01*
X1146187D01*
X1144327Y780765D01*
Y738781D01*
X1140888Y735342D01*
X1129400D01*
X1122363Y728305D01*
X1069139D01*
X1061182Y720348D01*
X1061181D01*
X947070Y606237D01*
X818349D01*
X807945Y595833D01*
Y594362D01*
G01X803220D02*
Y601363D01*
X814124Y612267D01*
X944995D01*
X1066363Y733635D01*
X1121543D01*
X1125420Y737512D01*
Y747676D01*
X1131917Y754173D01*
Y764210D01*
X1133600Y765893D01*
Y785505D01*
X1136057Y787962D01*
Y981915D01*
X1137417Y983275D01*
X1138747D01*
X1140727Y985255D01*
G01X1115869Y760989D02*
X1119230Y757628D01*
Y740378D01*
X1115697Y736845D01*
X1065033D01*
X943755Y615567D01*
X812884D01*
X797200Y599883D01*
G01X796702Y758455D02*
Y761195D01*
G01X794157Y761295D02*
Y761575D01*
X796578Y763996D01*
X796699D01*
G01X799577Y760985D02*
Y758405D01*
X802620Y755362D01*
X809700D01*
X810850Y756512D01*
Y758756D01*
G01X794658Y770104D02*
X797417Y767345D01*
G01X820110Y1243537D02*
X814012D01*
X813507Y1244042D01*
X803116D01*
G01X819401Y1252919D02*
X817570D01*
X815946Y1251295D01*
X802855D01*
X801935Y1252215D01*
G01X794157Y1252034D02*
Y1248685D01*
G01X796280Y1254402D02*
Y1254028D01*
X803116Y1247192D01*
G01X845500Y273830D02*
X843128D01*
X841600Y272302D01*
Y269152D01*
X839190Y266742D01*
X818060D01*
X816850Y267952D01*
Y269902D01*
X818219Y271271D01*
X822500D01*
G01Y278948D02*
X825394D01*
X827410Y276932D01*
Y272882D01*
X825880Y271352D01*
X822581D01*
X822500Y271271D01*
G01X815060Y280072D02*
X816495Y281507D01*
X822500D01*
G01X813490Y273862D02*
X822468D01*
X822500Y273830D01*
G01X816220Y277162D02*
X816993Y276389D01*
X822500D01*
G01X810920Y280062D02*
X813239Y277743D01*
Y276820D01*
G01X829720Y292762D02*
X831220Y291262D01*
Y287502D01*
X827784Y284066D01*
X822500D01*
G01X813293Y284311D02*
Y287062D01*
G01X812499Y301629D02*
X812522Y301652D01*
X816380D01*
X817510Y302782D01*
Y308232D01*
X816436Y309306D01*
X812499D01*
G01X810720Y586862D02*
X811265Y587407D01*
Y594533D01*
X819094Y602362D01*
X947735D01*
X1062557Y717184D01*
X1062558D01*
X1070469Y725095D01*
X1123693D01*
X1130730Y732132D01*
X1142218D01*
X1147537Y737451D01*
Y761779D01*
X1149587Y763829D01*
Y777625D01*
X1152027Y780065D01*
X1155347D01*
X1156817Y778595D01*
X1164007D01*
X1165347Y779935D01*
Y991625D01*
X1166497Y992775D01*
X1168287D01*
X1178427Y1002915D01*
X1181326D01*
X1192687Y1014276D01*
Y1029626D01*
X1195466Y1032405D01*
X1209187D01*
X1210037Y1033255D01*
X1224357D01*
X1225157Y1032455D01*
X1243297D01*
X1260502Y1015250D01*
G01X1247301Y1022801D02*
X1244307Y1025795D01*
X1226547D01*
X1223067Y1029275D01*
X1211067D01*
X1207827Y1026035D01*
X1196897D01*
X1196037Y1025175D01*
Y1012935D01*
X1181907Y998805D01*
X1178977D01*
X1171417Y991245D01*
Y779465D01*
X1167027Y775075D01*
X1156467D01*
X1154460Y773068D01*
Y763026D01*
X1150747Y759313D01*
Y736121D01*
X1143548Y728922D01*
X1132060D01*
X1125023Y721885D01*
X1071800D01*
X948977Y599062D01*
X820600D01*
X815120Y593582D01*
G01X810850Y763874D02*
Y770272D01*
G01X822374Y757039D02*
X820657Y758756D01*
X818724D01*
G01X859100Y765425D02*
X862296D01*
X863617Y766746D01*
Y772995D01*
X860217Y776395D01*
X841667D01*
X839847Y774575D01*
X828027D01*
X826157Y776445D01*
X822447D01*
X820967Y774965D01*
Y770765D01*
X818724Y768522D01*
Y763874D01*
G01D02*
X814770D01*
G01X825425Y770072D02*
X828699Y766798D01*
G01X815241Y957546D02*
X817366D01*
X819085Y959265D01*
G01X815241Y954200D02*
X817300D01*
X819085Y952415D01*
G01X815241Y994357D02*
X819577Y990021D01*
Y987865D01*
G01X838020Y1232432D02*
X826640D01*
X820110Y1238962D01*
Y1243537D01*
G01X815241Y1255381D02*
X813372Y1253512D01*
X810908D01*
G01X812440Y1258727D02*
X816743D01*
X819401Y1256069D01*
G01Y1252919D02*
X819423Y1252941D01*
X819998D01*
X821135Y1254078D01*
Y1257933D01*
X821734Y1258532D01*
X825714D01*
X829093Y1255153D01*
Y1254181D01*
X830647Y1252627D01*
Y1246448D01*
X831310Y1245785D01*
X838217D01*
X839287Y1246855D01*
Y1248259D01*
X841203Y1250175D01*
X846572D01*
X847271Y1250874D01*
Y1253648D01*
G01X824268Y1256206D02*
X823418Y1255356D01*
Y1252493D01*
X823877Y1252034D01*
G01X815241Y1248688D02*
X811521D01*
G01X826501Y1254553D02*
X826100Y1254152D01*
Y1250041D01*
X825256Y1249197D01*
G01D02*
X822746Y1246687D01*
X820110D01*
G01X1216363Y1698605D02*
X1222155D01*
X1223600Y1697160D01*
Y1685710D01*
X1218730Y1680840D01*
Y1656159D01*
X1190150Y1627579D01*
Y1617805D01*
X1166750Y1594405D01*
X1131032D01*
X1127503Y1590876D01*
Y1557103D01*
X1123603Y1553203D01*
Y1522853D01*
X1113660Y1512910D01*
X1104550D01*
X1055810Y1464170D01*
Y1407160D01*
X1029832Y1381182D01*
X999322D01*
X952502Y1334362D01*
X826090D01*
G01X1194793Y1698295D02*
X1198493D01*
X1202578Y1694210D01*
X1214790D01*
X1216370Y1692630D01*
Y1687300D01*
X1201030Y1671960D01*
Y1646280D01*
X1191750Y1637000D01*
X1159310D01*
X1155330Y1633020D01*
Y1615180D01*
X1152200Y1612050D01*
X1135410D01*
X1124653Y1601293D01*
Y1558552D01*
X1120353Y1554252D01*
Y1531943D01*
X1108070Y1519660D01*
Y1517000D01*
X1106800Y1515730D01*
X1102360D01*
X1050810Y1464180D01*
Y1409232D01*
X1027760Y1386182D01*
X997250D01*
X950430Y1339362D01*
X826090D01*
G01X1162383Y1652505D02*
X1162268Y1652620D01*
X1158400D01*
X1154564Y1648784D01*
Y1645606D01*
X1137110Y1628152D01*
Y1621235D01*
X1120100Y1604225D01*
Y1559800D01*
X1115061Y1554761D01*
Y1540700D01*
X1095820Y1521459D01*
Y1518910D01*
X1042210Y1465300D01*
Y1410792D01*
X1024490Y1393072D01*
X993690D01*
X946880Y1346262D01*
X824540D01*
X823130Y1344852D01*
Y1332322D01*
X826090Y1329362D01*
G01Y1344362D02*
X948358D01*
X995178Y1391182D01*
X1025688D01*
X1045810Y1411304D01*
Y1465780D01*
X1097910Y1517880D01*
Y1520201D01*
X1116973Y1539264D01*
Y1554772D01*
X1121500Y1559299D01*
Y1602921D01*
X1136369Y1617790D01*
X1139930D01*
X1144040Y1621900D01*
Y1633050D01*
X1155990Y1645000D01*
Y1647560D01*
X1158670Y1650240D01*
X1171118D01*
X1173383Y1652505D01*
G01X1115802Y1615010D02*
X1118700Y1612112D01*
Y1560001D01*
X1113863Y1555164D01*
Y1542513D01*
X1093740Y1522390D01*
Y1520880D01*
X1040480Y1467620D01*
Y1411332D01*
X1024080Y1394932D01*
X993610D01*
X946400Y1347722D01*
X823380D01*
X820920Y1345262D01*
Y1344342D01*
G01X1074010Y1510650D02*
X1069060Y1505700D01*
Y1504092D01*
X1039250Y1474282D01*
Y1411842D01*
X1023570Y1396162D01*
X993100D01*
X945890Y1348952D01*
X821074D01*
X818420Y1346298D01*
Y1344342D01*
G01X842645Y220362D02*
X841720Y219437D01*
Y215937D01*
G01X837160Y218212D02*
X839435Y215937D01*
X841720D01*
G01X837160Y213207D02*
X836960Y213407D01*
X836205D01*
X833445Y216167D01*
Y223143D01*
G01X838820Y206872D02*
X841720Y209772D01*
Y212787D01*
G01X833445Y223143D02*
X837434D01*
X837500Y223077D01*
G01X847580Y232222D02*
X834610D01*
X833445Y231057D01*
Y226293D01*
G01X839450Y272662D02*
X843177Y276389D01*
X845500D01*
G01Y278948D02*
X840850D01*
G01X840063Y285022D02*
X841019Y284066D01*
X845500D01*
G01X827620Y302962D02*
X828846Y304188D01*
X835499D01*
G01Y311865D02*
X830417D01*
G01X835499Y301629D02*
X844250D01*
G01X835499Y309306D02*
X844100D01*
G01X831530Y651932D02*
X891878D01*
X918328Y678382D01*
X968944D01*
X1044127Y753565D01*
X1047065D01*
X1053749Y760249D01*
G01X849454Y761685D02*
X848166D01*
X846987Y760506D01*
Y755205D01*
X844134Y752352D01*
X826930D01*
G01X830587Y741205D02*
X828637Y739255D01*
X826497D01*
G01X838587Y766825D02*
X836787D01*
X834327Y769285D01*
G01D02*
X832667D01*
X832157Y768775D01*
Y766555D01*
X833120Y765592D01*
Y764094D01*
G01X859100Y769165D02*
X857457D01*
X855607Y767315D01*
Y765575D01*
X854987Y764955D01*
X844218D01*
X843357Y764094D01*
X840994D01*
G01X841827Y766795D02*
X840994Y765962D01*
Y764094D01*
G01Y758976D02*
X837127D01*
G01X844957Y763065D02*
Y757705D01*
X843737Y756485D01*
X833631D01*
X833120Y756996D01*
Y758976D01*
G01X840851Y1229802D02*
Y1234954D01*
X840651Y1235154D01*
Y1236811D01*
G01Y1239961D02*
X840743Y1239869D01*
X842737D01*
X845240Y1242372D01*
G01X840651Y1239961D02*
X840559Y1239869D01*
X838911D01*
X838819Y1239961D01*
X833207D01*
G01X842630Y1256912D02*
Y1252577D01*
X842445Y1252392D01*
G01X844997Y1248155D02*
X843587Y1246745D01*
X841747D01*
G01X1201600Y1633790D02*
X1196430Y1628620D01*
Y1622008D01*
X1180775Y1606353D01*
Y1600545D01*
X1173085Y1592855D01*
X1131675D01*
X1129053Y1590233D01*
Y1555952D01*
X1125153Y1552052D01*
Y1521623D01*
X1114920Y1511390D01*
X1105050D01*
X1058310Y1464650D01*
Y1406124D01*
X1030868Y1378682D01*
X1000358D01*
X953538Y1331862D01*
X832090D01*
G01Y1326862D02*
X955610D01*
X1002430Y1373682D01*
X1031150D01*
X1064250Y1406782D01*
Y1467912D01*
X1106131Y1509793D01*
X1360921D01*
X1394470Y1543342D01*
X1400160D01*
G01X1205563Y1698340D02*
X1208053Y1695850D01*
X1218920D01*
X1222290Y1692480D01*
Y1686253D01*
X1217420Y1681383D01*
Y1658960D01*
X1194310Y1635850D01*
X1183290D01*
X1180300Y1632860D01*
Y1614181D01*
X1171823Y1605704D01*
Y1601601D01*
X1165937Y1595715D01*
X1130489D01*
X1126193Y1591419D01*
Y1557592D01*
X1122293Y1553692D01*
Y1523113D01*
X1113555Y1514375D01*
X1103515D01*
X1053310Y1464170D01*
Y1408196D01*
X1028796Y1383682D01*
X998286D01*
X951466Y1336862D01*
X832090D01*
G01X1184383Y1652505D02*
X1180148Y1648270D01*
X1158900D01*
X1157420Y1646790D01*
Y1644810D01*
X1149790Y1637180D01*
Y1616540D01*
X1147000Y1613750D01*
X1134705D01*
X1122953Y1601998D01*
Y1558852D01*
X1118653Y1554552D01*
Y1532693D01*
X1108430Y1522470D01*
X1106210D01*
X1048310Y1464570D01*
Y1410268D01*
X1026724Y1388682D01*
X996214D01*
X949394Y1341862D01*
X832090D01*
G01X1040970Y128332D02*
X1025078Y144224D01*
Y150704D01*
X1022043Y153739D01*
X1011426D01*
X1007155Y158010D01*
X1001234D01*
X997793Y161451D01*
X980155D01*
X971644Y169962D01*
X954020D01*
X951720Y167662D01*
X930327D01*
X916983Y162135D01*
X905905Y151057D01*
X875793D01*
X871793Y147057D01*
X854015D01*
X848922Y141964D01*
Y115224D01*
X847660Y113962D01*
G01X853100Y113762D02*
X851560Y115302D01*
Y142002D01*
X854777Y145219D01*
X872555D01*
X876555Y149219D01*
X906667D01*
X918682Y161234D01*
X930097Y165962D01*
X952420D01*
X954920Y168462D01*
X970544D01*
X979230Y159776D01*
X996359D01*
X999773Y156362D01*
X1005909D01*
X1010301Y151970D01*
X1021212D01*
X1023240Y149942D01*
Y143922D01*
X1034229Y132933D01*
Y128953D01*
G01X845500Y281507D02*
X849005D01*
X849800Y280712D01*
Y274662D01*
X848950Y273812D01*
X845518D01*
X845500Y273830D01*
G01Y286625D02*
X850093D01*
G01X855480Y299692D02*
X853630Y301542D01*
X852806D01*
G01X852965Y308852D02*
X859920D01*
G01X844250Y301629D02*
X849569D01*
X849656Y301542D01*
G01X844100Y309306D02*
X849361D01*
X849815Y308852D01*
G01X860574Y445404D02*
Y450746D01*
X857605Y453715D01*
Y476017D01*
X874203Y492615D01*
Y509627D01*
X877039Y512463D01*
X889634D01*
X891858Y510239D01*
X897976D01*
X900227Y507988D01*
X902359D01*
X902999Y507348D01*
G01X844841Y957546D02*
X846966D01*
X848685Y959265D01*
G01X844841Y954200D02*
X846900D01*
X848685Y952415D01*
G01X849177Y987865D02*
Y990021D01*
X844841Y994357D01*
G01X845240Y1242372D02*
X845919Y1243051D01*
X849767D01*
G01X851867Y1256798D02*
X847271D01*
G01X844941Y1258727D02*
X846870Y1256798D01*
X847271D01*
G01X849767Y1249865D02*
Y1253138D01*
X849257Y1253648D01*
X847271D01*
G01X849767Y1246715D02*
Y1243051D01*
G01X933122Y246115D02*
X931383Y244376D01*
Y235675D01*
X927460Y231752D01*
X912000D01*
X910476Y233276D01*
X904801D01*
X874731Y203206D01*
Y195793D01*
X873200Y194262D01*
G01X867700Y268262D02*
X866851Y269111D01*
X863249D01*
X863140Y269220D01*
G01X859990D02*
X861852Y271082D01*
X864994D01*
X867237Y273325D01*
G01X861080Y459742D02*
X865051Y455771D01*
X900505D01*
X902875Y458141D01*
Y462837D01*
G01X927470Y815112D02*
X924658Y812300D01*
Y801500D01*
X880151Y756993D01*
X874155D01*
G01X922100Y181791D02*
X908821D01*
X905633Y184979D01*
X894387D01*
X890170Y180762D01*
Y174012D01*
X887520Y171362D01*
G01X917386Y184114D02*
X910097D01*
X907022Y187189D01*
X892317D01*
X887520Y182392D01*
Y176862D01*
G01X908620Y188899D02*
X884197D01*
X880411Y185113D01*
X875169D01*
G01X887590Y471552D02*
X876122Y483020D01*
Y508959D01*
X878069Y510906D01*
X883406D01*
X885185Y509127D01*
X895028D01*
X895556Y508599D01*
Y506875D01*
G01X899049Y501792D02*
Y501913D01*
X895940Y505022D01*
X892702D01*
X884900Y497220D01*
Y483016D01*
X898087Y469829D01*
Y465987D01*
G01X1400000Y1626362D02*
X1409862Y1616500D01*
X1451532D01*
X1455600Y1612432D01*
Y1593812D01*
X1455100Y1593312D01*
X1454940D01*
X1451280Y1589652D01*
Y1569372D01*
X1445690Y1563782D01*
X1422780D01*
X1419390Y1560392D01*
X1416260D01*
X1405630Y1549762D01*
Y1542292D01*
X1371816Y1508478D01*
X1106386D01*
X1066260Y1468352D01*
Y1405791D01*
X878410Y1217941D01*
Y1074602D01*
X907770Y1045242D01*
G01X906120Y261252D02*
X924710Y268952D01*
X947800D01*
X949660Y270812D01*
X991754D01*
X1012942Y292000D01*
Y294995D01*
G01X909190Y473392D02*
X907420Y471622D01*
Y469137D01*
G01X911520Y465987D02*
X907420D01*
G01X902875D02*
X898087D01*
G01X907420D02*
X902875D01*
G01X911340Y502872D02*
X910708D01*
X907953Y500117D01*
X906655D01*
G01X906149Y507348D02*
X907002Y508201D01*
X911361D01*
G01X906655Y503631D02*
X908056Y505032D01*
X913023D01*
X917278Y500777D01*
X918212D01*
G01X903505Y503631D02*
X901849D01*
X900100Y505380D01*
Y505492D01*
X899290Y506302D01*
X896730D01*
X896157Y506875D01*
X895556D01*
G01X903505Y500117D02*
X901803D01*
X901582Y500338D01*
X900503D01*
X899049Y501792D01*
G01X903505Y500117D02*
X905292Y498330D01*
X907528D01*
X908028Y497830D01*
Y494592D01*
X909009Y493611D01*
G01X912288Y472430D02*
X911520Y471662D01*
Y469137D01*
G01X912828Y498251D02*
Y496501D01*
X912159Y495832D01*
Y493611D01*
G01X918212Y497677D02*
X917397Y498492D01*
X916553D01*
X912173Y502872D01*
X911340D01*
G01X911361Y508201D02*
X912752D01*
X917623Y503330D01*
X918131D01*
G01X912828Y498251D02*
X911905D01*
X909984Y496330D01*
G01X924761Y523114D02*
X924707Y523060D01*
X921656D01*
X921585Y523131D01*
X921149D01*
G01X909600Y521162D02*
X912980Y517782D01*
X918670D01*
X920889Y520001D01*
X921129D01*
X921149Y519981D01*
G01X914500Y1663825D02*
X915346D01*
X917002Y1662169D01*
X918052D01*
X919488Y1660733D01*
G01X926120Y1671500D02*
X923240Y1674380D01*
Y1690429D01*
X918779Y1694890D01*
X918780D01*
G01X922320Y1666937D02*
Y1668560D01*
X918020Y1672860D01*
G01D02*
X917861D01*
X915621Y1675100D01*
Y1681731D01*
X918780Y1684890D01*
G01X914500Y1666975D02*
X918300D01*
G01X914500D02*
Y1671400D01*
G01X931500Y201612D02*
Y197612D01*
G01X923836Y193563D02*
X927056D01*
X928892Y195399D01*
X929287D01*
X931500Y197612D01*
G01X943369Y508153D02*
X941533Y509989D01*
X936300D01*
X935805Y510484D01*
Y512988D01*
X937643Y514826D01*
Y514925D01*
G01X1076598Y477087D02*
Y481750D01*
X1073002Y485346D01*
X983112D01*
X977812Y490646D01*
X953134D01*
X941135Y502645D01*
Y507526D01*
X940399Y508262D01*
X928920D01*
X928100Y509082D01*
Y516492D01*
X928393Y516785D01*
Y518516D01*
G01X926173Y512391D02*
Y514111D01*
X924761Y515523D01*
Y519964D01*
G01Y523114D02*
X925395Y523748D01*
X930606D01*
X931720Y524862D01*
G01X940550Y517400D02*
X940048Y517902D01*
X937810D01*
X933842Y513934D01*
Y512200D01*
X933740Y512098D01*
G01X928393Y521666D02*
X930477D01*
X930795Y521348D01*
X933095D01*
G01X945524Y515483D02*
X946132Y516952D01*
Y518583D01*
X944127Y523423D01*
X942330Y525220D01*
X938679D01*
X937471Y524012D01*
X934110D01*
X933186Y523088D01*
Y521439D01*
X933095Y521348D01*
G01X940140Y514925D02*
X937643D01*
G01X930590Y512098D02*
Y514289D01*
X933012Y516711D01*
G01X936245Y521348D02*
Y519944D01*
X933012Y516711D01*
G01X939970Y523263D02*
X938055Y521348D01*
X936245D01*
G01X944261Y517871D02*
X942237Y522762D01*
Y522763D01*
X941737Y523263D01*
X939970D01*
G01X941740Y512922D02*
X940593Y511775D01*
X937643D01*
G01X942610Y515350D02*
Y516565D01*
X942296Y518144D01*
X941481Y520113D01*
X939970D01*
G01X933979Y1663752D02*
Y1661327D01*
G01X929979Y1663787D02*
Y1661352D01*
G01X926120Y1666937D02*
Y1671500D01*
G01X929979Y1666937D02*
X926120D01*
G01X938220Y1666837D02*
X934044D01*
X933979Y1666902D01*
G01D02*
X933700Y1667181D01*
Y1671500D01*
G01D02*
X933400D01*
X928779Y1676121D01*
Y1684889D01*
X928780Y1684890D01*
G01X942100Y1666875D02*
X934100Y1674875D01*
Y1700210D01*
X938780Y1704890D01*
G01X946100Y1671800D02*
Y1677570D01*
X938780Y1684890D01*
G01X950660Y399472D02*
X955051D01*
X955122Y399401D01*
G01X949920Y404602D02*
X954176D01*
X955122Y403656D01*
G01X1081930Y477132D02*
Y478878D01*
X1073723Y487085D01*
X983833D01*
X978533Y492385D01*
X954330D01*
X943369Y503346D01*
Y505003D01*
G01X945100Y534464D02*
Y535098D01*
X946482Y536480D01*
Y540448D01*
X942720Y544210D01*
Y586139D01*
X1075253Y718672D01*
X1126953D01*
X1133853Y725572D01*
X1144738D01*
X1153957Y734791D01*
Y755799D01*
X1158077Y759919D01*
Y762400D01*
X1159078Y763401D01*
G01X953900Y1663725D02*
X956800D01*
G01X950100D02*
X953900D01*
G01X950100Y1666875D02*
X946100D01*
G01D02*
Y1671800D01*
G01X942100Y1671100D02*
Y1666875D01*
G01X962570Y282812D02*
X965940Y279442D01*
Y274492D01*
X967870Y272562D01*
X990450D01*
X991960Y274072D01*
Y276342D01*
X1008942Y293324D01*
Y294995D01*
G01X970730Y377872D02*
X970275Y378327D01*
Y380952D01*
G01X977949Y384205D02*
X973942Y388212D01*
X971551D01*
X969595Y386256D01*
X969431D01*
G01D02*
Y390302D01*
G01Y386256D02*
X969364Y386189D01*
G01X969431Y394178D02*
Y398138D01*
G01X972220Y386251D02*
X973425Y385046D01*
Y380952D01*
G01X956487Y394831D02*
X958272Y396616D01*
Y399401D01*
G01X974026Y398056D02*
X973944Y398138D01*
X969431D01*
G01X983629Y397628D02*
Y399452D01*
X981064Y402017D01*
X969375D01*
G01X965890Y405967D02*
X963579Y403656D01*
X958272D01*
G01X972379Y503716D02*
X972326Y503663D01*
X968355D01*
G01X970788Y501230D02*
X968355Y503663D01*
G01X960620Y503687D02*
X964318D01*
X964347Y503716D01*
G01Y501262D02*
Y503716D01*
G01X1536837Y965965D02*
X1588747Y914055D01*
Y791735D01*
X1583057Y786045D01*
Y777285D01*
X1556128Y750356D01*
X1543653Y720238D01*
X1539815Y714493D01*
X1502067Y676745D01*
Y660766D01*
X1487220Y645919D01*
Y625513D01*
X1473589Y611882D01*
X1399589D01*
X1356939Y569232D01*
X1309960D01*
X1249838Y544329D01*
X1212306D01*
X1190099Y522122D01*
X1098323D01*
X1092563Y516362D01*
X1034843D01*
X1033633Y517572D01*
X1022080D01*
X1020870Y516362D01*
X986736D01*
X971619Y513356D01*
X969351Y512416D01*
G01X957220Y582862D02*
Y598362D01*
X1075920Y717062D01*
X1127620D01*
X1134520Y723962D01*
X1145406D01*
X1157770Y736326D01*
Y745005D01*
X1158475Y746707D01*
X1175746Y763978D01*
X1177585D01*
X1177677Y764070D01*
G01X985499Y168753D02*
X985445Y168807D01*
Y175508D01*
G01X1007820Y229999D02*
X1003170Y225349D01*
Y204779D01*
X1004690Y203259D01*
Y190609D01*
X1001880Y187799D01*
X995720D01*
X986579Y178658D01*
X985445D01*
G01X1159460Y194090D02*
X1145830D01*
X1116538Y223382D01*
X1097900D01*
X1077020Y244262D01*
X1024755D01*
X1018038Y247044D01*
X996550Y268532D01*
X981470D01*
G01X988818Y346372D02*
X990334Y344856D01*
Y341799D01*
G01X980916Y384286D02*
X978220Y386982D01*
Y392862D01*
X974720Y396362D01*
Y397362D01*
X974026Y398056D01*
G01X988219Y412821D02*
X984254D01*
G01D02*
X980092D01*
G01X992345D02*
X988219D01*
G01X979240Y425212D02*
X983400Y421052D01*
X985079D01*
X988219Y417912D01*
Y415971D01*
G01X1526427Y1019785D02*
X1528741Y1017471D01*
Y989011D01*
X1585077Y932675D01*
X1596937D01*
X1598796Y930816D01*
Y782504D01*
X1593582Y777290D01*
Y775490D01*
X1587170Y769078D01*
Y748372D01*
X1578660Y739862D01*
X1561620D01*
X1559848Y738090D01*
X1550154Y714686D01*
X1546042Y708534D01*
X1511497Y673989D01*
Y657852D01*
X1496680Y643035D01*
Y621592D01*
X1477510Y602422D01*
X1403510D01*
X1360020Y558932D01*
X1312510D01*
X1254416Y534869D01*
X1216227D01*
X1194020Y512662D01*
X1100824D01*
X1089134Y500972D01*
X1015272D01*
X1008735Y507509D01*
X985573D01*
X980720Y512362D01*
G01X986400Y503200D02*
X1008300D01*
X1014500Y497000D01*
X1093600D01*
X1104900Y508300D01*
X1197900D01*
X1220300Y530700D01*
X1252741D01*
X1308751Y553900D01*
X1317100D01*
G01X990334Y341799D02*
X990364Y341829D01*
X999484D01*
G01X994689Y379348D02*
Y377332D01*
X993901Y376544D01*
G01X999440Y371782D02*
X1003575Y375917D01*
Y380862D01*
G01X991369Y408252D02*
X992345Y409228D01*
Y412821D01*
G01X997617Y412383D02*
X994956Y415044D01*
Y424327D01*
G01X990454Y421961D02*
Y422541D01*
X989425Y423570D01*
Y426445D01*
X989635Y426655D01*
G01D02*
X991647D01*
X993012Y425290D01*
Y421570D01*
G01X1001671Y422682D02*
Y419162D01*
G01D02*
X997225D01*
G01X1003220Y512862D02*
X1003510Y513152D01*
X1093894D01*
X1099030Y518288D01*
X1191688D01*
X1213895Y540495D01*
X1250325D01*
X1311084Y565662D01*
X1358792D01*
X1401178Y608048D01*
X1475178D01*
X1491054Y623924D01*
Y644961D01*
X1505297Y659204D01*
Y671325D01*
G01X1448620Y1556162D02*
X1446020Y1553562D01*
X1415120D01*
X1409920Y1548362D01*
Y1532562D01*
X1382828Y1505470D01*
X1109570D01*
X1070920Y1466820D01*
Y1364562D01*
X993020Y1286662D01*
Y784902D01*
X996797Y781125D01*
Y774799D01*
X995120Y773122D01*
G01X994942Y777055D02*
X990758Y781239D01*
Y1287599D01*
X1068658Y1365499D01*
Y1468369D01*
X1107169Y1506880D01*
X1381039D01*
X1407658Y1533499D01*
Y1549299D01*
X1414183Y1555824D01*
X1424782D01*
X1425620Y1556662D01*
G01X1002070Y1256942D02*
Y1255702D01*
X1003903Y1253869D01*
X1006660D01*
G01X1003841Y1262074D02*
X1004800Y1261115D01*
X1005577D01*
X1006897Y1262435D01*
G01X996320Y1280683D02*
X996999Y1281362D01*
X1000432D01*
X1015707Y1296637D01*
Y1297993D01*
X1018056Y1300342D01*
X1018778D01*
X1019884Y1299236D01*
X1020606D01*
X1021659Y1300289D01*
Y1301011D01*
X1020553Y1302117D01*
Y1302839D01*
X1077920Y1360206D01*
Y1446462D01*
X1129625Y1498167D01*
X1397321D01*
X1435810Y1459678D01*
Y1455952D01*
X1434720Y1454862D01*
G01X1440440Y1454892D02*
X1437520Y1457812D01*
Y1460388D01*
X1423435Y1474473D01*
X1423434D01*
X1398030Y1499877D01*
X1128916D01*
X1076210Y1447171D01*
Y1360915D01*
X1013872Y1298577D01*
Y1297262D01*
X999682Y1283072D01*
X997310D01*
X996320Y1284062D01*
G01X1008120Y198293D02*
X1010697D01*
X1012755Y196235D01*
Y194609D01*
G01X1019585D02*
Y196884D01*
X1017360Y199109D01*
G01D02*
X1015905Y197654D01*
Y194609D01*
G01X1019355Y218423D02*
X1016606D01*
X1016436Y218253D01*
X1014780D01*
G01X1021118Y294290D02*
X1020069Y295339D01*
Y299838D01*
G01X1008942Y298145D02*
X1012942D01*
G01X1015520Y302862D02*
X1012942Y300284D01*
Y298145D01*
G01X1024099Y299838D02*
X1020069D01*
G01X1017720Y307787D02*
Y302287D01*
X1020069Y299938D01*
Y299838D01*
G01X1013720Y307787D02*
Y304662D01*
X1015520Y302862D01*
G01X1009800Y343800D02*
X1010900Y342700D01*
X1081700D01*
X1123300Y384300D01*
X1214000D01*
X1229900Y368400D01*
X1303100D01*
X1306200Y371500D01*
X1395800D01*
X1451700Y315600D01*
Y297600D01*
X1454700Y294600D01*
Y282100D01*
X1458000Y278800D01*
Y276200D01*
X1463200Y271000D01*
X1501000D01*
X1542200Y229800D01*
Y190600D01*
X1539200Y187600D01*
Y170300D01*
X1518575Y149675D01*
Y138662D01*
G01X1015688Y420548D02*
Y416974D01*
G01X1010420Y416062D02*
X1011332Y416974D01*
X1015688D01*
G01X1508067Y664655D02*
Y659094D01*
X1493090Y644117D01*
Y623080D01*
X1476022Y606012D01*
X1402022D01*
X1358801Y562791D01*
X1311469D01*
X1252726Y538459D01*
X1214739D01*
X1192532Y516252D01*
X1099874D01*
X1092344Y508722D01*
X1035830D01*
X1032848Y505740D01*
X1016076D01*
X1010884Y510932D01*
X1005520D01*
G01X1256097Y914995D02*
X1240637D01*
X1238818Y916814D01*
X1236497D01*
X1231428Y911745D01*
X1227977D01*
X1225278Y909046D01*
Y761935D01*
X1225644Y761569D01*
Y752668D01*
X1231347Y746965D01*
Y742515D01*
X1188581Y699749D01*
X1081998D01*
X1008560Y626311D01*
Y589682D01*
G01X1016220Y590862D02*
X1013760Y593322D01*
Y596538D01*
X1013805Y596583D01*
Y623897D01*
X1083980Y694072D01*
X1190280D01*
X1236860Y740652D01*
Y758890D01*
X1235360Y760390D01*
G01X1264570Y891259D02*
X1242010Y868699D01*
Y780065D01*
X1241640Y779695D01*
Y766188D01*
X1239257Y763805D01*
Y739365D01*
X1191334Y691442D01*
X1084900D01*
X1016360Y622902D01*
Y594682D01*
G01X1019000Y601042D02*
Y622274D01*
X1085141Y688415D01*
X1191697D01*
X1242398Y739116D01*
Y751242D01*
G01X1011160Y594682D02*
Y625002D01*
X1083150Y696992D01*
X1189384D01*
X1233937Y741545D01*
Y758967D01*
X1235360Y760390D01*
G01X1005960Y594682D02*
Y627092D01*
X1080927Y702059D01*
X1176181D01*
X1216057Y741935D01*
Y748025D01*
X1223327Y755295D01*
Y757615D01*
G01X1012769Y766798D02*
X1007444D01*
G01X1023203Y989083D02*
Y991137D01*
X1019983Y994357D01*
G01X1032030Y1251503D02*
Y1250883D01*
X1031180Y1250033D01*
Y1244189D01*
X1029771Y1242780D01*
X1019300D01*
X1017530Y1244550D01*
Y1247262D01*
X1017900Y1247632D01*
G01D02*
X1016300D01*
X1015540Y1246872D01*
X1011620D01*
X1009810Y1248682D01*
Y1253869D01*
G01X1019983Y1255381D02*
X1018865Y1254263D01*
X1016980D01*
G01X1015170Y1249722D02*
Y1251621D01*
X1016980Y1253431D01*
Y1254263D01*
G01X1019983Y1252034D02*
X1022835D01*
G01X1019983Y1248688D02*
X1023012Y1245659D01*
G01X1031153Y390152D02*
X1031343Y389962D01*
X1035688D01*
G01X1024154Y601152D02*
Y622024D01*
X1085665Y683535D01*
X1204167D01*
X1252847Y732215D01*
Y738220D01*
G01X1029630Y601252D02*
Y620964D01*
X1087581Y678915D01*
X1210262D01*
X1259998Y728651D01*
Y732442D01*
G01X1021654Y606302D02*
Y622792D01*
X1084707Y685845D01*
X1192577D01*
X1247060Y740328D01*
Y754385D01*
X1248657Y755982D01*
X1249122D01*
G01X1026654Y596152D02*
Y621256D01*
X1086623Y681225D01*
X1207615D01*
X1256193Y729803D01*
Y730590D01*
G01X1033260Y601272D02*
Y621327D01*
X1088288Y676355D01*
X1213157D01*
X1266220Y729418D01*
Y736432D01*
X1269310Y739522D01*
Y744908D01*
X1272397Y747995D01*
X1273719D01*
X1274198Y747516D01*
G01X1035760Y592952D02*
X1033960Y594752D01*
Y597882D01*
X1035760Y599682D01*
Y608732D01*
X1036050Y609022D01*
Y620612D01*
X1089260Y673822D01*
X1215416D01*
X1268830Y727236D01*
Y735602D01*
X1271830Y738602D01*
Y744538D01*
X1273357Y746065D01*
Y746675D01*
X1274198Y747516D01*
G01X1053745Y742341D02*
X1052098Y740694D01*
X1051295D01*
X1045270Y734669D01*
X1036954D01*
G01X1033441Y766798D02*
X1037144D01*
G01X1032527Y959265D02*
X1030808Y957546D01*
X1028683D01*
G01X1032063Y950820D02*
X1028683Y954200D01*
G01X1069216Y1251277D02*
X1061491Y1243552D01*
X1054783D01*
X1051120Y1247215D01*
X1046227D01*
X1045934Y1246922D01*
X1037919D01*
X1033338Y1251503D01*
X1032030D01*
G01X1030830Y1261302D02*
Y1260752D01*
X1029700Y1259622D01*
X1025344D01*
X1022666Y1256944D01*
G01X1025816D02*
X1026644Y1257772D01*
X1028200D01*
X1028560Y1258132D01*
X1031630D01*
X1036194Y1253568D01*
X1040735D01*
X1044448Y1249855D01*
X1051070D01*
X1052504Y1251289D01*
Y1254086D01*
G01X1030270Y1256042D02*
X1028880Y1254652D01*
Y1251503D01*
G01X1514741Y921964D02*
X1526591D01*
X1534268Y918784D01*
X1554080Y898972D01*
Y781408D01*
X1537285Y764613D01*
X1525655Y736533D01*
X1481047Y691925D01*
X1476689D01*
X1471428Y689746D01*
X1464527Y682845D01*
X1460077D01*
X1455528Y684729D01*
X1453401D01*
X1427459Y658787D01*
X1373495Y636438D01*
X1340767Y603710D01*
X1265064Y572352D01*
X1051230D01*
X1040720Y582862D01*
Y591862D01*
G01X1526000Y745162D02*
X1522477Y736656D01*
X1480090Y694235D01*
X1476229D01*
X1470119Y691705D01*
X1463570Y685155D01*
X1460537D01*
X1455988Y687039D01*
X1451749D01*
X1425450Y660740D01*
X1372438Y638780D01*
X1340122Y606464D01*
X1263346Y574662D01*
X1052920D01*
X1045720Y581862D01*
Y591672D01*
G01X1038260Y601272D02*
Y607822D01*
X1039050Y608612D01*
Y620091D01*
X1090381Y671422D01*
X1216283D01*
X1271280Y726419D01*
Y734663D01*
X1273257Y736640D01*
G01X1043260Y601272D02*
Y603128D01*
X1044622Y604490D01*
Y618684D01*
X1091873Y665935D01*
X1218473D01*
X1281627Y729089D01*
Y739560D01*
X1280797Y740390D01*
G01X1045760Y596272D02*
Y602202D01*
X1046630Y603072D01*
Y617051D01*
X1092531Y662952D01*
X1219419D01*
X1283610Y727143D01*
Y740923D01*
X1284797Y742110D01*
G01X1048260Y601272D02*
X1048340Y601192D01*
X1051390D01*
X1052510Y602312D01*
Y605392D01*
X1049180Y608722D01*
Y616172D01*
X1092960Y659952D01*
X1221150D01*
X1286080Y724882D01*
Y740827D01*
X1284797Y742110D01*
G01X1051680Y614772D02*
X1094253Y657345D01*
X1222987D01*
X1287810Y722168D01*
Y733818D01*
X1289817Y735825D01*
Y740995D01*
G01X1057749Y760249D02*
X1057212Y759712D01*
X1054286D01*
X1053749Y760249D01*
G01X1047010Y1259222D02*
Y1255241D01*
X1046482Y1254713D01*
G01X1057047Y1256865D02*
X1054557D01*
X1054186Y1257236D01*
X1052504D01*
G01X1049683Y1258727D02*
X1051174Y1257236D01*
X1052504D01*
G01X1082030Y1254277D02*
Y1251481D01*
X1080706Y1250157D01*
X1074582D01*
X1070277Y1254462D01*
X1052880D01*
X1052504Y1254086D01*
G01X1172310Y584562D02*
X1169340Y581592D01*
X1078872D01*
X1060720Y599744D01*
Y613382D01*
X1097340Y650002D01*
X1231960D01*
X1260520Y678562D01*
X1278574D01*
X1307720Y707708D01*
Y740113D01*
X1305277Y742556D01*
Y749720D01*
G01X1058220Y585862D02*
Y614412D01*
X1095420Y651612D01*
X1225370D01*
X1292694Y718936D01*
X1296945D01*
X1300347Y722338D01*
Y733510D01*
X1298480Y735377D01*
Y738633D01*
X1300317Y740470D01*
G01X1061470Y585862D02*
Y582975D01*
X1067473Y576972D01*
X1259973D01*
X1340819Y610460D01*
X1371077Y640718D01*
X1424141Y662699D01*
X1448592Y687150D01*
Y691330D01*
X1453877Y696615D01*
X1457072D01*
X1463567Y693925D01*
X1469191D01*
X1475686Y696615D01*
X1478727D01*
X1517575Y735463D01*
Y741355D01*
G01X1056220Y605052D02*
X1055200Y606072D01*
Y614761D01*
X1094864Y654425D01*
X1224870D01*
X1292307Y721862D01*
X1296334D01*
X1297927Y723455D01*
Y726320D01*
X1295947Y728300D01*
G01X1065749Y763399D02*
X1061749D01*
G01X1093172Y1011260D02*
X1083613Y1001701D01*
X1082198Y998284D01*
X1080269Y996355D01*
X1077807D01*
X1074187Y992735D01*
Y792375D01*
X1066117Y784305D01*
Y763767D01*
X1065749Y763399D01*
G01X1061749Y760249D02*
X1061192Y759692D01*
X1058306D01*
X1057749Y760249D01*
G01X1061867Y774038D02*
X1060557Y772728D01*
Y769382D01*
X1063141Y766798D01*
G01X1062227Y959265D02*
X1060508Y957546D01*
X1058383D01*
G01X1062123Y950460D02*
X1058383Y954200D01*
G01Y994357D02*
X1061837D01*
G01X1069216Y1251277D02*
Y1248478D01*
X1071660Y1246034D01*
X1073219D01*
X1076204Y1243049D01*
X1089796D01*
X1090314Y1243567D01*
Y1246759D01*
X1090273Y1246800D01*
G01X1058383Y1248688D02*
X1055531D01*
G01X1059410Y1252272D02*
X1060405Y1251277D01*
X1066066D01*
G01X1573246Y306650D02*
X1569510D01*
X1542754Y333406D01*
Y346579D01*
X1507875Y381458D01*
Y424976D01*
X1495919Y436932D01*
X1461302D01*
X1458833Y434463D01*
X1442827D01*
X1400173Y391809D01*
X1120814D01*
X1088203Y359198D01*
X1079652D01*
X1076353Y362497D01*
Y363966D01*
G01X1572396Y309450D02*
X1570246D01*
X1545254Y334442D01*
Y347615D01*
X1510375Y382494D01*
Y426012D01*
X1496885Y439502D01*
X1460336D01*
X1457797Y436963D01*
X1441791D01*
X1399137Y394309D01*
X1119778D01*
X1087167Y361698D01*
X1080688D01*
X1078853Y363533D01*
Y363966D01*
G01X1073250Y582332D02*
X1073420D01*
X1076470Y579282D01*
X1171920D01*
X1180000Y587362D01*
X1182699D01*
X1185744Y584317D01*
X1205525D01*
X1210880Y589672D01*
X1268355D01*
X1293304Y600006D01*
X1359399Y666101D01*
X1384393D01*
X1391999Y673707D01*
X1404849D01*
X1422473Y691331D01*
X1438555D01*
X1452767Y705543D01*
Y708071D01*
X1453985Y709289D01*
X1455706D01*
X1456922Y708073D01*
X1475049D01*
X1492672Y725696D01*
Y741263D01*
X1496649Y745240D01*
X1499267D01*
G01X1084376Y774754D02*
X1082657Y773035D01*
Y764693D01*
X1083296Y764054D01*
G01X1097749Y779005D02*
X1086328Y767584D01*
Y764922D01*
X1087196Y764054D01*
G01X1265784Y1076853D02*
X1248269D01*
X1242527Y1082595D01*
X1227307D01*
X1226407Y1083495D01*
X1208377D01*
X1207477Y1082595D01*
X1195976D01*
X1193166Y1079785D01*
X1189356D01*
X1182926Y1073355D01*
X1179097D01*
X1178647Y1072905D01*
X1175287D01*
X1174917Y1072535D01*
X1163797D01*
X1163217Y1073115D01*
X1156857D01*
X1156577Y1073395D01*
X1149767D01*
X1141747Y1065375D01*
Y1054855D01*
X1136607Y1049715D01*
Y1047285D01*
X1133357Y1044035D01*
Y1016205D01*
X1121990Y1004838D01*
X1101390D01*
X1097337Y1000785D01*
Y785075D01*
X1088827Y776565D01*
X1086187D01*
X1084376Y774754D01*
G01X1084703Y960926D02*
X1088083Y957546D01*
G01Y954200D02*
X1085958D01*
X1084239Y952481D01*
G01X1079383Y994357D02*
Y991721D01*
X1077607Y989945D01*
Y986295D01*
X1079367Y984535D01*
G01X1076520Y1259072D02*
Y1254845D01*
X1076179Y1254504D01*
G01X1079383Y1258727D02*
X1080683Y1257427D01*
X1082030D01*
G01X1086613Y1256826D02*
X1084313D01*
X1083712Y1257427D01*
X1082030D01*
G01Y1254277D02*
X1098836D01*
X1103550Y1249563D01*
Y1245682D01*
X1104601Y1244631D01*
G01X1088083Y1248688D02*
X1087626D01*
X1084140Y1245202D01*
G01X1253863Y1071764D02*
X1253819D01*
Y1071765D01*
X1247537D01*
X1240117Y1079185D01*
X1226347D01*
X1225077Y1080455D01*
X1209948D01*
X1208018Y1078525D01*
X1197967D01*
X1192977Y1073535D01*
X1189632D01*
X1182977Y1066880D01*
X1179923D01*
X1179238Y1066195D01*
X1172976D01*
X1172426Y1065645D01*
X1165236D01*
X1164476Y1066405D01*
X1159057D01*
X1153627Y1060975D01*
X1152887D01*
X1149187Y1057275D01*
X1147057D01*
X1144917Y1055135D01*
Y1047905D01*
X1140327Y1043315D01*
X1137457D01*
X1136337Y1042195D01*
Y1016036D01*
X1120773Y1000472D01*
X1116599D01*
X1107157Y991030D01*
Y772125D01*
X1102967Y767935D01*
X1098857D01*
X1094893Y771899D01*
X1092213D01*
X1090547Y770233D01*
Y764603D01*
X1091096Y764054D01*
G01X1098896D02*
X1094996D01*
G01X1288529Y1069460D02*
X1247191D01*
X1239126Y1077525D01*
X1224886D01*
X1223576Y1076215D01*
X1209417D01*
X1209067Y1076565D01*
X1204377D01*
X1200647Y1072835D01*
X1195867D01*
X1191227Y1068195D01*
X1189137D01*
X1183447Y1062505D01*
X1180127D01*
X1179577Y1063055D01*
X1173167D01*
X1172307Y1063915D01*
X1165357D01*
X1164297Y1062855D01*
X1160117D01*
X1149357Y1052095D01*
Y1047291D01*
X1146721Y1044655D01*
X1146577D01*
X1140682Y1038760D01*
Y1016870D01*
X1131569Y1007757D01*
X1130060D01*
X1121475Y999172D01*
X1116869D01*
X1111498Y993801D01*
Y773096D01*
X1108237Y769835D01*
X1106677D01*
X1103297Y766455D01*
X1101297D01*
X1098896Y764054D01*
G01X1095199Y768537D02*
X1095028D01*
X1093266Y766775D01*
X1092709D01*
G01X1259335Y1074313D02*
X1248449D01*
X1241917Y1080845D01*
X1227307D01*
X1225837Y1082315D01*
X1208777D01*
X1207307Y1080845D01*
X1197828D01*
X1192232Y1075249D01*
X1188931D01*
X1183067Y1069385D01*
X1179077D01*
X1178707Y1069755D01*
X1174107D01*
X1173157Y1070705D01*
X1164707D01*
X1163567Y1069565D01*
X1156787D01*
X1153957Y1066735D01*
X1150449D01*
X1143677Y1059963D01*
Y1048235D01*
X1140927Y1045485D01*
X1137398D01*
X1134772Y1042859D01*
Y1016049D01*
X1120348Y1001625D01*
X1115667D01*
X1110497Y996455D01*
X1100997D01*
X1098447Y993905D01*
Y779703D01*
X1097749Y779005D01*
G01X1117783Y1057940D02*
X1115167Y1055324D01*
Y1018745D01*
X1112987Y1016565D01*
X1112907D01*
X1111667Y1015325D01*
X1097237D01*
X1093172Y1011260D01*
G01X1090273Y1246800D02*
X1093775D01*
X1095456Y1248481D01*
Y1251318D01*
X1095547Y1251409D01*
G01X1088262Y1252293D02*
X1089175Y1251380D01*
X1090712D01*
X1090741Y1251409D01*
X1092397D01*
G01X1106696Y764054D02*
X1102796D01*
G01X1260341Y1067280D02*
X1253819D01*
Y1067281D01*
X1246511D01*
X1240927Y1072865D01*
X1224587D01*
X1222987Y1074465D01*
X1211057D01*
X1208877Y1072285D01*
X1203007D01*
X1201577Y1070855D01*
X1196607D01*
X1192267Y1066515D01*
X1189468D01*
X1184055Y1061102D01*
X1180204D01*
X1178607Y1059505D01*
X1165018D01*
X1164828Y1059695D01*
X1158677D01*
X1155767Y1056785D01*
Y1048315D01*
X1154697Y1047245D01*
X1151987D01*
X1148287Y1043545D01*
X1147037D01*
X1142087Y1038595D01*
Y1016635D01*
X1132099Y1006647D01*
X1130520D01*
X1121660Y997787D01*
X1117054D01*
X1112608Y993341D01*
Y772556D01*
X1108605Y768553D01*
X1107945D01*
X1106696Y767304D01*
Y764054D01*
G01X1277419Y1062985D02*
X1253819D01*
Y1062986D01*
X1245636D01*
X1238417Y1070205D01*
X1225537D01*
X1224867Y1069535D01*
X1209377D01*
X1208877Y1070035D01*
X1204617D01*
X1200147Y1065565D01*
X1194677D01*
X1191927Y1062815D01*
X1188446D01*
X1185397Y1059766D01*
X1180958D01*
X1179437Y1058245D01*
X1168927D01*
X1164997Y1054315D01*
Y1045855D01*
X1161937Y1042795D01*
X1159587D01*
X1157557Y1040765D01*
X1150157D01*
X1143537Y1034145D01*
Y1016502D01*
X1132572Y1005537D01*
X1130980D01*
X1122120Y996677D01*
X1117514D01*
X1113718Y992881D01*
Y772096D01*
X1110838Y769216D01*
Y766070D01*
X1110680Y765912D01*
Y764216D01*
G01X1115869Y760989D02*
X1119869D01*
G01X1121627Y959265D02*
X1119908Y957546D01*
X1117783D01*
G01X1121523Y950460D02*
X1117783Y954200D01*
G01Y994357D02*
X1121237D01*
G01X1103530Y1263602D02*
Y1262972D01*
X1107830Y1258672D01*
Y1255883D01*
X1106753Y1254806D01*
X1105717D01*
G01X1106740Y1267902D02*
Y1262782D01*
X1111904Y1257618D01*
Y1257270D01*
G01Y1254120D02*
X1114102D01*
X1114773Y1253449D01*
X1116832D01*
G01X1104601Y1244631D02*
X1105879D01*
X1111904Y1250656D01*
Y1254120D01*
G01X1116832Y1257449D02*
Y1256599D01*
X1119982Y1253449D01*
G01X1117783Y1248688D02*
X1114448Y1245353D01*
G01X1124120Y643762D02*
X1147080Y620802D01*
X1215275D01*
X1262527Y668054D01*
X1280637D01*
X1324720Y712137D01*
Y727362D01*
X1322838Y729244D01*
X1321816D01*
G01X1133720Y642862D02*
Y640362D01*
X1145310Y628772D01*
X1221250D01*
X1261942Y669464D01*
X1280052D01*
X1321816Y711228D01*
Y726094D01*
G01X1129420Y644062D02*
X1130820Y645462D01*
X1170620D01*
X1177920Y638162D01*
X1222666D01*
X1261266Y676762D01*
X1279320D01*
X1309520Y706962D01*
Y743362D01*
X1308847Y744035D01*
Y749720D01*
G01X1127869Y764139D02*
X1123869D01*
G01X1232107Y1057940D02*
X1228501D01*
X1226746Y1059695D01*
X1209318D01*
X1206898Y1057275D01*
X1197007D01*
X1196057Y1056325D01*
X1193007D01*
X1191157Y1054475D01*
X1189058D01*
X1183912Y1049329D01*
X1182661D01*
X1179467Y1046135D01*
X1174227D01*
X1173717Y1045625D01*
Y1042745D01*
X1170267Y1039295D01*
Y1033605D01*
X1168227Y1031565D01*
X1165697D01*
X1163517Y1029385D01*
X1155891D01*
X1154627Y1028121D01*
Y1017475D01*
X1144717Y1007565D01*
Y997325D01*
X1139082Y991690D01*
X1137022D01*
X1134047Y988715D01*
X1129697D01*
X1128437Y987455D01*
Y773715D01*
X1127869Y773147D01*
Y764139D01*
G01X1123869Y760989D02*
X1119869D01*
G01X1125194Y768709D02*
X1123810D01*
X1122541Y767440D01*
Y766798D01*
G01X1135339Y1237271D02*
X1127069D01*
G01D02*
Y1238713D01*
X1124417Y1241365D01*
Y1242785D01*
X1120920Y1246282D01*
G01X1135036Y1251483D02*
X1134945Y1251392D01*
Y1249743D01*
X1135165Y1249523D01*
Y1245847D01*
X1138880Y1242132D01*
X1146990D01*
X1149282Y1244424D01*
Y1246638D01*
X1149903Y1247259D01*
G01X1135750Y1255672D02*
Y1253822D01*
X1135165Y1253237D01*
Y1251612D01*
X1135036Y1251483D01*
G01X1120920Y1246282D02*
X1119982Y1247220D01*
Y1253449D01*
G01X1133200Y1255702D02*
X1131978Y1254480D01*
Y1251575D01*
X1131886Y1251483D01*
G01X1550487Y681565D02*
X1537575D01*
X1522196Y666186D01*
Y652659D01*
X1507440Y637903D01*
Y616194D01*
X1482424Y591178D01*
X1407035D01*
X1362769Y546912D01*
X1318859D01*
X1260106Y522575D01*
X1222169D01*
X1193166Y493572D01*
X1142454D01*
X1136051Y499975D01*
Y503324D01*
G01X1550320Y696562D02*
Y696560D01*
X1520373Y666613D01*
Y653415D01*
X1505617Y638659D01*
Y616950D01*
X1481668Y593001D01*
X1406279D01*
X1362013Y548735D01*
X1316092D01*
X1257340Y524398D01*
X1221413D01*
X1192410Y495395D01*
X1143209D01*
X1138551Y500053D01*
Y503324D01*
G01X1138500Y586362D02*
X1141085Y588947D01*
X1145467D01*
G01X1142967Y592097D02*
X1145467D01*
G01X1149467D02*
X1153467D01*
G01X1145467D02*
X1149467D01*
G01X1149562Y599122D02*
X1149567Y599117D01*
X1153477D01*
G01X1149552Y606082D02*
X1149557Y606087D01*
X1153537D01*
G01X1140697Y608762D02*
Y602422D01*
X1140912Y602207D01*
G01D02*
X1143997Y599122D01*
X1146412D01*
G01X1150140Y610362D02*
X1149117D01*
X1146402Y607647D01*
Y606082D01*
G01X1153477Y595967D02*
X1142502D01*
X1137887Y600582D01*
Y610736D01*
X1145343Y618192D01*
X1216357D01*
X1261909Y663744D01*
X1285419D01*
X1330610Y708935D01*
Y730471D01*
X1328745Y732336D01*
G01X1153537Y602937D02*
X1144342D01*
X1143507Y603772D01*
Y608444D01*
X1148035Y612972D01*
X1220030D01*
X1263420Y656362D01*
X1289619D01*
X1337697Y704440D01*
Y728652D01*
G01X1144810Y613762D02*
X1146630Y615582D01*
X1217440D01*
X1262220Y660362D01*
X1286820D01*
X1333220Y706762D01*
Y732363D01*
X1330328Y735255D01*
Y738567D01*
G01X1136720Y641362D02*
X1147775Y630307D01*
X1219066D01*
X1263212Y674453D01*
X1280982D01*
X1315417Y708888D01*
Y730510D01*
X1316282Y731375D01*
G01X1151327Y959265D02*
X1149608Y957546D01*
X1147483D01*
G01X1151223Y950460D02*
X1147483Y954200D01*
G01X1140727Y985255D02*
X1142637Y987165D01*
Y990466D01*
X1147927Y995756D01*
Y1005994D01*
X1157297Y1015364D01*
X1163003D01*
X1168001Y1020362D01*
X1171425D01*
G01X1149903Y1247259D02*
X1151102D01*
X1152017Y1246344D01*
X1153218D01*
X1157456Y1250582D01*
X1161793D01*
X1165118Y1247257D01*
X1170735D01*
X1174640Y1243352D01*
Y1238352D01*
X1176130Y1236862D01*
X1178580D01*
X1179520Y1237802D01*
Y1247373D01*
X1179563Y1247416D01*
G01X1138783Y1255381D02*
Y1255659D01*
X1136066Y1258376D01*
Y1259805D01*
X1136123Y1259862D01*
G01X1138783Y1258727D02*
X1140680Y1256830D01*
X1140793D01*
X1142921Y1254702D01*
Y1254602D01*
G01D02*
Y1252946D01*
X1142264Y1252289D01*
Y1246654D01*
X1144577Y1244341D01*
G01X1172649Y1254287D02*
Y1252464D01*
X1170273Y1250088D01*
X1166088D01*
X1162974Y1253202D01*
X1161029D01*
X1160839Y1253392D01*
X1153171D01*
X1150900Y1255663D01*
Y1257692D01*
X1148837Y1259755D01*
X1145862D01*
X1143859Y1257752D01*
X1142921D01*
G01X1138783Y1252034D02*
Y1249351D01*
X1139796Y1248338D01*
G01X1147483Y1248688D02*
X1146088D01*
X1144792Y1249984D01*
G01X1148563Y1257097D02*
X1146773Y1255307D01*
Y1254056D01*
X1149903Y1250926D01*
Y1250409D01*
G01X1165440Y176450D02*
X1160930Y171940D01*
Y142862D01*
X1208360Y95432D01*
X1232720D01*
X1235275Y97987D01*
X1246555D01*
X1252520Y92022D01*
G01X1168710Y176590D02*
X1164300Y172180D01*
Y142780D01*
X1180390Y126690D01*
X1196930D01*
G01X1167190Y526922D02*
Y531181D01*
X1187249Y551240D01*
X1249552D01*
X1307484Y575236D01*
X1354525D01*
X1396331Y617042D01*
X1468951D01*
X1481890Y629981D01*
Y647781D01*
X1496277Y662168D01*
Y678245D01*
X1535814Y717782D01*
X1540309Y724509D01*
X1552389Y753667D01*
X1575737Y777015D01*
Y789875D01*
X1579816Y793954D01*
G01X1153467Y592097D02*
X1154775D01*
X1157980Y588892D01*
G01D02*
X1158620Y589532D01*
X1164563D01*
X1164858Y589827D01*
G01X1158300Y585862D02*
X1167800D01*
X1169600Y587662D01*
X1173027D01*
X1182692Y597327D01*
X1186058D01*
G01X1177570Y602052D02*
Y599625D01*
X1176387Y598442D01*
X1174209D01*
X1170594Y594827D01*
X1164858D01*
G01X1170740Y602132D02*
X1170545Y602327D01*
X1164858D01*
G01Y597327D02*
X1164663Y597132D01*
X1159887D01*
X1158067Y598952D01*
X1158030D01*
G01D02*
X1153642D01*
X1153477Y599117D01*
G01X1164858Y604827D02*
X1161012D01*
X1159107Y606732D01*
Y607992D01*
X1158047Y609052D01*
G01D02*
X1155082Y606087D01*
X1153537D01*
G01X1164858Y592327D02*
X1162044D01*
X1160559Y593812D01*
X1158020D01*
G01D02*
X1155865Y595967D01*
X1153477D01*
G01X1153537Y602937D02*
X1157052D01*
X1158054Y603939D01*
G01D02*
X1159720Y602273D01*
Y601683D01*
X1161576Y599827D01*
X1164858D01*
G01X1158054Y603939D02*
Y603965D01*
G01X1172742Y770832D02*
X1167990D01*
X1166020Y768862D01*
Y766457D01*
X1166077Y766400D01*
G01X1159078Y763401D02*
X1162077Y766400D01*
X1166077D01*
G01X1168483Y1255381D02*
X1165891D01*
X1165631Y1255121D01*
X1163983D01*
X1163891Y1255029D01*
G01X1164830Y1628830D02*
X1162325Y1631335D01*
X1160310D01*
G01X1163970Y1620600D02*
X1160310Y1624260D01*
Y1628185D01*
G01X1225100Y91500D02*
X1221500Y87900D01*
X1195600D01*
X1182100Y101400D01*
Y103000D01*
X1183100Y104000D01*
X1185400D01*
G01X1169690Y526922D02*
Y531092D01*
X1188008Y549410D01*
X1251842D01*
X1308835Y573017D01*
X1354895D01*
X1397090Y615212D01*
X1469710D01*
X1483720Y629222D01*
Y647334D01*
X1498807Y662421D01*
Y678035D01*
X1536629Y715857D01*
X1541188Y722680D01*
X1553660Y752788D01*
X1577937Y777065D01*
Y785715D01*
X1579632Y787410D01*
G01X1181300Y584762D02*
Y582362D01*
X1181800Y581862D01*
X1207565D01*
X1213065Y587362D01*
X1270284D01*
X1293607Y597023D01*
X1360227Y663643D01*
X1385624D01*
X1393128Y671147D01*
X1407205D01*
X1423910Y687852D01*
X1438412D01*
X1452065Y701505D01*
X1457153D01*
X1457773Y700885D01*
X1461342Y699407D01*
X1464638D01*
X1470509Y705278D01*
X1475597D01*
X1495315Y724996D01*
Y732256D01*
X1494968Y732603D01*
G01X1175217Y595762D02*
X1177407D01*
X1181520Y599875D01*
Y604301D01*
X1182046Y604827D01*
X1186058D01*
G01X1177677Y764070D02*
X1177761D01*
X1179842Y766151D01*
Y778732D01*
G01X1253087Y978815D02*
X1241387D01*
X1239567Y976995D01*
X1223777D01*
X1222507Y975725D01*
X1209397D01*
X1207867Y977255D01*
X1198457D01*
X1195167Y980545D01*
Y985505D01*
X1193917Y986755D01*
X1179917D01*
X1179037Y985875D01*
X1176037D01*
X1174807Y984645D01*
Y778162D01*
X1172742Y776097D01*
Y773982D01*
G01X1296637Y970755D02*
X1225477D01*
X1223067Y973165D01*
X1217647D01*
X1209807Y965325D01*
X1197627D01*
X1193927Y961625D01*
Y952735D01*
X1192037Y950845D01*
X1188747D01*
X1179787Y941885D01*
Y933255D01*
X1179127Y932595D01*
Y786062D01*
X1180042Y785147D01*
Y784262D01*
X1179842Y784062D01*
Y781882D01*
G01X1181027Y959265D02*
X1179308Y957546D01*
X1177183D01*
G01X1180923Y950460D02*
X1177183Y954200D01*
G01Y994357D02*
X1180637D01*
G01X1171425Y1020362D02*
Y1019537D01*
X1172400Y1018562D01*
X1173399D01*
X1174575Y1017386D01*
Y1016362D01*
G01X1264362Y1048399D02*
X1246904D01*
X1242488Y1052815D01*
X1226316D01*
X1225276Y1053855D01*
X1210588D01*
X1209508Y1052775D01*
X1194868D01*
X1191358Y1049265D01*
X1189697D01*
X1179857Y1039425D01*
X1175347D01*
X1174575Y1038653D01*
Y1020362D01*
G01X1200386Y1247545D02*
X1200444Y1247486D01*
Y1245455D01*
X1200809Y1245090D01*
Y1243216D01*
X1199938Y1242345D01*
X1194134D01*
X1191606Y1244873D01*
X1182106D01*
X1179563Y1247416D01*
G01X1168483Y1258727D02*
X1169716Y1257494D01*
X1170760D01*
X1170909Y1257345D01*
X1172557D01*
X1172649Y1257437D01*
G01D02*
X1172706Y1257494D01*
X1173017D01*
X1174945Y1259422D01*
X1178527D01*
X1179080Y1259975D01*
Y1260672D01*
G01X1199679Y1254574D02*
X1199762D01*
X1200348Y1253988D01*
Y1251528D01*
X1198105Y1249285D01*
X1193297D01*
X1188875Y1253707D01*
X1183103D01*
X1178928Y1257882D01*
X1176387D01*
X1172849Y1254344D01*
X1172706D01*
X1172649Y1254287D01*
G01X1177120Y1248688D02*
X1174331D01*
G01X1177222Y1255567D02*
Y1252907D01*
X1179563Y1250566D01*
G01X1217125Y134600D02*
X1210370D01*
X1208960Y133190D01*
Y128050D01*
X1207600Y126690D01*
X1196930D01*
G01X1194800Y143112D02*
X1211570D01*
X1213420Y144962D01*
G01X1197396Y605911D02*
Y607913D01*
X1197280Y608029D01*
Y610352D01*
G01X1201672Y605605D02*
X1201366Y605911D01*
X1197396D01*
G01X1197280Y610352D02*
X1191981D01*
X1188956Y607327D01*
X1186058D01*
G01X1201312Y599133D02*
X1201075Y598896D01*
X1197396D01*
G01D02*
X1196310Y599982D01*
X1193200D01*
X1192890Y600292D01*
G01D02*
X1192425Y599827D01*
X1186058D01*
G01X1482751Y749227D02*
Y735019D01*
X1473867Y726135D01*
X1466263Y722985D01*
X1463603Y720325D01*
X1453107D01*
X1447277Y714495D01*
Y708165D01*
X1436898Y697786D01*
X1406358D01*
X1396464Y687892D01*
X1388543Y684611D01*
X1381997Y678065D01*
X1363137D01*
X1289551Y604479D01*
X1266408Y594892D01*
X1212453D01*
X1211380Y595965D01*
Y599371D01*
X1207990Y602761D01*
X1197396D01*
G01D02*
X1195778D01*
X1192887Y605652D01*
G01D02*
X1189562Y602327D01*
X1186058D01*
G01X1494963Y749587D02*
Y747941D01*
X1490016Y742994D01*
Y727863D01*
X1476223Y714070D01*
X1469789Y711405D01*
X1459257D01*
X1457717Y712945D01*
X1453545D01*
X1450033Y709433D01*
Y706941D01*
X1437948Y694856D01*
X1420638D01*
X1413637Y687855D01*
X1400337D01*
X1398176Y685694D01*
X1390357Y682455D01*
X1383047Y675145D01*
X1364047D01*
X1291030Y602128D01*
X1267259Y592282D01*
X1211370D01*
X1207800Y595852D01*
X1197502D01*
X1197396Y595746D01*
G01D02*
X1196662Y595012D01*
X1192877D01*
G01D02*
X1189827D01*
X1189642Y594827D01*
X1186058D01*
G01Y592327D02*
X1201052D01*
X1201977Y593252D01*
G01X1185687Y744475D02*
X1192577Y751365D01*
Y758135D01*
X1193724Y759282D01*
X1195097D01*
G01X1254166Y942501D02*
X1239209D01*
X1238540Y941832D01*
X1225839D01*
X1223540Y944131D01*
X1210283D01*
X1200137Y933985D01*
Y778995D01*
X1195097Y773955D01*
Y768190D01*
G01Y765040D02*
Y759282D01*
G01X1200497Y765040D02*
Y762435D01*
X1199597Y761535D01*
Y759254D01*
G01X1202307Y757082D02*
Y757255D01*
X1200308Y759254D01*
X1199597D01*
G01X1198183Y957546D02*
X1202495Y961858D01*
G01X1201627Y955185D02*
X1199168D01*
X1198183Y954200D01*
G01X1201403Y989083D02*
Y991137D01*
X1198183Y994357D01*
G01X1193590Y1267912D02*
X1193210Y1267532D01*
Y1260022D01*
X1195076Y1258156D01*
Y1256140D01*
G01X1199679Y1257724D02*
X1199595D01*
X1198160Y1259159D01*
X1197103D01*
X1195470Y1260792D01*
Y1262802D01*
G01X1209790Y1259423D02*
X1205229D01*
X1201205Y1255399D01*
X1200504D01*
X1199679Y1254574D01*
G01X1198183Y1252034D02*
X1197382Y1252835D01*
X1196357D01*
X1195097Y1251575D01*
G01X1453600Y1595662D02*
X1450740D01*
X1448580Y1593502D01*
Y1569462D01*
X1446880Y1567762D01*
X1186608D01*
X1184290Y1570080D01*
G01X1184330Y1573260D02*
X1185128Y1572462D01*
X1406250D01*
X1408620Y1570092D01*
X1433390D01*
X1433720Y1569762D01*
G01X1199400Y1627800D02*
X1207400Y1619800D01*
X1395000D01*
X1404100Y1610700D01*
X1432300D01*
X1435200Y1613600D01*
X1441200D01*
X1446700Y1608100D01*
Y1598400D01*
G01X1215960Y121002D02*
Y117340D01*
X1218710Y114590D01*
X1221340D01*
X1222100Y115350D01*
Y119482D01*
X1223000Y120382D01*
X1231355D01*
X1244993Y134020D01*
Y144736D01*
X1245930Y145673D01*
Y147460D01*
X1249881Y151411D01*
X1251668D01*
X1257894Y157637D01*
Y158721D01*
X1261120Y161947D01*
Y163862D01*
X1263650Y166392D01*
X1267945D01*
X1269670Y168117D01*
X1275157D01*
X1283501Y176461D01*
X1290924D01*
X1293511Y179048D01*
G01X1202920Y117162D02*
X1214095Y105987D01*
X1228704D01*
G01X1215960Y121002D02*
X1215920Y120962D01*
X1211668D01*
G01X1202860Y120392D02*
X1205880Y123412D01*
X1210620D01*
X1211668Y122364D01*
Y120962D01*
G01X1210910Y129502D02*
Y128772D01*
X1216575Y123107D01*
X1219982D01*
X1220689Y122400D01*
X1230503D01*
X1242983Y134880D01*
Y145004D01*
X1244000Y146021D01*
Y147945D01*
X1249894Y153839D01*
G01X1231668Y140962D02*
Y137192D01*
X1231158Y136682D01*
X1204342D01*
X1203532Y135872D01*
Y132394D01*
X1206434Y129492D01*
G01X1206694Y139512D02*
X1219224D01*
X1220034Y138702D01*
X1227814D01*
X1228518Y139406D01*
Y140962D01*
G01X1213420Y144962D02*
X1215420Y142962D01*
X1226518D01*
X1228518Y144962D01*
G01X1206664Y158952D02*
X1209799Y162087D01*
X1215715D01*
X1219350Y165722D01*
X1234580D01*
X1242470Y173612D01*
G01X1200830Y206002D02*
Y201612D01*
X1202570Y199872D01*
X1206390D01*
X1214220Y207702D01*
X1217540D01*
X1220460Y204782D01*
Y199532D01*
X1222270Y197722D01*
X1225000D01*
X1230240Y192482D01*
X1230435D01*
G01X1284746Y207271D02*
X1281629D01*
X1278720Y204362D01*
X1277120D01*
X1275120Y202362D01*
X1272020D01*
X1271080Y201422D01*
X1265480D01*
X1250665Y186607D01*
X1224235D01*
X1216290Y194552D01*
Y204292D01*
X1215720Y204862D01*
G01X1201977Y593252D02*
X1204683Y590546D01*
Y588714D01*
G01X1214000Y599262D02*
Y601362D01*
X1209757Y605605D01*
X1204822D01*
G01X1208980Y598462D02*
X1205133D01*
X1204462Y599133D01*
G01X1212937Y756730D02*
X1210288Y754081D01*
G01D02*
X1212141D01*
X1212537Y753685D01*
Y751380D01*
G01X1202300Y753962D02*
Y754332D01*
X1204497Y756529D01*
Y765040D01*
G01X1208937Y756730D02*
Y755425D01*
X1207607Y754095D01*
G01D02*
Y752310D01*
X1208537Y751380D01*
G01X1244237Y928847D02*
X1240525Y925135D01*
X1231667D01*
X1229627Y923095D01*
X1225886D01*
X1222536Y919745D01*
X1219678D01*
X1216737Y916804D01*
Y810397D01*
X1218537Y808597D01*
Y765480D01*
X1212937Y759880D01*
G01X1260887Y935665D02*
X1229567D01*
X1228787Y934885D01*
X1224917D01*
X1224097Y935705D01*
X1216777D01*
X1214397Y933325D01*
X1210627D01*
X1204597Y927295D01*
Y770322D01*
X1204497Y770222D01*
Y768190D01*
G01X1209457Y787702D02*
Y770942D01*
X1209247Y770732D01*
Y768180D01*
G01X1206432Y758995D02*
Y762005D01*
X1209247Y764820D01*
Y765030D01*
G01X1244383Y939465D02*
X1225437D01*
X1224437Y938465D01*
X1213017D01*
X1202317Y927765D01*
Y772215D01*
X1200497Y770395D01*
Y768190D01*
G01X1292792Y928724D02*
X1290215Y931301D01*
X1233643D01*
X1231927Y929585D01*
X1225387D01*
X1224977Y929175D01*
X1224947D01*
X1223537Y927765D01*
X1221237D01*
X1214497Y921025D01*
Y809225D01*
X1215887Y807835D01*
Y766830D01*
X1208937Y759880D01*
G01X1212407Y773625D02*
X1213667Y772365D01*
Y768824D01*
X1211641Y766798D01*
G01X1250230Y933374D02*
X1231886D01*
X1230637Y932125D01*
X1224147D01*
X1223077Y933195D01*
X1219527D01*
X1213817Y927485D01*
X1211727D01*
X1209627Y925385D01*
Y869655D01*
X1208697Y868725D01*
Y866215D01*
X1209927Y864985D01*
Y859395D01*
X1208937Y858405D01*
Y829105D01*
X1210077Y827965D01*
Y825085D01*
X1208807Y823815D01*
Y819075D01*
X1209787Y818095D01*
Y816575D01*
X1208347Y815135D01*
Y812415D01*
X1209457Y811305D01*
Y787702D01*
G01X1223793Y1239961D02*
X1216149D01*
G01X1209790Y1259423D02*
X1210487D01*
X1215307Y1254603D01*
X1230681D01*
G01X1204161Y1244598D02*
Y1246539D01*
X1206310Y1248688D01*
X1206883D01*
G01X1204305Y1254514D02*
X1206388D01*
X1207048Y1255174D01*
G01X1204305Y1254514D02*
X1203358Y1253567D01*
Y1250517D01*
X1202614Y1249773D01*
G01X1249408Y140054D02*
X1248474Y139120D01*
Y132944D01*
X1235699Y120169D01*
X1233724Y115401D01*
X1232695Y114372D01*
X1227214D01*
X1225700Y112858D01*
Y108962D01*
G01X1230668Y116962D02*
X1232284Y118578D01*
Y119032D01*
X1246464Y133212D01*
Y143300D01*
X1249430Y146266D01*
Y147620D01*
G01X1252128Y137354D02*
X1250934Y136160D01*
Y133127D01*
X1238240Y120433D01*
X1233335Y108593D01*
X1230729Y105987D01*
X1228704D01*
G01X1237664Y141202D02*
Y135999D01*
X1233807Y132142D01*
X1230698D01*
X1228518Y129962D01*
G01D02*
X1223396Y124840D01*
X1217658D01*
X1217158Y125340D01*
Y126942D01*
G01X1234746Y136040D02*
X1232968Y134262D01*
X1231668D01*
G01X1220305Y130810D02*
X1222990D01*
X1223100Y130700D01*
G01X1217155Y130810D02*
Y134570D01*
X1217125Y134600D01*
G01X1234093Y144962D02*
X1231668D01*
G01D02*
Y140962D01*
G01X1232198Y152612D02*
Y156672D01*
G01X1249720Y177662D02*
X1249428D01*
X1232198Y160432D01*
Y156672D01*
G01X1228520Y202162D02*
X1230964Y199718D01*
X1232603Y199392D01*
X1237630D01*
X1242295Y194727D01*
Y193362D01*
G01X1229720Y197302D02*
X1233585Y193437D01*
Y192482D01*
G01X1233780Y214572D02*
X1230005D01*
X1229295Y213862D01*
G01Y205862D02*
X1233282Y201875D01*
G01X1229295Y209862D02*
X1231720D01*
G01X1229295Y217862D02*
X1231720D01*
G01X1232720Y377862D02*
Y374862D01*
X1236820Y370762D01*
X1300650D01*
X1303850Y373962D01*
X1396245D01*
X1459020Y311187D01*
Y282162D01*
X1464681Y276501D01*
X1474658D01*
X1477797Y273362D01*
X1501376D01*
X1545330Y229408D01*
Y187772D01*
X1543120Y185562D01*
Y148362D01*
X1536930Y142172D01*
Y136332D01*
X1540600Y132662D01*
X1548308D01*
X1553189Y127781D01*
G01X1230720Y380362D02*
X1234220Y383862D01*
X1400924D01*
X1458024Y326762D01*
X1492400D01*
X1502262Y316900D01*
X1510437D01*
G01X1252880Y924465D02*
X1251020Y922605D01*
X1235397D01*
X1231057Y918265D01*
X1228997D01*
X1222867Y912135D01*
Y872495D01*
X1219047Y868675D01*
Y855635D01*
X1222787Y851895D01*
Y826315D01*
X1219536Y823064D01*
Y810866D01*
X1222707Y807695D01*
Y763500D01*
G01X1223327Y757615D02*
Y759730D01*
X1222707Y760350D01*
G01X1267447Y912265D02*
X1235747D01*
X1229977Y906495D01*
Y771705D01*
X1230237Y771445D01*
Y765717D01*
X1228860Y764340D01*
G01X1224439Y956561D02*
X1226898D01*
X1227883Y957546D01*
G01X1231327Y955185D02*
X1228868D01*
X1227883Y954200D01*
G01Y994357D02*
Y992147D01*
X1224031Y988295D01*
G01X1236583Y1057940D02*
X1232107D01*
G01X1223793Y1239961D02*
Y1243811D01*
G01X1230681Y1246715D02*
Y1244283D01*
X1228500Y1242102D01*
G01D02*
X1227420D01*
X1225711Y1243811D01*
X1223793D01*
G01X1224189Y1259155D02*
X1221823Y1256789D01*
X1220083D01*
G01X1226899Y1257968D02*
X1227816D01*
X1228031Y1257753D01*
X1230681D01*
G01X1235234Y1256802D02*
X1233314D01*
X1232363Y1257753D01*
X1230681D01*
G01Y1249865D02*
Y1254603D01*
G01X1227847Y1251715D02*
X1224007D01*
G01X1241010Y110782D02*
X1239240D01*
X1238084Y111938D01*
Y114569D01*
X1240014Y119227D01*
X1252944Y132157D01*
Y133892D01*
X1259104Y140052D01*
X1262183D01*
X1263479Y141348D01*
G01X1291264Y183716D02*
X1290064D01*
X1288851Y182503D01*
X1285604D01*
X1284745Y183362D01*
X1280741D01*
X1279636Y182257D01*
X1278758D01*
X1269736Y173235D01*
X1267957D01*
X1265944Y171222D01*
X1257140D01*
X1236300Y150382D01*
Y144169D01*
X1234746Y142615D01*
Y136040D01*
G01X1290014Y180574D02*
X1284912D01*
X1284207Y181279D01*
X1282762D01*
X1280701Y179218D01*
X1277997D01*
X1270404Y171625D01*
X1268624D01*
X1266611Y169612D01*
X1258804D01*
X1245831Y156639D01*
Y153694D01*
X1238600Y146463D01*
Y142138D01*
X1237664Y141202D01*
G01X1244120Y167462D02*
Y168762D01*
X1247620Y172262D01*
X1251419D01*
X1265009Y185852D01*
X1273953D01*
X1276978Y188877D01*
X1281188D01*
X1282698Y190387D01*
G01X1242470Y173612D02*
X1246243Y177385D01*
Y178885D01*
X1259986Y192628D01*
X1264220D01*
X1266874Y195282D01*
X1268449D01*
X1269789Y196622D01*
G01X1252720Y193362D02*
X1242295D01*
G01X1236410Y201462D02*
X1236950Y202002D01*
X1238478D01*
X1239018Y201462D01*
G01X1236620Y221562D02*
Y220562D01*
X1239018Y218164D01*
Y217462D01*
G01X1242195Y221562D02*
Y217489D01*
X1242168Y217462D01*
G01X1284383Y215762D02*
X1282947D01*
X1279047Y211862D01*
X1274863D01*
X1273963Y210962D01*
X1262020D01*
X1260820Y212162D01*
X1254720D01*
X1249920Y216962D01*
X1242668D01*
X1242168Y217462D01*
G01X1248868Y213414D02*
X1248020Y214262D01*
X1242968D01*
X1242168Y213462D01*
G01X1255613Y209568D02*
X1252714D01*
X1248868Y213414D01*
G01X1246853Y208229D02*
X1245620Y209462D01*
X1242168D01*
G01X1265207Y208442D02*
X1261500D01*
X1260620Y207562D01*
X1247520D01*
X1246853Y208229D01*
G01X1252930Y205462D02*
X1242168D01*
G01X1244720Y230362D02*
X1247440D01*
X1254400Y223402D01*
X1257820D01*
X1259915Y221307D01*
X1260514D01*
G01X1519833Y277297D02*
X1519118Y276582D01*
X1480200D01*
X1476820Y279962D01*
X1466220D01*
X1462820Y283362D01*
Y312762D01*
X1397820Y377762D01*
X1302275D01*
X1299875Y375362D01*
X1237421D01*
X1236720Y376063D01*
Y377862D01*
G01X1545763Y159305D02*
Y185705D01*
X1546940Y186882D01*
Y233786D01*
X1505754Y274972D01*
X1479264D01*
X1476074Y278162D01*
X1465474D01*
X1461020Y282616D01*
Y312016D01*
X1397074Y375962D01*
X1303021D01*
X1300321Y373262D01*
X1236619D01*
X1234720Y375161D01*
Y380362D01*
G01X1246260Y760390D02*
X1245310Y759440D01*
Y752752D01*
X1243800Y751242D01*
X1242398D01*
G01X1254788Y873600D02*
X1247210Y866022D01*
Y776863D01*
X1246260Y775913D01*
Y763540D01*
G01X1246079Y876083D02*
X1239287Y869291D01*
Y785934D01*
X1238502Y785149D01*
Y770690D01*
X1237627Y769815D01*
X1235117D01*
X1233957Y768655D01*
Y764943D01*
X1235360Y763540D01*
G01X1250260Y760390D02*
Y757120D01*
X1249122Y755982D01*
G01X1258891Y881517D02*
X1244510Y867136D01*
Y777763D01*
X1243950Y777203D01*
Y765230D01*
X1242260Y763540D01*
G01X1313867Y908964D02*
X1297307D01*
X1297298Y908955D01*
X1278951D01*
X1246079Y876083D01*
G01X1251727Y907485D02*
X1242852D01*
G01X1312117Y921235D02*
X1309287Y924065D01*
X1293686D01*
X1288904Y928847D01*
X1244237D01*
G01X1321527Y925714D02*
X1319264D01*
X1314008Y930970D01*
X1300552D01*
X1292057Y939465D01*
X1244383D01*
G01X1377253Y1009297D02*
X1374479Y1007695D01*
G02X1372629I-925J1602D01*
G01X1372591Y1007717D01*
G03X1370778Y1007695I-887J-1624D01*
G02X1368928I-925J1602D01*
G01X1368875Y1007726D01*
G03X1367078Y1007695I-871J-1633D01*
G02X1365228I-925J1602D01*
G03X1363378I-925J-1602D01*
G02X1361528I-925J1602D01*
G01X1361475Y1007726D01*
G03X1359678Y1007695I-871J-1633D01*
G02X1357828I-925J1602D01*
G01X1357775Y1007726D01*
G03X1355978Y1007695I-871J-1633D01*
G02X1354128I-925J1602D01*
G01X1354075Y1007726D01*
G03X1352278Y1007695I-871J-1633D01*
G02X1350428I-925J1602D01*
G01X1350390Y1007717D01*
G03X1348579Y1007695I-886J-1624D01*
G02X1346729I-925J1602D01*
G01X1346691Y1007717D01*
G03X1344878Y1007695I-887J-1624D01*
G02X1343028I-925J1602D01*
G01X1342975Y1007726D01*
G03X1341178Y1007695I-871J-1633D01*
G02X1339328I-925J1602D01*
G03X1337478I-925J-1602D01*
G02X1335628I-925J1602D01*
G01X1335575Y1007726D01*
G03X1333778Y1007695I-871J-1633D01*
G02X1331928I-925J1602D01*
G03X1330078I-925J-1602D01*
G02X1328228I-925J1602D01*
G01X1328175Y1007726D01*
G03X1326378Y1007695I-871J-1633D01*
G02X1324528I-925J1602D01*
G03X1322678I-925J-1602D01*
G02X1320828I-925J1602D01*
G03X1319903Y1007943I-925J-1601D01*
G01X1319185D01*
X1315706Y1004464D01*
X1276320D01*
Y1004465D01*
X1265637D01*
X1247301Y1022801D01*
G01X1314312Y1066331D02*
X1294159D01*
X1293047Y1065219D01*
X1253819D01*
Y1065220D01*
X1247044D01*
G01X1313190Y1085714D02*
X1312219Y1086685D01*
X1287396D01*
X1284358Y1089723D01*
X1248000D01*
G01X1236583Y1248688D02*
X1239435D01*
G01X1246654Y1672007D02*
Y1660152D01*
G01X1262320Y96012D02*
X1269420D01*
G01X1258539Y109263D02*
X1263220Y113944D01*
Y115362D01*
X1260520Y118062D01*
Y126962D01*
X1258195Y129287D01*
Y129412D01*
G01X1260641Y114399D02*
X1260410D01*
X1258195Y116614D01*
Y126262D01*
G01X1266723Y106735D02*
X1262383D01*
G01X1291224Y163122D02*
X1289104Y161002D01*
Y159262D01*
X1287714Y157872D01*
Y155023D01*
X1287133Y153620D01*
X1285616Y152103D01*
X1284080Y151467D01*
X1283424D01*
X1281184Y149227D01*
Y147769D01*
X1264124Y130709D01*
Y128282D01*
X1262211Y126369D01*
Y119840D01*
X1267014Y115037D01*
Y112012D01*
G01X1291544Y160583D02*
X1291194Y160233D01*
Y157861D01*
X1289782Y156449D01*
Y154287D01*
X1288509Y151210D01*
X1284153Y146854D01*
Y143784D01*
X1278991Y138622D01*
X1275853D01*
X1271413Y134182D01*
Y132632D01*
X1264294Y125513D01*
Y120689D01*
X1266926Y118057D01*
G01X1254520Y115562D02*
X1253160Y116922D01*
Y120107D01*
G01X1300212Y174099D02*
Y173041D01*
X1297633Y170462D01*
X1296593D01*
X1294661Y168530D01*
X1290565D01*
X1284753Y162718D01*
X1283702Y160182D01*
X1281748Y158228D01*
Y155705D01*
X1276532Y150489D01*
Y149101D01*
X1264333Y136902D01*
X1260367D01*
X1256064Y132599D01*
Y119094D01*
X1254520Y117550D01*
Y115562D01*
G01X1286513Y161483D02*
X1285637Y159366D01*
Y155507D01*
X1285273Y154628D01*
X1284864Y154219D01*
X1283534Y153668D01*
X1282642D01*
X1278858Y149884D01*
Y148536D01*
X1264403Y134081D01*
X1263592Y134892D01*
X1261564D01*
X1258195Y131523D01*
Y129412D01*
G01X1253161Y128848D02*
Y124107D01*
G01X1293802Y170399D02*
X1290590D01*
X1283968Y163777D01*
X1282778Y160905D01*
X1280577Y158704D01*
Y156154D01*
X1274231Y149808D01*
Y148900D01*
X1263343Y138012D01*
X1259907D01*
X1254954Y133059D01*
Y130641D01*
X1253161Y128848D01*
G01X1249408Y140054D02*
Y143218D01*
X1252999Y146809D01*
X1255412D01*
X1257541Y147691D01*
X1261472Y151622D01*
X1266919D01*
G01X1249430Y147620D02*
X1250784D01*
X1259729Y156565D01*
Y158017D01*
X1262920Y161208D01*
Y163462D01*
X1264040Y164582D01*
X1269044D01*
X1270254Y163372D01*
X1272434D01*
X1275141Y166079D01*
X1275451Y166827D01*
X1283851Y175227D01*
X1290624D01*
G01X1254356Y139582D02*
X1255656Y140882D01*
X1257044D01*
X1258725Y142563D01*
X1261335D01*
X1264012Y145240D01*
Y148527D01*
G01X1303407Y175949D02*
X1299566D01*
X1297579Y173962D01*
X1296334D01*
X1295334Y172962D01*
X1287424D01*
X1280287Y165825D01*
X1279201Y163204D01*
X1276404Y160407D01*
Y157755D01*
X1267176Y148527D01*
X1264012D01*
G01X1252122Y156067D02*
Y159420D01*
X1256544Y163842D01*
X1257266D01*
X1258693Y162415D01*
G01X1276952Y174834D02*
X1271845Y169727D01*
X1269003D01*
X1267278Y168002D01*
X1262460D01*
X1258693Y164235D01*
Y162415D01*
G01X1306617Y188899D02*
X1302907D01*
X1300837Y190969D01*
X1299177D01*
X1297594Y192552D01*
X1291113D01*
X1290275Y193390D01*
X1281949D01*
X1279747Y191188D01*
X1275876D01*
X1272870Y188182D01*
X1260240D01*
X1249720Y177662D01*
G01X1291291Y185597D02*
X1284675D01*
X1283330Y186942D01*
X1277600D01*
X1274100Y183442D01*
X1268599D01*
X1261899Y176742D01*
Y174648D01*
G01X1263830Y195682D02*
X1267250Y199102D01*
X1272157D01*
X1273093Y200038D01*
G01X1293807Y214799D02*
X1292687D01*
X1291033Y213145D01*
X1286467D01*
X1283794Y210472D01*
X1281546D01*
X1278216Y207142D01*
X1271689D01*
X1268549Y204002D01*
X1263360D01*
X1252720Y193362D01*
G01X1267773Y208373D02*
Y207415D01*
X1266920Y206562D01*
X1262120D01*
X1261020Y205462D01*
X1252930D01*
G01X1260514Y221307D02*
X1263766D01*
X1268201Y216872D01*
X1273473D01*
X1276083Y214262D01*
X1278144D01*
X1282381Y218499D01*
X1289739D01*
G01X1256070Y229512D02*
X1257655Y231097D01*
X1260544D01*
G01D02*
X1263029D01*
X1264244Y232312D01*
X1274818D01*
X1276259Y230871D01*
X1277749D01*
G01X1277266Y868490D02*
X1271417Y862641D01*
Y750345D01*
X1266750Y745678D01*
Y740261D01*
X1263787Y737298D01*
Y735590D01*
G01X1256832Y741785D02*
X1256193Y741146D01*
Y733740D01*
G01X1263787Y732440D02*
X1263785Y732442D01*
X1259998D01*
G01X1261607Y853715D02*
X1264420Y850902D01*
Y749373D01*
X1256832Y741785D01*
G01X1252847Y741370D02*
Y745420D01*
G01X1270912Y877372D02*
X1255318Y861778D01*
Y772885D01*
X1261820Y766383D01*
Y750162D01*
X1257078Y745420D01*
X1252847D01*
G01X1271410Y866886D02*
X1269047Y864523D01*
Y751286D01*
X1263937Y746176D01*
Y745540D01*
G01X1258667Y751405D02*
X1257623Y752449D01*
X1255728D01*
G01X1262954Y873559D02*
X1250260Y860865D01*
Y763540D01*
G01X1316497Y897915D02*
X1305361D01*
X1299891Y892445D01*
X1290265D01*
X1261607Y863787D01*
Y853715D01*
G01X1265003Y860128D02*
X1266727Y858404D01*
Y752955D01*
G01X1310157Y895459D02*
X1305405D01*
X1300331Y890385D01*
X1291859D01*
X1265003Y863529D01*
Y860128D01*
G01X1315577Y903119D02*
X1311369D01*
X1310019Y904469D01*
X1302541D01*
X1299937Y901865D01*
X1283053D01*
X1254788Y873600D01*
G01X1315857Y900079D02*
X1303021D01*
X1300137Y897195D01*
X1286590D01*
X1262954Y873559D01*
G01X1315252Y904925D02*
X1313913Y906264D01*
X1300837D01*
X1298778Y904205D01*
X1281579D01*
X1258891Y881517D01*
G01X1319946Y906832D02*
X1319414Y907364D01*
X1298117D01*
X1297328Y906575D01*
X1279886D01*
X1264570Y891259D01*
G01X1304388Y916964D02*
X1272216D01*
X1270247Y914995D01*
X1256097D01*
G01X1313747Y911735D02*
X1274850D01*
X1270600Y907485D01*
X1251727D01*
G01X1306318Y919935D02*
X1304528Y921725D01*
X1292287D01*
X1289547Y924465D01*
X1252880D01*
G01X1320127Y927345D02*
X1318722Y928750D01*
X1318092D01*
X1314072Y932770D01*
X1301671D01*
X1291940Y942501D01*
X1254166D01*
G01X1314238Y926214D02*
X1311364Y929088D01*
X1299644D01*
X1293067Y935665D01*
X1260887D01*
G01X1314505Y923523D02*
X1310264Y927764D01*
X1298248D01*
X1292638Y933374D01*
X1250230D01*
G01X1307426Y978814D02*
X1263349D01*
Y978815D01*
X1253087D01*
G01X1379104Y1012501D02*
X1376328Y1010899D01*
X1376290Y1010877D01*
G02X1374479Y1010899I-886J1624D01*
G03X1372629I-925J-1602D01*
G01X1372591Y1010877D01*
G02X1370778Y1010899I-887J1624D01*
G03X1368928I-925J-1602D01*
G02X1367078I-925J1602D01*
G03X1365228I-925J-1602D01*
G01X1365175Y1010868D01*
G02X1363378Y1010899I-871J1633D01*
G03X1361528I-925J-1602D01*
G02X1359678I-925J1602D01*
G03X1357828I-925J-1602D01*
G01X1357775Y1010868D01*
G02X1355978Y1010899I-871J1633D01*
G03X1354128I-925J-1602D01*
G01X1354075Y1010868D01*
G02X1352278Y1010899I-871J1633D01*
G03X1350428I-925J-1602D01*
G01X1350390Y1010877D01*
G02X1348579Y1010899I-886J1624D01*
G03X1346729I-925J-1602D01*
G01X1346691Y1010877D01*
G02X1344878Y1010899I-887J1624D01*
G03X1343028I-925J-1602D01*
G02X1341178I-925J1602D01*
G03X1339328I-925J-1602D01*
G01X1339275Y1010868D01*
G02X1337478Y1010899I-871J1633D01*
G03X1335628I-925J-1602D01*
G02X1333778I-925J1602D01*
G03X1331928I-925J-1602D01*
G02X1330078I-925J1602D01*
G03X1328228I-925J-1602D01*
G02X1326378I-925J1602D01*
G03X1324528I-925J-1602D01*
G02X1322678I-925J1602D01*
G03X1320942Y1010960I-925J-1602D01*
G01X1320836Y1010899D01*
X1320801Y1010864D01*
X1316814D01*
X1316414Y1010464D01*
X1276980D01*
Y1010465D01*
X1265287D01*
X1260502Y1015250D01*
G01X1316947Y1032706D02*
X1306979D01*
X1295676Y1044009D01*
X1274226D01*
X1269836Y1048399D01*
X1264362D01*
G01X1331602Y1036468D02*
G02X1330127Y1036420I-760J667D01*
G01X1329855Y1036691D01*
G03X1328088I-883J-883D01*
G01X1327711Y1036314D01*
G02X1326527I-592J592D01*
G01X1326201Y1036640D01*
G03X1324467I-867J-867D01*
G01X1324200Y1036373D01*
G02X1324198Y1036372I-2J2D01*
G01X1319306D01*
X1318214Y1037464D01*
X1310332D01*
X1299132Y1048664D01*
X1279941D01*
X1277396Y1051209D01*
X1253916D01*
G01X1320820Y1071656D02*
X1320712Y1071764D01*
X1253863D01*
G01X1319973Y1067280D02*
X1317442D01*
X1316758Y1067964D01*
X1292468D01*
X1291784Y1067280D01*
X1260341D01*
G01X1321906Y1072860D02*
X1320972D01*
X1320797Y1073035D01*
X1305498D01*
X1304220Y1074313D01*
X1259335D01*
G01X1315448Y1078062D02*
X1308069D01*
X1306095Y1080036D01*
X1283776D01*
X1280467Y1083345D01*
X1265387D01*
G01X1314261Y1079413D02*
X1313796D01*
X1311649Y1081560D01*
X1286112D01*
X1281177Y1086495D01*
X1253557D01*
G01X1262402Y1672007D02*
Y1663455D01*
X1259433Y1660486D01*
G01X1266926Y118057D02*
X1268946Y116037D01*
X1270630D01*
X1276345Y110322D01*
Y102705D01*
G01X1269420Y96012D02*
X1271320D01*
X1274863Y99555D01*
X1276345D01*
G01X1283485Y115130D02*
X1281955Y113600D01*
X1279485D01*
G01X1267014Y112012D02*
Y108893D01*
X1266723Y108602D01*
Y106735D01*
G01X1269228Y147097D02*
X1265707Y143576D01*
G01X1291084Y171732D02*
X1289065D01*
X1282175Y164842D01*
X1280993Y161988D01*
X1278514Y159509D01*
Y156971D01*
X1271021Y149478D01*
Y148890D01*
X1269228Y147097D01*
G01X1277490Y165946D02*
X1277460Y165916D01*
X1276978Y164752D01*
X1276354Y163247D01*
X1274354Y161247D01*
Y158562D01*
X1272788Y156996D01*
X1272293D01*
X1269147Y153850D01*
G01X1291834Y174057D02*
X1285601D01*
X1277490Y165946D01*
G01X1271954Y159143D02*
X1268570D01*
X1266347Y156920D01*
G01X1290759Y178472D02*
X1289845Y177558D01*
X1281735D01*
X1279011Y174834D01*
X1276952D01*
G01X1273093Y200038D02*
Y196776D01*
X1272939Y196622D01*
G01X1290734Y199122D02*
X1281780D01*
X1278320Y195662D01*
X1277193D01*
X1275493Y193962D01*
G01X1277355Y216851D02*
X1281940Y221436D01*
X1282176D01*
G01X1267618Y225382D02*
X1267698Y225462D01*
X1270018D01*
G01X1273168Y229462D02*
Y225462D01*
G01X1285393Y222262D02*
X1284105Y223550D01*
X1275080D01*
X1273168Y225462D01*
G01X1277749Y230871D02*
X1279174Y229446D01*
X1282449D01*
X1288517Y223378D01*
X1292628D01*
X1293807Y222199D01*
G01X1278320Y239292D02*
X1277790Y239822D01*
X1272150D01*
X1270083Y237755D01*
Y235206D01*
G01X1280134D02*
X1273233D01*
G01X1294357Y224688D02*
X1292830Y226215D01*
X1289715D01*
X1287047Y228883D01*
Y230478D01*
X1282319Y235206D01*
X1280134D01*
G01X1284120Y241567D02*
X1283148Y242539D01*
X1280291D01*
G01X1274257Y740490D02*
Y737640D01*
X1273257Y736640D01*
G01X1295535Y871113D02*
X1280127Y855705D01*
Y745869D01*
X1277257Y742999D01*
Y736560D01*
G01X1278043Y862242D02*
X1275078Y859277D01*
Y754946D01*
X1274198Y754066D01*
Y750666D01*
G01X1285316Y865291D02*
X1277667Y857642D01*
Y746694D01*
X1274613Y743640D01*
X1274257D01*
G01X1280797Y743540D02*
X1282517Y745260D01*
Y854572D01*
X1291306Y863361D01*
G01X1308417Y885151D02*
X1306693D01*
X1305373Y883831D01*
X1299632D01*
X1278043Y862242D01*
G01X1309317Y894510D02*
X1306534D01*
X1300319Y888295D01*
X1292819D01*
X1271410Y866886D01*
G01X1308997Y891562D02*
X1307818D01*
X1302010Y885754D01*
X1294530D01*
X1277266Y868490D01*
G01X1315087Y898957D02*
X1304207D01*
X1300105Y894855D01*
X1288395D01*
X1270912Y877372D01*
G01X1307657Y901135D02*
X1302416D01*
X1300796Y899515D01*
X1284433D01*
X1270249Y885331D01*
G01X1313617Y912964D02*
X1272016D01*
X1271317Y912265D01*
X1267447D01*
G01X1313837Y910435D02*
X1277036D01*
X1271402Y904801D01*
G01X1377253Y1015705D02*
X1375354Y1014661D01*
X1374310Y1014058D01*
G02X1372836I-737J1277D01*
G01X1372778Y1014092D01*
G03X1370610Y1014058I-1054J-1961D01*
G02X1369136I-737J1277D01*
G03X1366952Y1014082I-1113J-1927D01*
G01X1366911Y1014058D01*
G02X1365437I-737J1277D01*
G01X1365396Y1014082D01*
G03X1363210Y1014058I-1072J-1951D01*
G02X1361736I-737J1277D01*
G03X1359552Y1014082I-1113J-1927D01*
G01X1359511Y1014058D01*
G02X1358037I-737J1277D01*
G01X1357996Y1014082D01*
G03X1355810Y1014058I-1072J-1951D01*
G02X1354336I-737J1277D01*
G01X1354278Y1014092D01*
G03X1352110Y1014058I-1054J-1961D01*
G02X1350636I-737J1277D01*
G01X1350578Y1014092D01*
G03X1348410Y1014058I-1054J-1961D01*
G02X1346936I-737J1277D01*
G01X1346878Y1014092D01*
G03X1344710Y1014058I-1054J-1961D01*
G02X1343236I-737J1277D01*
G03X1341052Y1014082I-1113J-1927D01*
G01X1341011Y1014058D01*
G02X1339537I-737J1277D01*
G01X1339496Y1014082D01*
G03X1337310Y1014058I-1072J-1951D01*
G02X1335836I-737J1277D01*
G03X1333796Y1014155I-1114J-1927D01*
G02X1331960Y1014147I-927J2023D01*
G03X1329951Y1014082I-938J-2095D01*
G01X1329910Y1014058D01*
X1320093D01*
X1318954Y1012919D01*
X1306486D01*
X1303796Y1015609D01*
X1278764D01*
G01X1316878Y1030155D02*
X1306630D01*
X1294921Y1041864D01*
X1277461D01*
G01X1311268Y1050398D02*
X1310515D01*
X1302205Y1058708D01*
X1269227D01*
X1267471Y1060464D01*
G01X1311278Y1051801D02*
X1301902Y1061177D01*
X1279227D01*
X1277419Y1062985D01*
G01X1320360Y1040218D02*
X1319814Y1040764D01*
Y1041864D01*
X1318559Y1043119D01*
X1310271D01*
X1309711Y1042887D01*
X1307989D01*
X1300612Y1050264D01*
X1281841D01*
X1275830Y1056275D01*
G01X1321777Y1074619D02*
X1320603D01*
X1320563Y1074659D01*
X1307867D01*
X1305673Y1076853D01*
X1265784D01*
G01X1314070Y1086595D02*
X1312160Y1088505D01*
X1288507D01*
X1283962Y1093050D01*
X1271087D01*
G01X1309466Y1091586D02*
X1304171Y1096881D01*
X1273878D01*
X1270528Y1100231D01*
G01X1309985Y1093164D02*
X1304694Y1098455D01*
X1277304D01*
X1275528Y1100231D01*
G01X1278150Y1672007D02*
Y1664088D01*
X1274548Y1660486D01*
G01X1292899Y98519D02*
X1287641Y103777D01*
Y111980D01*
G01X1294354Y103166D02*
X1294357Y103163D01*
X1297821D01*
G01X1291704Y103156D02*
X1294847Y100013D01*
X1297821D01*
G01X1297884Y120072D02*
Y115068D01*
X1300810Y112142D01*
Y103002D01*
X1297821Y100013D01*
G01X1291704Y115169D02*
X1295806D01*
X1295807Y115168D01*
G01X1294751Y133852D02*
Y117642D01*
X1295807Y116586D01*
Y115168D01*
G01X1291311Y152073D02*
X1290911Y151673D01*
X1290251Y150081D01*
X1286268Y146098D01*
Y144365D01*
X1288111Y142522D01*
Y140444D01*
X1287220Y139553D01*
Y134893D01*
X1290394Y131719D01*
Y123858D01*
X1283485Y116950D01*
Y115130D01*
G01X1293802Y159299D02*
Y155252D01*
X1293380Y154830D01*
Y150502D01*
X1290300Y147422D01*
Y140183D01*
X1289150Y139033D01*
Y136083D01*
X1291909Y133324D01*
Y123272D01*
X1287641Y119006D01*
Y115130D01*
G01X1297012Y157449D02*
X1295693Y156130D01*
Y154594D01*
X1294569Y153470D01*
Y149059D01*
X1293412Y147902D01*
Y145320D01*
X1294191Y143439D01*
Y142317D01*
X1293059Y141185D01*
Y139430D01*
X1294751Y137738D01*
Y133852D01*
G01X1297086Y153810D02*
Y148318D01*
X1295701Y146933D01*
Y145397D01*
X1297100Y142019D01*
Y137039D01*
X1297753Y136386D01*
Y121113D01*
X1297884Y120982D01*
Y120072D01*
G01X1292304Y157842D02*
Y156080D01*
X1291860Y155636D01*
Y153399D01*
X1291311Y152073D01*
G01X1288758Y163728D02*
X1286513Y161483D01*
G01X1296999Y198149D02*
Y199777D01*
X1296574Y200202D01*
X1291814D01*
X1290734Y199122D01*
G01X1285899Y196392D02*
X1297329D01*
X1299114Y194607D01*
X1300595D01*
X1302532Y192670D01*
X1303937D01*
X1305874Y190733D01*
X1307621D01*
X1308381Y189973D01*
Y187999D01*
X1307431Y187049D01*
X1303407D01*
G01X1291194Y188899D02*
X1289706Y190387D01*
X1285848D01*
G01X1300204Y188899D02*
X1291194D01*
G01X1296999Y216649D02*
X1292925D01*
X1292038Y215762D01*
X1284383D01*
G01X1300220Y218499D02*
X1300218Y218497D01*
Y217087D01*
X1298093Y214962D01*
X1296593D01*
X1294593Y212962D01*
X1293273D01*
X1287582Y207271D01*
X1284746D01*
G01X1291983Y208562D02*
X1293683D01*
X1296999Y211878D01*
Y212949D01*
G01Y205549D02*
Y205527D01*
X1295474Y204002D01*
X1288904D01*
G01X1303422Y220349D02*
X1292782D01*
X1292128Y221003D01*
X1286652D01*
X1285393Y222262D01*
G01X1296999Y224049D02*
Y224062D01*
X1296993Y224068D01*
Y225662D01*
X1292554Y230101D01*
G01D02*
Y233217D01*
X1284204Y241567D01*
X1284120D01*
G01X1293807Y218499D02*
X1289739D01*
G01X1305117Y797125D02*
X1299962Y791970D01*
Y790092D01*
X1295808Y785938D01*
X1294895Y783734D01*
Y773760D01*
X1296937Y771718D01*
Y745639D01*
X1295147Y743849D01*
Y742605D01*
X1293047Y740505D01*
Y731350D01*
X1292007Y730310D01*
G01X1299327Y765475D02*
Y744545D01*
X1297577Y742795D01*
Y741175D01*
X1295387Y738985D01*
Y735860D01*
X1295947Y735300D01*
G01Y732150D02*
Y728300D01*
G01X1289817Y740995D02*
X1292937Y744115D01*
Y754585D01*
X1287727Y759795D01*
Y840543D01*
X1305288Y858104D01*
G01X1284797Y745260D02*
X1284637Y745420D01*
Y853253D01*
X1287674Y856290D01*
G01X1297298Y790982D02*
X1295550Y792730D01*
X1291879D01*
X1290059Y790910D01*
Y760749D01*
X1294937Y755871D01*
Y752540D01*
G01X1309210Y792802D02*
X1308860Y792452D01*
X1303894D01*
X1302680Y791238D01*
Y789434D01*
X1298020Y784774D01*
X1297379Y783229D01*
Y775202D01*
X1299327Y773254D01*
Y765475D01*
G01X1307538Y883114D02*
X1305764Y881340D01*
X1301365D01*
X1285316Y865291D01*
G01X1291306Y863361D02*
X1304409Y876464D01*
X1305114D01*
X1308414Y879764D01*
G01X1287674Y856290D02*
X1305838Y874454D01*
X1308150D01*
X1310124Y876428D01*
Y877527D01*
X1310512Y877915D01*
G01X1307134Y880344D02*
X1304920Y878130D01*
X1302552D01*
X1295535Y871113D01*
G01X1313377Y922205D02*
X1309618Y925964D01*
X1295552D01*
X1292792Y928724D01*
G01X1305421Y918785D02*
X1304851Y919355D01*
X1290507D01*
X1288257Y921605D01*
G01X1319903Y999684D02*
X1313675Y993456D01*
Y982125D01*
X1302305Y970755D01*
X1296637D01*
G01X1396603Y1039136D02*
X1386299D01*
X1380715Y1033552D01*
Y1029481D01*
X1378201Y1026967D01*
X1305738D01*
X1294241Y1038464D01*
X1284922D01*
G01X1318648Y1046021D02*
X1318532Y1046137D01*
X1307503D01*
X1301578Y1052062D01*
X1287543D01*
X1283850Y1055755D01*
Y1055776D01*
X1283822Y1055804D01*
G01X1319302Y1047371D02*
X1308757D01*
X1302737Y1053391D01*
X1294374D01*
X1291775Y1055990D01*
G01X1317325Y1069460D02*
X1288529D01*
G01X1315146Y1064495D02*
X1314600Y1065041D01*
X1297380D01*
X1296478Y1064139D01*
G01X1671660Y1569412D02*
X1669950Y1571122D01*
Y1604122D01*
X1625210Y1648862D01*
X1474580D01*
X1471142Y1652300D01*
X1402300D01*
X1388600Y1638600D01*
X1383500D01*
X1376600Y1645500D01*
X1308122D01*
X1290360Y1663262D01*
Y1730862D01*
X1287010Y1734212D01*
X1286024D01*
G01X1293898Y1672007D02*
Y1663552D01*
X1296930Y1660520D01*
G01X1386200Y1645700D02*
X1382550Y1649350D01*
X1308150D01*
X1296980Y1660520D01*
X1296930D01*
G01X1349480Y77072D02*
X1338799Y66391D01*
X1313685D01*
X1311424Y68652D01*
G01X1302080Y117032D02*
Y116582D01*
X1308920Y109742D01*
Y107262D01*
X1308232Y106574D01*
X1307237Y106162D01*
X1306720D01*
X1305095Y104537D01*
Y99262D01*
G01X1310000Y113552D02*
Y119137D01*
X1309228Y121001D01*
Y121993D01*
G01X1302060Y113852D02*
X1303220Y112692D01*
Y110637D01*
G01X1303728Y130365D02*
X1303680Y130317D01*
X1299890D01*
G01X1302509Y134795D02*
Y131584D01*
X1303728Y130365D01*
G01X1302293Y154927D02*
Y152361D01*
X1302593Y152061D01*
Y145835D01*
X1299820Y143062D01*
Y137484D01*
X1302509Y134795D01*
G01X1308825Y136721D02*
Y133504D01*
X1310150Y132179D01*
G01X1310880Y143431D02*
Y139802D01*
X1311720Y138962D01*
Y134662D01*
X1312355Y134027D01*
Y128810D01*
X1314269Y126896D01*
Y125188D01*
G01X1305115Y142712D02*
Y132768D01*
X1307728Y130155D01*
Y126643D01*
X1309228Y125143D01*
G01X1309832Y157449D02*
Y154449D01*
X1311844Y152437D01*
Y151973D01*
X1315353Y148464D01*
Y146030D01*
G01X1306626Y162999D02*
X1305022Y160224D01*
X1305021D01*
G03Y158374I1605J-925D01*
G02X1305088Y158124I-433J-250D01*
G01Y153381D01*
X1306613Y151856D01*
Y149128D01*
X1308825Y146916D01*
Y136721D01*
G01X1306626Y159299D02*
Y154013D01*
X1308319Y152320D01*
Y150265D01*
X1310880Y147704D01*
Y143431D01*
G01X1321747Y136899D02*
Y139438D01*
X1317640Y143545D01*
Y148414D01*
X1311672Y154382D01*
Y157649D01*
G03X1311435Y158374I-1840J-200D01*
G02Y160224I1602J925D01*
G01X1313037Y162999D01*
G01X1309832Y164849D02*
X1308229Y162074D01*
G03Y160224I1603J-925D01*
G02Y158374I-1603J-925D01*
G03X1307984Y157557I1603J-926D01*
G01Y154393D01*
X1310328Y152049D01*
Y151001D01*
X1313181Y148148D01*
Y141601D01*
X1315020Y139762D01*
G01X1303417Y157449D02*
Y152942D01*
X1304603Y151756D01*
Y148295D01*
X1305115Y147783D01*
Y142712D01*
G01X1300217Y159299D02*
Y156954D01*
X1299193Y155930D01*
Y152308D01*
X1300481Y151020D01*
G01X1320880Y143430D02*
X1319650Y144660D01*
Y148684D01*
X1313037Y155297D01*
Y159299D01*
G01X1326826Y138922D02*
Y140516D01*
X1321707Y145635D01*
Y149089D01*
X1319794Y151002D01*
X1319056D01*
X1315770Y154288D01*
G01X1317332Y154270D02*
X1319210Y152392D01*
X1321124D01*
X1326974Y146542D01*
Y144338D01*
G01X1309049Y182865D02*
Y180417D01*
X1309817Y179649D01*
G01X1309918Y201187D02*
X1308384Y199653D01*
Y199181D01*
X1307352Y198149D01*
X1303407D01*
G01X1306190Y210502D02*
X1305807Y210119D01*
Y207940D01*
X1303416Y205549D01*
G01X1306614Y203699D02*
X1309189Y206274D01*
G01X1313033Y222199D02*
Y221539D01*
X1314800Y219772D01*
X1314970D01*
G01X1303425Y224049D02*
Y226020D01*
X1301235Y228210D01*
G01X1311420Y738262D02*
Y733087D01*
X1313132Y731375D01*
G01X1304707Y769984D02*
Y756136D01*
X1305277Y755566D01*
Y752870D01*
G01X1307627Y764735D02*
Y757555D01*
X1308847Y756335D01*
Y752870D01*
G01X1316307Y749720D02*
X1313597Y747010D01*
Y745370D01*
G01D02*
X1312292D01*
X1311420Y744498D01*
Y738262D01*
G01X1301487Y749720D02*
X1301777Y749430D01*
Y741930D01*
X1300317Y740470D01*
G01X1301927Y759935D02*
Y753310D01*
X1301487Y752870D01*
G01X1304260Y788265D02*
X1304889Y787636D01*
Y774927D01*
X1304707Y774745D01*
Y769984D01*
G01X1307469Y787772D02*
Y787373D01*
X1308027Y786815D01*
Y784625D01*
X1306967Y783565D01*
Y774845D01*
X1307627Y774185D01*
Y764735D01*
G01X1301034Y784165D02*
X1301397D01*
X1303037Y782525D01*
Y777505D01*
X1301927Y776395D01*
Y759935D01*
G01X1309930Y789852D02*
X1309865Y789695D01*
X1311327Y786165D01*
Y773755D01*
X1314227Y770855D01*
G01D02*
X1316307Y768775D01*
Y752870D01*
G01X1320032Y775725D02*
X1320254Y776412D01*
X1310930Y794659D01*
X1307806Y795441D01*
X1306701Y794779D01*
G01X1316500Y851513D02*
X1316147Y851160D01*
Y849590D01*
X1308177Y841620D01*
Y802776D01*
X1323345Y787608D01*
Y769844D01*
G01X1328187Y774757D02*
Y786524D01*
X1310836Y803875D01*
Y840214D01*
X1316547Y845925D01*
Y847675D01*
X1317995Y849123D01*
Y850835D01*
G01X1318245Y846005D02*
Y842140D01*
X1313587Y837482D01*
Y804835D01*
X1332947Y785475D01*
Y767085D01*
G01X1305288Y858104D02*
X1318669Y871485D01*
X1320948D01*
G01X1323171Y877014D02*
X1322011D01*
X1320402Y875405D01*
X1316127D01*
X1311407Y870685D01*
Y868055D01*
G01X1313869Y877657D02*
Y875671D01*
X1311531Y873333D01*
X1310057D01*
X1309164Y872440D01*
X1306809D01*
X1298830Y864461D01*
G01X1309922Y890470D02*
X1307717Y888265D01*
G01X1316837Y1034315D02*
X1310200D01*
X1300851Y1043664D01*
G01X1311798Y1054354D02*
X1312786D01*
X1314317Y1055885D01*
X1314733D01*
G01X1305878Y1062943D02*
X1307682Y1061139D01*
X1310777D01*
X1311860Y1062222D01*
X1313826D01*
G01X1307032Y1058856D02*
X1309215Y1056673D01*
X1312845D01*
X1313698Y1057526D01*
X1315995D01*
G01X1311780Y1058894D02*
X1315882D01*
G01X1311937Y1048974D02*
X1309565D01*
X1303135Y1055404D01*
X1299240D01*
X1298540Y1056104D01*
G01X1309194Y1655255D02*
X1300865Y1663584D01*
Y1733226D01*
X1301851Y1734212D01*
X1305709D01*
G01X1313583Y1672007D02*
Y1660466D01*
G01X1386600Y1641400D02*
X1388700Y1643500D01*
Y1647300D01*
X1384900Y1651100D01*
X1317100D01*
X1313583Y1654617D01*
Y1660466D01*
G01X1315353Y146030D02*
Y142988D01*
X1319216Y139125D01*
Y134843D01*
X1320919Y133140D01*
Y126808D01*
X1319288Y125177D01*
G01X1323493Y132305D02*
Y134305D01*
X1322041Y135757D01*
Y136605D01*
X1321747Y136899D01*
G01X1315020Y139762D02*
Y139362D01*
X1317320Y137062D01*
Y133852D01*
X1317891Y133281D01*
Y132178D01*
G01X1327428Y126352D02*
Y127612D01*
X1326473Y128567D01*
Y135011D01*
X1324359Y137125D01*
Y139951D01*
X1320880Y143430D01*
G01X1332497Y133931D02*
X1332073Y134355D01*
X1328946D01*
G01D02*
Y136420D01*
X1326826Y138540D01*
Y138922D01*
G01X1322693Y155262D02*
X1334481Y143474D01*
Y138672D01*
X1341718Y131435D01*
Y130781D01*
G01X1316241Y157449D02*
X1317369D01*
X1318145Y156673D01*
Y155221D01*
X1319774Y153592D01*
X1321638D01*
X1328341Y146889D01*
Y145950D01*
X1332002Y142289D01*
G01X1326974Y144338D02*
Y142433D01*
X1334679Y134728D01*
Y131075D01*
X1332886Y129282D01*
G01X1325179Y155848D02*
X1336131Y144896D01*
Y139682D01*
X1342841Y132972D01*
X1344581D01*
X1348079Y129474D01*
G01X1336819Y150298D02*
Y153317D01*
X1332754Y157382D01*
X1331754D01*
X1330021Y159115D01*
X1326617D01*
X1324897Y160835D01*
Y161420D01*
X1323318Y162999D01*
X1319452D01*
G01X1325304Y157891D02*
X1325720Y157475D01*
X1326433D01*
X1337750Y146158D01*
Y140513D01*
X1343511Y134752D01*
X1346043D01*
X1351633Y129162D01*
X1355004D01*
X1355881Y128285D01*
X1355987D01*
G01X1363266Y155703D02*
X1365697Y158134D01*
Y162426D01*
X1363249Y164874D01*
X1354777D01*
X1352821Y166830D01*
X1352099D01*
X1350220Y164951D01*
X1348359D01*
X1346840Y166470D01*
X1345169D01*
X1343649Y164950D01*
X1341883D01*
X1340288Y166545D01*
X1334458D01*
X1332483Y164570D01*
X1331420D01*
X1329939Y163089D01*
X1327451D01*
X1326844Y163696D01*
X1325381D01*
X1324228Y164849D01*
X1322652D01*
G01X1329062Y157449D02*
X1330299Y156212D01*
X1330894D01*
X1332654Y154452D01*
G01X1329620Y227682D02*
X1330070Y227232D01*
Y225672D01*
X1331130Y224612D01*
Y223762D01*
X1330570Y223202D01*
Y221162D01*
X1329757Y220349D01*
X1329062D01*
G01X1317567Y745380D02*
X1319677Y743270D01*
Y735090D01*
X1321816Y732951D01*
Y729244D01*
G01X1328745Y732336D02*
X1326358Y734723D01*
Y737747D01*
G01X1323208D02*
Y741707D01*
G01X1320032Y752870D02*
Y775725D01*
G01Y749720D02*
X1317567Y747255D01*
Y745380D01*
G01X1323345Y769844D02*
Y749053D01*
X1322297Y748005D01*
Y742618D01*
X1323208Y741707D01*
G01X1334298Y741727D02*
Y744268D01*
X1333831Y744735D01*
X1328126D01*
X1325955Y746906D01*
Y752576D01*
X1328187Y754808D01*
Y774757D01*
G01X1334298Y738577D02*
X1330338D01*
X1330328Y738567D01*
G01X1319845Y847135D02*
Y839892D01*
X1316257Y836304D01*
Y805944D01*
X1338495Y783706D01*
Y774984D01*
G01X1316092Y1054750D02*
Y1053513D01*
G01X1318151Y1655269D02*
Y1733585D01*
X1318778Y1734212D01*
X1321457D01*
G01X1329331Y1672007D02*
Y1660390D01*
G01X1348610Y84712D02*
X1348930Y84392D01*
X1351960D01*
X1354820Y87252D01*
Y109383D01*
X1345166Y119037D01*
Y120618D01*
G01X1342016D02*
Y124718D01*
G01X1341718Y130781D02*
Y125016D01*
X1342016Y124718D01*
G01X1332002Y142289D02*
Y139249D01*
X1336929Y134322D01*
Y127283D01*
X1336930Y127282D01*
G01X1342525Y149507D02*
X1337610D01*
X1336819Y150298D01*
G01X1339481Y154705D02*
X1340834Y153352D01*
X1345075D01*
X1346604Y151823D01*
Y149507D01*
G01X1343034Y141698D02*
X1346550Y138182D01*
X1352765D01*
X1353850Y137097D01*
G01X1339727Y161149D02*
X1337853Y159275D01*
Y156333D01*
X1339481Y154705D01*
G01X1332268Y162999D02*
Y159982D01*
G01X1337637Y162994D02*
X1335782Y164849D01*
X1335472D01*
G01X1357514Y150092D02*
X1350964Y156642D01*
Y160402D01*
X1349954Y161412D01*
X1348484D01*
X1346897Y162999D01*
X1342937D01*
G01X1351165Y150861D02*
X1346140Y155886D01*
Y157449D01*
G01X1339059Y212239D02*
X1338505D01*
X1337890Y211624D01*
Y208730D01*
X1339045Y207575D01*
G01D02*
X1339518Y207102D01*
X1340176D01*
X1340440Y207366D01*
Y208536D01*
X1339727Y209249D01*
G01X1337697Y728652D02*
Y746378D01*
X1334641Y749434D01*
G01X1330888Y752584D02*
X1330979Y752493D01*
X1332930D01*
X1332931Y752492D01*
X1334549D01*
X1334641Y752584D01*
G01X1332947Y767085D02*
X1330888Y765026D01*
Y752584D01*
G01X1338495Y774984D02*
X1340757Y772722D01*
Y751488D01*
X1338495Y749226D01*
G01X1333709Y1655241D02*
Y1733859D01*
X1334062Y1734212D01*
X1337205D01*
G01X1345079Y1672007D02*
Y1660508D01*
G01X1393250Y93802D02*
Y89582D01*
X1382550Y78882D01*
X1365380D01*
X1361920Y82342D01*
Y110323D01*
X1355987Y116256D01*
Y124123D01*
G01X1378839Y87626D02*
X1369130D01*
X1368620Y88136D01*
Y110862D01*
X1362587Y116895D01*
Y124123D01*
G01X1355987Y128285D02*
Y124123D01*
G01X1352167Y120618D02*
Y124718D01*
G01X1348079Y129474D02*
X1351014Y126539D01*
Y125523D01*
X1351819Y124718D01*
X1352167D01*
G01X1352550Y157449D02*
X1357757D01*
X1364844Y150362D01*
Y133782D01*
G01X1348386Y156646D02*
X1353894Y151138D01*
Y144872D01*
G01X1362564Y161142D02*
X1354994D01*
X1353137Y162999D01*
X1349344D01*
G01X1356220Y581862D02*
Y591243D01*
X1383612Y618635D01*
X1468291D01*
X1480297Y630641D01*
Y649145D01*
X1494767Y663615D01*
Y678872D01*
X1534376Y718481D01*
X1539113Y725569D01*
X1551354Y755116D01*
X1572300Y776062D01*
Y790072D01*
X1582017Y799789D01*
Y893008D01*
G01X1356047Y680000D02*
Y698805D01*
X1368547Y711305D01*
X1389167D01*
X1399806Y721944D01*
X1426525D01*
G01X1361727Y680665D02*
X1364357Y683295D01*
Y685725D01*
X1368657Y690025D01*
X1382697D01*
X1389297Y696625D01*
X1391277D01*
X1397537Y702885D01*
X1435488D01*
X1442957Y710354D01*
Y718252D01*
X1449118Y724413D01*
G01X1365737Y128285D02*
Y124123D01*
G01X1364844Y133782D02*
Y129178D01*
X1365737Y128285D01*
G01X1370207Y682245D02*
X1368737Y683715D01*
Y685645D01*
X1370907Y687815D01*
X1388903D01*
X1395141Y690399D01*
X1405497Y700755D01*
X1436137D01*
X1444667Y709285D01*
Y715862D01*
X1453218Y724413D01*
G01X1367889Y1419235D02*
X1369475Y1417649D01*
Y1416491D01*
G01X1372625D02*
Y1412791D01*
G01X1382157Y1408975D02*
X1376441D01*
X1372625Y1412791D01*
G01X1370577Y1421899D02*
X1380859D01*
X1381370Y1421388D01*
Y1417304D01*
G01X1381235Y236020D02*
X1383143Y234112D01*
X1385854D01*
X1386930Y235188D01*
G01X1392997Y1415275D02*
Y1419228D01*
X1392400Y1419825D01*
G01X1387470Y1418302D02*
X1385518D01*
X1384520Y1417304D01*
G01X1392400Y1419825D02*
X1390943D01*
X1389420Y1418302D01*
X1387470D01*
G01X1385109Y1410427D02*
X1383657Y1408975D01*
X1382157D01*
G01X1387068Y1413991D02*
X1384719D01*
X1384520Y1413792D01*
G01X1404571Y924100D02*
X1402212D01*
X1401971Y924341D01*
G01X1467587Y770665D02*
X1491747D01*
X1506367Y785285D01*
X1514058D01*
X1524674Y795901D01*
Y850387D01*
X1524966Y850679D01*
Y878060D01*
G01X1491828Y766875D02*
X1508238Y783285D01*
X1514487D01*
X1526566Y795364D01*
Y878605D01*
G01X1479870Y763842D02*
X1492728D01*
X1510451Y781565D01*
X1515187D01*
X1528276Y794654D01*
Y878765D01*
X1527916Y879125D01*
G01X1432125Y924530D02*
X1430083D01*
X1429355Y923802D01*
G01X1527931Y1050818D02*
X1529944D01*
X1530577Y1050185D01*
X1536277D01*
X1544337Y1042125D01*
G01X1543727Y1021175D02*
X1541463D01*
X1526143Y1036495D01*
X1523181D01*
G01X1527647Y1052545D02*
X1532288D01*
G01X1423256Y1403728D02*
X1423335D01*
X1425150Y1401913D01*
X1428690D01*
X1428725Y1401948D01*
G01X1425840Y1408229D02*
X1424840D01*
X1424333Y1407722D01*
X1422371D01*
G01X1418870Y1406742D02*
X1415237D01*
X1414190Y1407789D01*
G01X1422371Y1407722D02*
X1421391Y1406742D01*
X1418870D01*
G01X1431430Y256383D02*
Y255442D01*
X1485670Y201202D01*
X1523250D01*
X1527140Y197312D01*
X1532660D01*
X1534720Y199372D01*
Y199803D01*
G01X1431430Y264060D02*
X1438470Y257020D01*
Y250467D01*
X1486275Y202662D01*
X1527890D01*
X1528720Y201832D01*
Y199862D01*
G01X1463950Y258172D02*
X1461840Y256062D01*
X1458820D01*
X1447504Y267378D01*
X1431431D01*
G01X1434597Y717132D02*
X1437156D01*
G01D02*
X1437122Y717098D01*
Y712575D01*
G01X1432487Y712485D02*
X1437032D01*
X1437122Y712575D01*
G01X1429675Y721944D02*
X1429672Y721941D01*
Y717865D01*
G01X1434835Y732212D02*
Y732295D01*
X1436271Y733731D01*
Y749839D01*
X1457097Y770665D01*
X1467587D01*
G01X1434835Y732212D02*
Y732129D01*
X1439715Y727249D01*
Y724612D01*
G01X1429675Y721944D02*
Y724284D01*
X1430097Y724706D01*
Y726635D01*
G01D02*
X1436437D01*
X1437156Y725916D01*
Y724612D01*
G01X1446071Y735656D02*
X1448996D01*
X1449797Y734855D01*
Y731045D01*
X1448934Y730182D01*
X1440150D01*
G01D02*
X1442769Y727563D01*
X1445018D01*
G01X1438457Y737565D02*
X1443220Y732802D01*
X1446071D01*
G01X1480250Y757753D02*
X1483742Y761245D01*
X1492974D01*
X1511104Y779375D01*
X1515841D01*
X1530286Y793820D01*
Y879797D01*
X1521677Y888406D01*
X1515824D01*
G01X1518967Y891005D02*
X1516252D01*
G01X1520528Y917924D02*
X1517597D01*
X1514995Y915322D01*
X1513847D01*
G01X1531827Y913665D02*
X1530007Y915485D01*
X1523157D01*
X1521887Y914215D01*
X1519447D01*
G01X1527257Y917665D02*
X1523397D01*
X1521597Y915865D01*
X1518387D01*
X1517437Y914915D01*
G01X1530185Y757790D02*
Y761227D01*
X1551641Y782683D01*
Y898144D01*
X1531556Y918229D01*
X1527126Y920064D01*
X1517717D01*
X1514376Y916723D01*
X1513097D01*
G01X1521528Y1031364D02*
X1515679D01*
X1513664Y1033379D01*
X1511857D01*
G01X1513732Y1026693D02*
X1514710Y1025715D01*
X1528949D01*
X1538393Y1016271D01*
G01X1540227Y1027095D02*
X1538466D01*
X1527317Y1038244D01*
X1523181D01*
G01X1522746Y1048368D02*
X1519804D01*
X1519310Y1048862D01*
G01X1524437Y1050398D02*
X1524716D01*
X1526746Y1048368D01*
G01X1588459Y1068895D02*
X1579499D01*
X1574619Y1064015D01*
X1528329D01*
X1527389Y1063075D01*
X1524037D01*
X1522820Y1064292D01*
X1513320D01*
X1511213Y1062185D01*
X1435609D01*
X1433989Y1060565D01*
X1432753D01*
G01X1567737Y1036815D02*
X1545975Y1058577D01*
X1536977D01*
X1536976Y1058576D01*
X1514784D01*
G01X1516241Y1056024D02*
X1535688D01*
X1537108Y1054604D01*
X1538898D01*
X1543667Y1049835D01*
G01X1515765Y1057097D02*
X1537526D01*
X1537527Y1057098D01*
X1541554D01*
X1555937Y1042715D01*
G01X1520737Y1061993D02*
X1515154D01*
G01X1450270Y143022D02*
Y144182D01*
X1451450Y145362D01*
X1453145D01*
G01X1464645D02*
X1462145Y142862D01*
X1455645D01*
X1453145Y145362D01*
G01X1448820Y148092D02*
X1450090Y149362D01*
X1453145D01*
G01X1464645Y169862D02*
X1462645Y167862D01*
X1455220D01*
X1453220Y169862D01*
X1453145D01*
G01Y153362D02*
X1450720D01*
G01X1453145Y161862D02*
X1450720D01*
G01X1449740Y166912D02*
X1450790Y165862D01*
X1453145D01*
G01X1447340Y157402D02*
X1447800Y157862D01*
X1453145D01*
G01X1450720Y169862D02*
X1453145D01*
G01Y181862D02*
X1450720D01*
G01X1453145Y177862D02*
X1450720D01*
G01X1453145Y173862D02*
X1450720D01*
G01X1458818Y724413D02*
X1458727Y724504D01*
X1457078D01*
X1456987Y724413D01*
X1455049D01*
X1454958Y724504D01*
X1453309D01*
X1453218Y724413D01*
G01X1446071Y738216D02*
X1448877D01*
X1455692Y731401D01*
G01D02*
X1457027Y730066D01*
Y729270D01*
X1458734Y727563D01*
X1458818D01*
G01X1449118Y724413D02*
X1445018D01*
G01X1502745Y759915D02*
X1513925Y771095D01*
X1518637D01*
X1538116Y790574D01*
Y881664D01*
X1531385Y888395D01*
Y889314D01*
X1522424Y898275D01*
X1516713D01*
G01X1489387Y757925D02*
X1493347D01*
X1512117Y776695D01*
X1516853D01*
X1532896Y792738D01*
Y880056D01*
X1518938Y894014D01*
X1517250D01*
G01X1496813Y757699D02*
X1513029Y773915D01*
X1517765D01*
X1535506Y791656D01*
Y880334D01*
X1528382Y887458D01*
Y890520D01*
X1522960Y895942D01*
X1516825D01*
X1516503Y895620D01*
G01X1540426Y855555D02*
Y882677D01*
X1522838Y900265D01*
X1517266D01*
G01X1517784Y901372D02*
X1523419D01*
X1542481Y882310D01*
Y789428D01*
X1520198Y767145D01*
X1514946D01*
X1505947Y758146D01*
Y751745D01*
X1507002Y750690D01*
Y746256D01*
X1502401Y741655D01*
Y741315D01*
G01X1510557Y747202D02*
Y748634D01*
X1509207Y749984D01*
Y758465D01*
X1515866Y765124D01*
X1519786D01*
X1543591Y788929D01*
Y882982D01*
X1523832Y902741D01*
X1513865D01*
G01X1531403Y765791D02*
X1549331Y783719D01*
Y888130D01*
X1526806Y910655D01*
X1520697D01*
G01X1515642Y903840D02*
X1525972D01*
X1540800Y889012D01*
G01X1523197Y759045D02*
Y760935D01*
X1547921Y785659D01*
Y887182D01*
X1526299Y908804D01*
X1523843D01*
G01X1518017Y757455D02*
X1546811Y786249D01*
Y886100D01*
X1525339Y907572D01*
X1523536D01*
G01X1535622Y905170D02*
X1526637Y914155D01*
X1524097D01*
X1522177Y912235D01*
X1520817D01*
G01X1448971Y921875D02*
Y923647D01*
X1450997Y925673D01*
G01X1455650Y962400D02*
X1456778D01*
X1458014Y961164D01*
Y960036D01*
X1459331Y958719D01*
X1515033D01*
X1517449Y956303D01*
Y946856D01*
X1518341Y945964D01*
X1535518D01*
X1544993Y936489D01*
G01X1514567Y966419D02*
X1517141D01*
X1520949Y962611D01*
Y953656D01*
X1523141Y951464D01*
X1532855D01*
X1532856Y951465D01*
X1543042D01*
G01X1514467Y965007D02*
X1515341D01*
X1519300Y961048D01*
Y951105D01*
X1522349Y948056D01*
X1535580D01*
G01X1530847Y978075D02*
X1526307Y982615D01*
X1518504D01*
X1516698Y984421D01*
X1502303D01*
X1498910Y981028D01*
X1498247D01*
G01X1497336Y982785D02*
X1501343Y986792D01*
X1522907D01*
G01X1510977Y971588D02*
X1518655D01*
X1522279Y967964D01*
X1525114D01*
X1527114Y965964D01*
X1536264D01*
X1536265Y965965D01*
X1536837D01*
G01X1532107Y971957D02*
X1529297Y974767D01*
X1508913D01*
X1508312Y975368D01*
X1501667D01*
G01X1513964Y1028159D02*
X1515770D01*
G01X1456804Y1025318D02*
G02X1459361Y1024019I-528J-4205D01*
G03X1461428Y1023716I1225J1154D01*
G02X1463225Y1023747I926J-1602D01*
G01X1463278Y1023716D01*
G03X1465128I925J1602D01*
G02X1466925Y1023747I926J-1602D01*
G01X1466978Y1023716D01*
G03X1468828I925J1602D01*
G02X1470625Y1023747I926J-1602D01*
G01X1470678Y1023716D01*
G03X1472528I925J1602D01*
G02X1474325Y1023747I926J-1602D01*
G01X1474378Y1023716D01*
G03X1476228I925J1602D01*
G02X1478025Y1023747I926J-1602D01*
G01X1478078Y1023716D01*
G03X1479928I925J1602D01*
G02X1481725Y1023747I926J-1602D01*
G01X1481778Y1023716D01*
G03X1483628I925J1602D01*
G02X1485425Y1023747I926J-1602D01*
G01X1485478Y1023716D01*
G03X1487328I925J1602D01*
G02X1489125Y1023747I926J-1602D01*
G01X1489178Y1023716D01*
G03X1491028I925J1602D01*
G02X1492825Y1023747I926J-1602D01*
G01X1492878Y1023716D01*
G03X1494728I925J1602D01*
G02X1496525Y1023747I926J-1602D01*
G01X1496578Y1023716D01*
G03X1498428I925J1602D01*
G02X1500225Y1023747I926J-1602D01*
G01X1500278Y1023716D01*
G03X1502128I925J1602D01*
G02X1503925Y1023747I926J-1602D01*
G01X1503978Y1023716D01*
G03X1505828I925J1602D01*
G02X1507625Y1023747I926J-1602D01*
G01X1507678Y1023716D01*
G03X1509349Y1023625I925J1602D01*
G02X1510095Y1023782I746J-1693D01*
G01X1513597D01*
X1515902Y1021477D01*
X1524735D01*
X1526427Y1019785D01*
G01X1523614Y1011464D02*
X1517614D01*
X1516041Y1013037D01*
Y1015905D01*
G01X1510453Y1043565D02*
X1512151D01*
X1512483Y1043233D01*
G01X1515417Y1040094D02*
X1529294D01*
X1534273Y1035115D01*
X1540157D01*
X1545047Y1030225D01*
G01X1513687Y1041181D02*
X1514898Y1042392D01*
X1531280D01*
X1535797Y1037875D01*
G01X1530467Y1045234D02*
X1529328Y1044095D01*
X1519197D01*
X1516801Y1046491D01*
X1515824D01*
G01X1515834Y1048035D02*
X1518103D01*
X1520334Y1045804D01*
X1527454D01*
X1529685Y1048035D01*
X1534799D01*
X1536273Y1046561D01*
G01X1459431Y1398970D02*
X1463249D01*
G01X1455734D02*
X1459431D01*
G01X1459968Y1402765D02*
Y1401415D01*
X1459431Y1400878D01*
Y1398970D01*
G01X1521115Y193262D02*
X1490570D01*
X1474280Y209552D01*
X1472525D01*
X1472335Y209362D01*
G01X1509040Y243362D02*
X1505100D01*
X1490540Y257922D01*
X1476554D01*
X1471510Y252878D01*
G01X1463197Y735656D02*
X1467841D01*
X1469067Y734430D01*
G01X1474000Y739362D02*
X1469068Y734430D01*
X1469067D01*
G01X1463197Y738216D02*
X1468603D01*
X1468947Y738560D01*
G01X1470656Y749226D02*
Y747735D01*
X1473717Y744674D01*
G01D02*
Y742078D01*
X1470199Y738560D01*
X1468947D01*
G01X1474656Y749226D02*
X1476197Y747685D01*
Y740215D01*
X1475344Y739362D01*
X1474000D01*
G01X1470656Y752376D02*
Y759118D01*
X1478413Y766875D01*
X1491828D01*
G01X1474656Y752376D02*
Y758628D01*
X1479870Y763842D01*
G01X1482751Y752377D02*
X1486741D01*
G01D02*
Y755279D01*
X1489387Y757925D01*
G01X1490992Y752739D02*
Y753830D01*
X1492437Y755275D01*
X1494389D01*
X1496813Y757699D01*
G01X1490992Y752739D02*
X1490994Y752737D01*
X1494963D01*
G01X1478656Y752376D02*
Y756159D01*
X1480250Y757753D01*
G01X1493700Y1665900D02*
X1491400Y1663600D01*
X1480800D01*
G01X1508959Y215802D02*
Y217967D01*
X1509183Y218191D01*
X1511593D01*
X1512103Y217681D01*
Y210485D01*
X1512613Y209975D01*
X1514103D01*
X1514613Y210485D01*
Y217681D01*
X1515123Y218191D01*
X1521899D01*
X1524539Y215551D01*
G01X1503020Y215802D02*
Y218822D01*
X1506957Y222759D01*
X1532927D01*
X1535561Y225393D01*
G01X1506600Y239092D02*
X1504473Y236965D01*
X1503751D01*
X1499459Y241257D01*
X1498737D01*
X1497684Y240204D01*
Y239482D01*
X1501976Y235190D01*
Y234468D01*
X1500923Y233415D01*
X1500201D01*
X1495909Y237707D01*
X1495187D01*
X1494134Y236654D01*
Y235932D01*
X1495841Y234225D01*
Y233505D01*
X1493583Y231246D01*
Y230526D01*
X1494638Y229471D01*
X1495358D01*
X1497616Y231730D01*
X1498336D01*
X1500120Y229946D01*
Y228692D01*
X1496720Y225292D01*
G01X1501840Y225502D02*
X1504044Y227706D01*
X1517957D01*
X1518467Y228216D01*
Y238486D01*
X1518977Y238996D01*
X1520467D01*
X1520977Y238486D01*
Y228216D01*
X1521487Y227706D01*
X1522977D01*
X1523487Y228216D01*
Y238486D01*
X1523997Y238996D01*
X1525487D01*
X1525997Y238486D01*
Y228216D01*
X1526507Y227706D01*
X1527486D01*
X1529670Y225522D01*
G01X1505297Y671325D02*
Y675265D01*
X1542413Y712381D01*
X1546253Y718126D01*
X1557798Y745990D01*
X1564468Y752660D01*
X1573507D01*
G01X1577599Y752568D02*
X1580545Y749622D01*
Y747337D01*
X1580033Y746825D01*
X1575857D01*
X1572627Y743595D01*
X1559775D01*
X1557681Y741501D01*
X1547199Y716197D01*
X1543332Y710410D01*
X1508067Y675145D01*
Y664655D01*
G01X1494968Y732603D02*
X1496520Y734155D01*
Y738451D01*
X1499271Y741202D01*
X1502381D01*
X1502401Y741222D01*
Y741315D01*
G01X1507016Y734391D02*
X1507005Y734402D01*
X1502396D01*
G01X1507016Y734391D02*
X1511606D01*
X1513759Y736544D01*
Y741093D01*
X1510557Y744295D01*
Y747202D01*
G01X1499245Y752840D02*
Y756415D01*
X1502745Y759915D01*
G01X1499245Y749690D02*
X1499267Y749668D01*
Y745240D01*
G01X1503645Y752840D02*
Y757483D01*
X1514767Y768605D01*
X1520075D01*
X1540426Y788956D01*
Y855555D01*
G01X1502953Y1734212D02*
X1499891D01*
X1497858Y1732179D01*
Y1670058D01*
X1493700Y1665900D01*
G01X1533148Y211614D02*
X1530170Y214592D01*
X1527760D01*
X1526172Y213004D01*
X1523806D01*
X1523163Y213647D01*
X1518975D01*
X1518110Y214512D01*
Y215551D01*
G01X1512244Y311522D02*
X1511985D01*
X1510437Y313070D01*
Y313750D01*
G01X1514725Y312712D02*
X1513434D01*
X1512244Y311522D01*
G01X1521975Y752840D02*
X1527107Y757972D01*
Y761495D01*
X1531403Y765791D01*
G01X1517575Y744505D02*
X1515017Y747063D01*
Y750282D01*
X1517575Y752840D01*
G01X1540800Y889012D02*
X1545201Y884611D01*
Y787659D01*
X1520587Y763045D01*
X1516697D01*
X1513962Y760310D01*
Y756453D01*
X1517575Y752840D01*
G01X1522907Y986792D02*
X1526369D01*
X1593967Y919194D01*
Y788805D01*
X1589117Y783955D01*
Y775725D01*
X1583759Y770367D01*
Y753178D01*
X1584000Y752937D01*
G01X1594997Y761590D02*
Y763165D01*
X1600497Y768665D01*
Y776785D01*
X1603116Y779404D01*
Y933636D01*
X1599426Y937326D01*
X1587087D01*
X1571327Y953086D01*
Y997245D01*
X1550997Y1017575D01*
X1541427D01*
X1529947Y1029055D01*
X1523837D01*
X1521528Y1031364D01*
G01X1518701Y1734212D02*
X1519790D01*
X1523600Y1730402D01*
Y1657452D01*
X1528240Y1652812D01*
X1624660D01*
X1676150Y1601322D01*
Y1522142D01*
X1677930Y1520362D01*
G01X1529500Y125862D02*
X1526520Y122882D01*
Y118682D01*
X1529000Y116202D01*
X1539900D01*
X1543910Y120212D01*
X1667270D01*
X1679620Y107862D01*
X1691320D01*
X1698120Y114662D01*
X1713820D01*
X1718420Y110062D01*
X1726166D01*
X1728999Y112895D01*
G01X1529500Y122122D02*
X1532260D01*
X1534000Y123862D01*
Y126787D01*
G01X1527185Y752840D02*
X1530185Y755840D01*
Y757790D01*
G01X1527185Y749690D02*
Y746347D01*
X1526000Y745162D01*
G01X1535580Y948056D02*
X1537601D01*
X1582017Y903640D01*
G01X1530847Y978075D02*
X1591957Y916965D01*
Y790145D01*
X1586567Y784755D01*
Y776095D01*
X1582000Y771528D01*
Y759937D01*
G01X1538393Y1016271D02*
X1539969Y1014695D01*
X1549267D01*
X1569387Y994575D01*
Y953004D01*
X1586286Y936105D01*
X1598787D01*
X1602006Y932886D01*
Y780994D01*
X1599387Y778375D01*
Y769824D01*
X1591183Y761620D01*
X1590915D01*
G01X1550917Y704332D02*
Y706365D01*
X1559017Y714465D01*
Y719959D01*
X1568120Y729062D01*
Y731262D01*
X1568920Y732062D01*
X1578334D01*
X1600077Y753805D01*
Y762205D01*
X1603967Y766095D01*
Y771495D01*
X1608737Y776265D01*
Y780185D01*
X1610607Y782055D01*
Y926105D01*
X1610127Y926585D01*
Y928355D01*
X1610607Y928835D01*
Y934615D01*
X1602527Y942695D01*
X1594507D01*
X1575657Y961545D01*
Y998605D01*
X1547167Y1027095D01*
X1540227D01*
G01X1535797Y1037875D02*
X1540376D01*
X1580017Y998234D01*
Y962049D01*
X1596401Y945665D01*
X1607677D01*
X1611052Y942290D01*
X1613972D01*
X1616048Y940214D01*
Y772417D01*
X1611117Y767486D01*
Y766099D01*
X1606788Y761770D01*
G01X1610788D02*
X1615207Y766189D01*
Y769215D01*
X1617617Y771625D01*
Y942855D01*
X1614427Y946045D01*
X1610207D01*
X1606627Y949625D01*
X1595994D01*
X1581467Y964152D01*
Y998354D01*
X1534587Y1045234D01*
X1530467D01*
G01X1536273Y1046561D02*
X1582647Y1000187D01*
Y964542D01*
X1596384Y950805D01*
X1607827D01*
X1611257Y947375D01*
X1615877D01*
X1618917Y944335D01*
Y770625D01*
X1616757Y768465D01*
Y763739D01*
X1614788Y761770D01*
G01X1531011Y1660548D02*
Y1733120D01*
X1532103Y1734212D01*
X1534449D01*
G01X1780320Y153162D02*
X1747220D01*
X1726320Y132262D01*
X1716920D01*
X1714620Y134562D01*
X1712020D01*
X1705903Y140679D01*
X1563081D01*
X1556049Y147711D01*
G01X1542401Y141561D02*
X1551140Y150300D01*
X1701900D01*
X1711700Y140500D01*
Y140200D01*
G01X1550353Y217352D02*
X1548810Y215809D01*
Y174132D01*
X1552566Y170376D01*
X1684353D01*
X1689646Y175669D01*
G01X1557760Y214792D02*
X1565930D01*
X1573155Y207567D01*
X1589003D01*
G01X1557900Y220362D02*
X1580167D01*
X1589003Y211526D01*
G01X1550390Y709885D02*
X1552017D01*
X1557197Y715065D01*
Y721639D01*
X1566220Y730662D01*
Y734462D01*
X1568120Y736362D01*
X1579734D01*
X1597377Y754005D01*
Y762015D01*
X1602207Y766845D01*
Y776075D01*
X1608897Y782765D01*
Y924865D01*
X1607797Y925965D01*
Y929075D01*
X1608827Y930105D01*
Y932985D01*
X1602757Y939055D01*
X1594937D01*
X1573447Y960545D01*
Y998135D01*
X1550407Y1021175D01*
X1543727D01*
G01X1544993Y936489D02*
X1572862Y908620D01*
Y905313D01*
X1582017Y896158D01*
G01X1543042Y951465D02*
X1577971Y916536D01*
Y914866D01*
X1582017Y910820D01*
G01X1545047Y1030225D02*
X1546456D01*
X1577920Y998761D01*
Y962452D01*
X1595857Y944515D01*
X1607117D01*
X1610847Y940785D01*
X1613767D01*
X1614938Y939614D01*
Y778376D01*
X1610847Y774285D01*
Y769043D01*
X1606059Y764255D01*
X1605273D01*
X1602788Y761770D01*
G01X1544337Y1042125D02*
X1584187Y1002275D01*
Y964572D01*
X1596414Y952345D01*
X1608387D01*
X1611877Y948855D01*
X1618587D01*
X1619657Y947785D01*
X1620757D01*
X1624377Y944165D01*
Y939875D01*
X1625057Y939195D01*
Y934785D01*
X1623187Y932915D01*
Y930085D01*
X1624290Y928982D01*
Y925208D01*
X1623950Y924868D01*
Y865752D01*
X1624741Y864961D01*
Y780470D01*
X1620117Y775846D01*
Y769215D01*
X1618788Y767886D01*
Y761770D01*
G01X1543667Y1049835D02*
X1588777Y1004725D01*
Y976714D01*
X1596936Y968555D01*
X1608002D01*
X1610802Y965755D01*
X1615717D01*
X1618227Y963245D01*
Y960135D01*
X1626177Y952185D01*
X1628247D01*
X1631777Y948655D01*
Y762619D01*
X1630928Y761770D01*
G01X1555937Y1042715D02*
X1590957Y1007695D01*
Y979025D01*
X1596867Y973115D01*
X1606927D01*
X1609287Y970755D01*
X1614797D01*
X1619983Y965569D01*
X1623071D01*
X1624787Y967285D01*
X1629327D01*
X1631307Y965305D01*
Y952044D01*
X1633467Y949884D01*
Y767005D01*
X1634928Y765544D01*
Y761770D01*
G01X1559400Y229832D02*
X1587329D01*
X1588987Y231490D01*
G01X1582000Y756787D02*
X1575977D01*
X1573507Y754317D01*
Y752660D01*
G01X1638928Y761770D02*
Y947094D01*
X1633017Y953005D01*
Y966785D01*
X1630627Y969175D01*
X1624407D01*
X1622587Y970995D01*
X1617867D01*
X1616607Y972255D01*
X1610707D01*
X1607637Y975325D01*
X1596767D01*
X1592917Y979175D01*
Y1011635D01*
X1567737Y1036815D01*
G01X1589023Y215568D02*
Y211546D01*
X1589003Y211526D01*
G01X1588987Y235982D02*
Y231490D01*
G01X1577599Y752568D02*
X1579247D01*
X1579339Y752660D01*
X1581127D01*
X1584000Y749787D01*
G01X1577599Y752568D02*
X1577507Y752660D01*
G01X1579632Y787410D02*
X1585337Y793115D01*
Y906794D01*
X1584461Y907670D01*
X1582017D01*
G01X1579816Y793954D02*
X1583827Y797965D01*
Y898680D01*
X1582017Y900490D01*
G01X1673860Y726522D02*
X1649120Y751262D01*
Y962962D01*
X1646220Y965862D01*
Y1009015D01*
X1639220Y1016015D01*
Y1071945D01*
X1637320Y1073845D01*
X1625789D01*
X1624409Y1072465D01*
X1610499D01*
X1608289Y1074675D01*
X1596309D01*
X1590529Y1068895D01*
X1588459D01*
G01X1585630Y1734212D02*
X1586250D01*
X1590060Y1730402D01*
Y1667442D01*
X1594590Y1662912D01*
X1618070D01*
X1678230Y1602752D01*
Y1590542D01*
G01X1603580Y206902D02*
X1602915Y207567D01*
X1592153D01*
G01X1604200Y234642D02*
X1602860Y235982D01*
X1592137D01*
G01X1590915Y765630D02*
Y761620D01*
G01X1608307Y772125D02*
Y768985D01*
X1605800Y766478D01*
G01X1602650Y1242752D02*
Y1241475D01*
X1604602Y1239523D01*
X1610182D01*
X1612616Y1241957D01*
X1623023D01*
X1625666Y1244600D01*
X1631177D01*
X1631545Y1244968D01*
G01X1602650Y1247445D02*
Y1242752D01*
G01X1609403Y1247684D02*
X1606492Y1250595D01*
X1602650D01*
G01X1593504Y1672007D02*
Y1668778D01*
X1596230Y1666052D01*
X1617430D01*
X1682350Y1601132D01*
Y1542642D01*
X1681070Y1541362D01*
X1678340D01*
G01X1626741Y766798D02*
X1625070Y768469D01*
X1624443D01*
X1623107Y769805D01*
G01X1613083Y957546D02*
X1611024D01*
X1609239Y959331D01*
G01X1613083Y954200D02*
X1615142D01*
X1616927Y952415D01*
G01X1623744Y996980D02*
X1620399Y1000325D01*
G01X1611475Y1259227D02*
X1613000Y1257702D01*
Y1255355D01*
X1612589Y1254944D01*
G01X1621983Y1258727D02*
Y1257481D01*
X1620727Y1256225D01*
G01D02*
X1617008D01*
X1616114Y1257119D01*
G01X1648801Y1257492D02*
X1647242Y1255933D01*
Y1249054D01*
X1646103Y1247915D01*
X1638707D01*
X1632994Y1253628D01*
X1627790D01*
X1627116Y1254302D01*
X1621709D01*
X1621376Y1253969D01*
X1616114D01*
G01X1619454Y1249290D02*
X1615927D01*
X1613183Y1252034D01*
G01X1624040Y1247202D02*
X1614630D01*
X1613027Y1248805D01*
G01X1609056Y1250602D02*
X1609403Y1250255D01*
Y1247684D01*
G01X1654143Y1250610D02*
Y1244481D01*
X1652458Y1242796D01*
X1639639D01*
X1637467Y1244968D01*
X1631545D01*
G01X1642883Y1255381D02*
X1640226D01*
X1639689Y1254844D01*
G01X1642883Y1252034D02*
X1639879D01*
X1639467Y1251622D01*
Y1250175D01*
G01X1623930Y1252242D02*
X1625278Y1250894D01*
X1628162D01*
X1630938Y1248118D01*
X1631545D01*
G01X1625000Y1672007D02*
Y1662782D01*
X1684500Y1603282D01*
Y1504222D01*
X1681140Y1500862D01*
X1678340D01*
G01X1654110Y434177D02*
X1655150Y433137D01*
Y404627D01*
X1650520Y399997D01*
Y382638D01*
X1722369Y310789D01*
Y234668D01*
X1724122Y232915D01*
Y202410D01*
X1752755Y173777D01*
X1759135D01*
X1763450Y169462D01*
X1771361D01*
X1773431Y167392D01*
X1774950D01*
G01X1651509Y756492D02*
X1654667Y759650D01*
Y759659D01*
G01X1658679D02*
X1654667D01*
G01X1652807Y769805D02*
X1654143Y768469D01*
X1654770D01*
X1656441Y766798D01*
G01X1646627Y959265D02*
X1644908Y957546D01*
X1642783D01*
G01Y954200D02*
X1644842D01*
X1646627Y952415D01*
G01X1651404Y992838D02*
Y995433D01*
X1648205Y998632D01*
G01X1690518Y1248005D02*
X1689640D01*
X1686194Y1244559D01*
X1684956D01*
X1683445Y1243048D01*
X1676181D01*
X1675667Y1243562D01*
X1671225D01*
X1670165Y1244622D01*
X1665696D01*
X1661836Y1248482D01*
X1659129D01*
X1657001Y1250610D01*
X1654143D01*
G01X1639689Y1259345D02*
Y1254844D01*
G01X1642883Y1258727D02*
X1644118Y1257492D01*
X1645651D01*
G01X1644714Y1249914D02*
Y1253971D01*
X1645651Y1254908D01*
Y1257492D01*
G01X1661300Y1252085D02*
X1660667D01*
X1658371Y1254381D01*
X1657491D01*
X1655840Y1256032D01*
Y1257989D01*
X1653327Y1260502D01*
X1651177D01*
X1648801Y1258126D01*
Y1257492D01*
G01X1651679Y1248885D02*
X1648368Y1245574D01*
G01X1649573Y1252942D02*
X1651493Y1254862D01*
Y1257125D01*
X1652230Y1257862D01*
X1653140D01*
G01X1649573Y1252942D02*
X1651473D01*
X1652291Y1253760D01*
X1654143D01*
G01X1666690Y193290D02*
X1668800Y191180D01*
X1695080D01*
X1708680Y177580D01*
Y175325D01*
G01X1780500Y314299D02*
X1786863D01*
X1796126Y323562D01*
X1830900D01*
X1834860Y327522D01*
Y381642D01*
X1833760Y382742D01*
Y398381D01*
X1836882Y401503D01*
Y430747D01*
X1829009Y438620D01*
X1784234D01*
X1779315Y443539D01*
X1682641D01*
X1664970Y461210D01*
Y472112D01*
G01X1660660Y602273D02*
X1659870D01*
X1659350Y602793D01*
Y606422D01*
X1660260Y607332D01*
X1661875D01*
G01X1666686Y762809D02*
X1662656D01*
G01X1696061Y1014019D02*
X1678504Y996462D01*
X1671020D01*
X1668120Y993562D01*
Y769263D01*
X1662656Y763799D01*
Y762809D01*
G01Y759659D02*
X1658679D01*
G01X1669489Y1259545D02*
Y1255044D01*
G01X1672583Y1255381D02*
X1671487Y1254285D01*
X1670248D01*
X1669489Y1255044D01*
G01X1661300Y1252085D02*
X1673530D01*
X1675414Y1253969D01*
G01X1672583Y1248688D02*
X1669731D01*
G01X1690999Y525507D02*
X1686715D01*
X1684810Y523602D01*
G01X1687166Y529824D02*
X1688936D01*
X1689615Y530503D01*
X1691104D01*
G01X1685766Y535011D02*
X1691445D01*
G01X1689769Y537339D02*
X1689421D01*
X1687017Y539743D01*
X1685358D01*
G01X1681810Y752955D02*
X1699526D01*
X1702848Y756277D01*
Y760493D01*
G01X1686041Y766798D02*
Y763095D01*
G01X1676427Y959265D02*
X1674708Y957546D01*
X1672583D01*
G01X1676427Y952415D02*
X1674642Y954200D01*
X1672583D01*
G01X1675642Y989103D02*
Y991298D01*
X1672583Y994357D01*
G01Y1258727D02*
X1674191Y1257119D01*
X1675414D01*
G01X1682942Y1258909D02*
X1678576D01*
X1676786Y1257119D01*
X1675414D01*
G01X1705013Y1253814D02*
X1703961D01*
X1701792Y1251645D01*
X1694801D01*
X1692194Y1254252D01*
X1686801D01*
X1684200Y1256853D01*
X1680024D01*
X1677140Y1253969D01*
X1675414D01*
G01X1681179Y1252034D02*
Y1251146D01*
X1679522Y1249489D01*
G01X1683578Y1253780D02*
X1686203Y1251155D01*
X1690518D01*
G01X1716875Y68062D02*
X1711401Y62588D01*
X1702131D01*
X1693604Y54061D01*
Y29468D01*
X1704755Y18317D01*
X1710025D01*
G01X1720895Y68062D02*
X1699000Y89957D01*
Y93287D01*
G01X1709000Y87362D02*
X1706501D01*
X1703000Y90863D01*
Y93287D01*
G01X1709521Y185170D02*
X1706849D01*
X1703026Y188993D01*
G01D02*
X1697745Y194274D01*
Y198330D01*
G01X1694575Y202470D02*
X1694595Y202450D01*
Y198330D01*
G01X1707160Y207275D02*
X1699925D01*
X1699740Y207090D01*
G01D02*
X1696140D01*
X1695490Y206440D01*
Y203385D01*
X1694575Y202470D01*
G01X1690208Y421855D02*
Y423611D01*
X1690151Y423668D01*
Y424971D01*
X1690560Y425380D01*
Y427037D01*
G01X1747080Y435870D02*
X1693604D01*
X1692260Y434526D01*
Y433543D01*
X1690560Y431843D01*
Y430187D01*
G01X1696851Y545507D02*
X1699743D01*
X1745000Y500250D01*
Y473458D01*
X1726240Y454698D01*
X1707082D01*
X1703518Y458262D01*
X1699620D01*
X1697220Y455862D01*
G01X1699300Y498632D02*
Y496872D01*
X1702735Y493437D01*
X1705720D01*
G01X1697210Y500802D02*
Y495847D01*
X1699620Y493437D01*
X1699720D01*
G01X1711720Y497964D02*
X1709018Y495262D01*
X1703550D01*
X1701635Y497177D01*
G01X1699150Y505477D02*
X1698548Y504875D01*
X1694158D01*
G01D02*
X1693990Y504707D01*
Y501482D01*
X1694050Y501422D01*
G01X1693711Y498527D02*
X1693841D01*
X1694341Y498027D01*
Y494355D01*
X1694339Y494353D01*
G01X1702930Y526102D02*
X1701565Y527467D01*
X1697311D01*
X1696851Y527927D01*
Y529507D01*
G01X1709844Y516106D02*
X1702298Y523652D01*
X1697448D01*
X1696851Y524249D01*
Y525507D01*
G01X1693701D02*
X1690999D01*
G01X1693701D02*
Y521507D01*
G01X1691104Y530503D02*
X1692100Y529507D01*
X1693701D01*
G01Y545507D02*
Y541507D01*
G01D02*
Y537507D01*
G01X1689769Y537339D02*
X1691184Y538754D01*
X1692454D01*
X1693701Y537507D01*
G01X1702067Y699040D02*
X1706017D01*
G01X1698048Y705662D02*
X1702067Y701643D01*
Y699040D01*
G01X1698020Y702962D02*
X1695820Y705162D01*
Y706058D01*
X1697457Y707695D01*
X1698503D01*
X1700238Y709430D01*
X1705804D01*
X1705896Y709522D01*
G01X1703310Y749455D02*
X1724967D01*
X1735127Y759615D01*
Y991585D01*
X1754667Y1011125D01*
X1794947D01*
X1797391Y1013569D01*
Y1237789D01*
X1797417Y1237815D01*
G01X1690620Y760702D02*
Y1002862D01*
X1695520Y1007762D01*
X1700620D01*
X1707211Y1014353D01*
Y1224606D01*
X1705582Y1226235D01*
X1705029D01*
G01X1706948Y760493D02*
X1702848D01*
G01X1706027Y959265D02*
X1704308Y957546D01*
X1702183D01*
G01Y954200D02*
X1704242D01*
X1706027Y952415D01*
G01X1705242Y989103D02*
Y991298D01*
X1702183Y994357D01*
G01X1702283Y1057940D02*
X1698982D01*
X1697747Y1056705D01*
Y1015705D01*
X1696061Y1014019D01*
G01X1705029Y1229385D02*
X1704866Y1229222D01*
X1698405D01*
X1697901Y1229726D01*
Y1234635D01*
X1699145Y1235879D01*
X1700586D01*
G01D02*
X1704137D01*
X1705076Y1236818D01*
Y1242032D01*
G01X1699852Y1245418D02*
X1699789Y1245355D01*
X1694649D01*
X1691999Y1248005D01*
X1690518D01*
G01X1699089Y1254244D02*
Y1258842D01*
G01X1699030Y1263912D02*
Y1262230D01*
X1703485Y1257775D01*
X1704202D01*
X1705013Y1256964D01*
G01X1702283Y1248688D02*
X1699431D01*
G01X1715210Y18282D02*
X1717020Y20092D01*
Y22662D01*
X1713173Y26509D01*
Y31169D01*
G01X1774435Y13667D02*
X1773780Y13012D01*
X1750070D01*
X1744120Y18962D01*
X1725220D01*
X1721720Y15462D01*
X1711420D01*
X1710025Y16857D01*
Y18317D01*
G01X1709589Y26062D02*
X1710025Y25626D01*
Y21467D01*
G01X1747720Y31862D02*
X1742220D01*
X1738430Y35652D01*
X1723154D01*
X1721682Y34180D01*
Y27955D01*
X1719589Y25862D01*
G01X1747720Y34362D02*
X1743719D01*
X1740719Y37362D01*
X1720072D01*
X1717026Y34316D01*
Y25925D01*
X1717089Y25862D01*
G01X1725320Y67962D02*
X1719210Y74072D01*
Y77152D01*
X1709000Y87362D01*
G01X1712720Y111862D02*
Y96583D01*
X1709424Y93287D01*
X1708000D01*
G01X1760478Y90027D02*
X1767796D01*
X1770730Y92961D01*
Y96075D01*
X1766550Y100255D01*
Y116855D01*
X1758103Y125302D01*
X1714890D01*
X1713418Y126774D01*
Y130862D01*
G01X1712820Y175355D02*
X1708710D01*
X1708680Y175325D01*
G01X1712820Y175355D02*
X1713030Y175565D01*
Y178140D01*
X1712080Y179090D01*
Y185170D01*
G01Y192650D02*
Y190620D01*
X1712770Y189930D01*
X1714160D01*
X1714639Y190409D01*
Y192650D01*
G01X1712080D02*
Y196749D01*
X1711599Y197230D01*
G01D02*
X1709109Y199720D01*
X1707145D01*
G01X1711599Y197230D02*
Y197329D01*
G01X1707160Y207275D02*
Y210079D01*
X1707159Y210080D01*
G01X1718786Y472252D02*
Y475752D01*
G01Y472252D02*
Y467517D01*
G01X1715711Y474399D02*
X1716633D01*
X1717986Y475752D01*
X1718786D01*
G01X1711720Y493437D02*
Y497964D01*
G01X1716134Y478443D02*
Y478593D01*
X1716793Y479252D01*
X1718786D01*
G01X1713158Y478243D02*
X1713508Y478593D01*
X1715984D01*
X1716134Y478443D01*
G01X1706017Y699040D02*
X1710057D01*
G01D02*
X1710427Y698670D01*
X1719063D01*
X1729578Y688155D01*
X1766537D01*
X1768317Y686375D01*
G01X1713920Y700962D02*
X1714897Y701939D01*
Y706095D01*
G01X1705896Y709522D02*
Y712121D01*
X1707746Y713971D01*
X1709395D01*
X1709486Y714062D01*
G01Y710912D02*
X1713556D01*
X1713606Y710862D01*
G01X1714897Y706095D02*
X1716117Y707315D01*
Y708351D01*
X1713606Y710862D01*
G01X1710915Y763651D02*
X1714955D01*
G01X1719277Y1013205D02*
Y766325D01*
X1717997Y765045D01*
X1716349D01*
X1714955Y763651D01*
G01X1706948Y760493D02*
X1706956Y760501D01*
X1710915D01*
G01X1712207Y769805D02*
X1713543Y768469D01*
X1714170D01*
X1715841Y766798D01*
G01X1731683Y1057940D02*
X1728528Y1054785D01*
X1721717D01*
X1719277Y1052345D01*
Y1013205D01*
G01X1705076Y1242032D02*
Y1246135D01*
X1705803Y1246862D01*
G01X1727041Y1248688D02*
Y1249722D01*
X1726099Y1250664D01*
X1723162D01*
X1722297Y1249799D01*
X1720183D01*
G01X1705013Y1253814D02*
X1705803Y1253024D01*
Y1250012D01*
G01Y1246862D02*
X1707783Y1248842D01*
Y1251944D01*
X1709013Y1253174D01*
Y1253814D01*
G01X1711109Y1252034D02*
Y1249878D01*
X1710363Y1249132D01*
G01X1714440Y1255381D02*
X1715440D01*
X1717139Y1253682D01*
X1717801D01*
X1718534Y1252949D01*
X1720183D01*
G01X1733920Y151362D02*
X1745620Y163062D01*
X1775020D01*
X1777574Y165616D01*
Y168168D01*
X1773910Y171832D01*
X1765109D01*
X1760836Y176105D01*
X1753327D01*
X1726300Y203132D01*
Y234963D01*
X1725069Y236194D01*
Y310352D01*
X1760979Y346262D01*
X1812720D01*
X1829189Y362731D01*
Y363731D01*
G01X1721220Y458362D02*
Y458562D01*
X1728820Y466162D01*
Y475762D01*
X1727330Y477252D01*
X1725092D01*
X1723592Y475752D01*
X1721936D01*
G01X1739316Y480939D02*
X1725279D01*
X1723592Y479252D01*
X1721936D01*
G01X1731983Y957546D02*
X1729924D01*
X1728139Y959331D01*
G01X1731983Y954200D02*
X1729858D01*
X1728139Y952481D01*
G01X1731983Y994357D02*
X1728924Y991298D01*
Y987935D01*
G01X1728689Y1258845D02*
Y1254344D01*
G01X1731983Y1255381D02*
X1729726D01*
X1728689Y1254344D01*
G01X1739237Y1256935D02*
X1736946D01*
X1736662Y1257219D01*
X1734714D01*
G01X1731983Y1258727D02*
X1733206D01*
X1734714Y1257219D01*
G01Y1254069D02*
X1740497D01*
X1741791Y1255363D01*
X1745609D01*
X1749307Y1251665D01*
X1756817D01*
X1759070Y1249412D01*
G01X1731983Y1252034D02*
X1734612Y1249405D01*
X1736715D01*
G01X1731983Y1248688D02*
X1728477Y1245182D01*
Y1242955D01*
G01X1745541Y766798D02*
Y763095D01*
G01X1756922Y1247632D02*
Y1246302D01*
X1755931Y1245311D01*
X1749690D01*
G01X1742337Y1252300D02*
X1742836Y1251801D01*
X1745402D01*
X1748742Y1248461D01*
X1749690D01*
G01X1769669Y15244D02*
X1771242Y16817D01*
X1774435D01*
G01X1768026Y24165D02*
X1769640Y25779D01*
Y31128D01*
X1769791Y31279D01*
G01X1758075Y43284D02*
X1762075D01*
G01X1767185Y48817D02*
X1762075Y43707D01*
Y43284D01*
G01X1769274Y50742D02*
X1769900Y50116D01*
Y43284D01*
G01X1771800Y178303D02*
X1769799D01*
X1765820Y182282D01*
G01X1767300Y174587D02*
X1768177D01*
X1768861Y173903D01*
X1771800D01*
G01X1770566Y303534D02*
Y305190D01*
X1769698Y306058D01*
X1764771D01*
G01D02*
X1764680Y305967D01*
G01X1780500Y323747D02*
Y327303D01*
X1779990Y327813D01*
X1771331D01*
X1767032Y323514D01*
Y308319D01*
X1764771Y306058D01*
G01X1761683Y957546D02*
X1759624D01*
X1757839Y959331D01*
G01X1761683Y954200D02*
X1759558D01*
X1757839Y952481D01*
G01X1761683Y994357D02*
X1764742Y991298D01*
Y989103D01*
G01X1758189Y1258875D02*
Y1254344D01*
G01X1761683Y1255381D02*
X1760646Y1254344D01*
X1758189D01*
G01X1769037Y1256835D02*
X1766746D01*
X1766462Y1257119D01*
X1764514D01*
G01X1761683Y1258727D02*
X1763291Y1257119D01*
X1764514D01*
G01X1793714Y1253019D02*
X1792800Y1252105D01*
X1783983D01*
X1782179Y1253909D01*
X1776387D01*
X1774534Y1255762D01*
X1772137D01*
X1770344Y1253969D01*
X1764514D01*
G01X1759070Y1249412D02*
X1761323Y1251665D01*
X1762210D01*
X1764514Y1253969D01*
G01X1761683Y1248688D02*
X1763397Y1246974D01*
X1764163D01*
G01X1779575Y13647D02*
X1782305D01*
G01X1774435Y13667D02*
X1774455Y13647D01*
X1779575D01*
G01X1775556Y21471D02*
X1778969D01*
X1779575Y20865D01*
Y16797D01*
G01X1773791Y31279D02*
X1769791D01*
G01X1774274Y50742D02*
X1777754Y47262D01*
Y43444D01*
G01X1771774Y53682D02*
X1772010Y53446D01*
Y48512D01*
X1773554Y46968D01*
Y43284D01*
G01X1776710Y53562D02*
Y50342D01*
X1781990Y45062D01*
Y43330D01*
G01X1779411Y50692D02*
X1786979D01*
X1787706Y49965D01*
G01X1770368Y72691D02*
Y75070D01*
X1771440Y76142D01*
Y91532D01*
X1773090Y93182D01*
G01Y115818D02*
Y93182D01*
G01X1808910Y143902D02*
X1782671D01*
X1777517Y138748D01*
Y121842D01*
X1773090Y117415D01*
Y115818D01*
G01X1782600Y175932D02*
Y178262D01*
X1780580Y180282D01*
X1775750D01*
X1774950Y179482D01*
Y178303D01*
G01X1779500Y171692D02*
Y175362D01*
X1778870Y175992D01*
X1775800D01*
X1774950Y175142D01*
Y173903D01*
G01X1777354Y295489D02*
Y299306D01*
X1779319Y301271D01*
Y303605D01*
G01Y306755D02*
Y309408D01*
X1780500Y310589D01*
Y314299D01*
G01X1779319Y303605D02*
X1774551D01*
X1774537Y303619D01*
G01D02*
X1774452Y303534D01*
X1770566D01*
G01X1773559Y767345D02*
Y763642D01*
G01X1788373Y1241769D02*
X1788243D01*
X1782942Y1247070D01*
X1778789D01*
G01X1770299Y1252034D02*
Y1249182D01*
G01X1773480Y1253692D02*
Y1252978D01*
X1775003Y1251455D01*
X1775485D01*
X1776720Y1250220D01*
X1778789D01*
G01X1799920Y52594D02*
X1797741Y50415D01*
X1792156D01*
X1791706Y49965D01*
G01X1787706Y53115D02*
X1790815Y50006D01*
X1791665D01*
X1791706Y49965D01*
G01X1791383Y957546D02*
X1789324D01*
X1787539Y959331D01*
G01X1791383Y954200D02*
X1789258D01*
X1787539Y952481D01*
G01X1791383Y994357D02*
X1794442Y991298D01*
Y989103D01*
G01X1797417Y1240965D02*
Y1244815D01*
G01Y1240965D02*
X1801227D01*
X1802670Y1239522D01*
G01X1788219Y1259312D02*
Y1254914D01*
X1788389Y1254744D01*
G01X1788360Y1264522D02*
Y1262173D01*
X1793714Y1256819D01*
G01Y1253019D02*
X1795537Y1254842D01*
Y1255492D01*
X1796864Y1256819D01*
G01X1810954Y1252789D02*
X1806474D01*
X1805398Y1253865D01*
X1799037D01*
X1797747Y1255155D01*
Y1255936D01*
X1796864Y1256819D01*
G01X1797417Y1244815D02*
X1795737D01*
X1794737Y1245815D01*
Y1250892D01*
X1796864Y1253019D01*
G01X1800019Y1252034D02*
X1800849Y1251204D01*
X1803357D01*
G01X1791383Y1248688D02*
X1788531D01*
G01X1804841Y763095D02*
Y766798D01*
G01X1815063Y1233103D02*
X1816360Y1234400D01*
Y1237686D01*
G01X1802670Y1239522D02*
X1804227Y1237965D01*
X1807845D01*
X1809349Y1236461D01*
G01X1821139Y1248155D02*
X1819050Y1246066D01*
Y1233212D01*
X1818290Y1232452D01*
G01X1816360Y1240836D02*
Y1243984D01*
X1815474Y1244870D01*
Y1246472D01*
G01X1829920Y1258322D02*
X1828258Y1256660D01*
X1816612D01*
G01X1829940Y1263662D02*
X1825005Y1258727D01*
X1811464D01*
X1810954Y1258217D01*
Y1255939D01*
G01X1815474Y1246472D02*
Y1249349D01*
X1813814Y1251009D01*
Y1254693D01*
G01X1818004Y1510021D02*
X1816354Y1511671D01*
X1814131D01*
X1812897Y1510437D01*
G01X1813994Y1507891D02*
X1815874D01*
X1818004Y1510021D01*
G01X1834600Y406442D02*
X1832150Y403992D01*
Y356104D01*
X1828204Y352158D01*
Y328654D01*
G01X1824827Y959265D02*
X1823108Y957546D01*
X1820983D01*
G01Y954200D02*
X1823042D01*
X1824827Y952415D01*
G01X1824042Y989103D02*
Y991298D01*
X1820983Y994357D01*
G01X1876720Y1001463D02*
Y1296041D01*
X1877718Y1297039D01*
X1885782D01*
X1886720Y1296101D01*
Y1001463D01*
G54D102*
X1247638Y269488D03*
X1405118Y112008D03*
X1766929Y1714960D03*
G54D111*
X1879155Y344948D03*
Y468898D03*
D03*
Y592848D03*
D03*
Y716798D03*
D03*
Y840748D03*
X1900275Y-19342D03*
X1889155Y344948D03*
Y468898D03*
D03*
X1900275Y592858D03*
X1889155Y592848D03*
D03*
X1900275Y716808D03*
X1889155Y716798D03*
D03*
X1900275Y840758D03*
D03*
X1889155Y840748D03*
X1900275Y964708D03*
X1910275Y-19342D03*
Y592858D03*
Y716808D03*
Y840758D03*
D03*
Y964708D03*
X1921395Y-19332D03*
X1931395D03*
Y592868D03*
X1921395D03*
X1931395D03*
X1921395D03*
Y1205068D03*
X1931395D03*
X1952395Y-19152D03*
X1942395D03*
Y593048D03*
X1952395D03*
X1942395D03*
X1952395D03*
Y1205248D03*
X1942395D03*
X1963362Y-19190D03*
Y593010D03*
D03*
Y1205210D03*
X1984482Y-19180D03*
X1973362Y-19190D03*
X1984482Y593020D03*
D03*
X1973362Y593010D03*
D03*
X1984482Y1205220D03*
X1973362Y1205210D03*
X1994482Y-19180D03*
Y593020D03*
D03*
Y1205220D03*
X2005452Y-19180D03*
X2015452D03*
Y593020D03*
X2005452D03*
X2015452D03*
X2005452D03*
Y1205220D03*
X2015452D03*
X2026452Y-19000D03*
Y593200D03*
D03*
Y1205400D03*
X2047419Y-19038D03*
X2036452Y-19000D03*
X2047419Y593162D03*
X2036452Y593200D03*
X2047419Y593162D03*
X2036452Y593200D03*
X2047419Y1205362D03*
X2036452Y1205400D03*
X2057419Y-19038D03*
Y593162D03*
D03*
Y1205362D03*
X2068539Y593172D03*
X2078539D03*
Y1205372D03*
X2068539D03*
G54D121*
G01X1691445Y535011D02*
X1692729Y534479D01*
X1693701Y533507D01*
G54D103*
X1254292Y139518D03*
X1251572Y142218D03*
X1258629Y162351D03*
X1252058Y156003D03*
G54D10*
X27559Y87795D03*
X40708Y631890D03*
Y1368897D03*
X38346Y1420330D03*
X51181Y1714961D03*
X117932Y605380D03*
X373622Y87795D03*
X395670Y1714961D03*
X661023Y631890D03*
X707677Y1714961D03*
X763601Y605413D03*
X800787Y87795D03*
X931692Y757874D03*
Y1072834D03*
Y1387795D03*
X1045865Y87795D03*
X1094074Y605380D03*
X1155708Y1714961D03*
X1271260Y631890D03*
X1461805Y1714961D03*
X1499606Y87795D03*
X1739706Y605455D03*
X1816771Y631890D03*
Y1368897D03*
X1819208Y1420330D03*
X1806299Y1714961D03*
X1829921Y87795D03*
G54D112*
X1879155Y354948D03*
Y458898D03*
Y478898D03*
Y582848D03*
Y602848D03*
Y706798D03*
Y726798D03*
Y830748D03*
X1900275Y-9342D03*
X1889155Y354948D03*
Y458898D03*
Y478898D03*
X1900275Y582858D03*
X1889155Y582848D03*
Y602848D03*
Y706798D03*
X1900275Y726808D03*
X1889155Y726798D03*
X1900275Y830758D03*
X1889155Y830748D03*
X1900275Y850758D03*
Y954708D03*
X1910275Y-9342D03*
Y582858D03*
Y726808D03*
Y830758D03*
Y850758D03*
Y954708D03*
X1921395Y-9332D03*
X1931395D03*
Y582868D03*
X1921395D03*
X1931395Y602868D03*
X1921395D03*
Y1195068D03*
X1931395D03*
X1942395Y-9152D03*
Y583048D03*
Y603048D03*
Y1195248D03*
X1963362Y-9190D03*
X1952395Y-9152D03*
X1963362Y583010D03*
X1952395Y583048D03*
X1963362Y603010D03*
X1952395Y603048D03*
X1963362Y1195210D03*
X1952395Y1195248D03*
X1973362Y-9190D03*
Y583010D03*
Y603010D03*
Y1195210D03*
X1994482Y-9180D03*
X1984482D03*
Y583020D03*
X1994482D03*
X1984482Y603020D03*
X1994482D03*
Y1195220D03*
X1984482D03*
X2005452Y-9180D03*
X2015452D03*
Y583020D03*
X2005452D03*
X2015452Y603020D03*
X2005452D03*
Y1195220D03*
X2015452D03*
X2026452Y-9000D03*
Y583200D03*
Y603200D03*
Y1195400D03*
X2047419Y-9038D03*
X2036452Y-9000D03*
X2047419Y583162D03*
X2036452Y583200D03*
X2047419Y603162D03*
X2036452Y603200D03*
X2047419Y1195362D03*
X2036452Y1195400D03*
X2057419Y-9038D03*
Y583162D03*
Y603162D03*
Y1195362D03*
X2068539Y603172D03*
X2078539D03*
Y1195372D03*
X2068539D03*
G54D122*
G01X47619Y418655D02*
X46548Y417584D01*
X45603D01*
X45113Y418074D01*
X43613D01*
X43123Y417584D01*
X41202D01*
X40480Y418306D01*
Y419270D01*
X40970Y419760D01*
Y421260D01*
X40480Y421750D01*
Y423184D01*
X40970Y423674D01*
Y425174D01*
X40480Y425664D01*
Y427164D01*
X40970Y427654D01*
Y429154D01*
X40480Y429644D01*
Y431144D01*
X41121Y432102D01*
X46335Y434259D01*
X47650Y435574D01*
X48090Y436636D01*
Y437703D01*
X48333Y437946D01*
Y439446D01*
G01X47618Y415613D02*
X46667Y416564D01*
X40779D01*
X39460Y417883D01*
Y431454D01*
X40445Y432927D01*
X45757Y435124D01*
X46785Y436153D01*
X47069Y436839D01*
X47070Y436840D01*
Y437722D01*
X46759Y438033D01*
Y439446D01*
G01X49360Y428806D02*
X49244D01*
X48170Y429880D01*
Y430827D01*
X48337Y430994D01*
X49052Y431290D01*
X50887D01*
X59629Y422548D01*
X62442D01*
X63382Y423488D01*
Y427617D01*
X64571Y428806D01*
G01X45960D02*
X47150Y429996D01*
Y431250D01*
X47759Y431859D01*
X48849Y432310D01*
X51310D01*
X60052Y423568D01*
X62019D01*
X62362Y423911D01*
Y427615D01*
X61171Y428806D01*
G01X48333Y444958D02*
Y446371D01*
X48022Y446682D01*
Y450412D01*
X49212Y451602D01*
G01X46759Y444958D02*
Y446458D01*
X47002Y446701D01*
Y450412D01*
X45812Y451602D01*
G01X64410Y1599102D02*
X65502Y1600194D01*
X69713D01*
X77933Y1608414D01*
X118386D01*
X126900Y1599900D01*
X135032D01*
X136522Y1598410D01*
G01X64410Y1602502D02*
X65698Y1601214D01*
X69290D01*
X77510Y1609434D01*
X118809D01*
X127323Y1600920D01*
X135028D01*
X136518Y1602410D01*
G01X99750Y1565378D02*
X100940Y1564188D01*
X105608D01*
X126940Y1585520D01*
X162255D01*
X164023Y1587288D01*
Y1587289D01*
X168926Y1592191D01*
X178413Y1596122D01*
X191443Y1609152D01*
X248389D01*
X249670Y1610433D01*
Y1617521D01*
X252851Y1625200D01*
X265650Y1637999D01*
Y1668581D01*
X267251Y1670182D01*
X268451D01*
X270276Y1672007D01*
G01X99750Y1561978D02*
X100940Y1563168D01*
X106031D01*
X127363Y1584500D01*
X162678D01*
X169504Y1591326D01*
X178991Y1595257D01*
X191866Y1608132D01*
X248812D01*
X250690Y1610010D01*
Y1617318D01*
X253716Y1624622D01*
X266670Y1637576D01*
Y1668158D01*
X267674Y1669162D01*
X268397D01*
X270276Y1667283D01*
G01X142081Y1598155D02*
Y1598158D01*
X140369Y1599870D01*
X137982D01*
X136522Y1598410D01*
G01X142081Y1602666D02*
X140365Y1600950D01*
X137978D01*
X136518Y1602410D01*
G01X230906Y1649173D02*
X229037Y1651042D01*
X219897D01*
X191262Y1622411D01*
X160554Y1603448D01*
X149947Y1599922D01*
X146998D01*
X145231Y1598155D01*
G01X230906Y1653897D02*
X229071Y1652062D01*
X219474D01*
X214786Y1647375D01*
X214107D01*
X213045Y1646313D01*
Y1645634D01*
X190624Y1623217D01*
X160119Y1604379D01*
X149781Y1600942D01*
X147030D01*
X145306Y1602666D01*
X145231D01*
G01X229135Y26474D02*
X227945Y27664D01*
Y41484D01*
X233626Y47165D01*
X243670Y71412D01*
Y80584D01*
X231220Y110641D01*
Y184992D01*
X234506Y192924D01*
X238395Y196813D01*
X278463Y213410D01*
X284269Y227425D01*
X318639Y241662D01*
X401510D01*
X410108Y245223D01*
X414252Y251428D01*
Y251429D01*
X418398Y257635D01*
Y273308D01*
X439725Y324797D01*
X440951Y326023D01*
X449268Y329466D01*
X453049Y330218D01*
X453050Y330219D01*
X456833Y330972D01*
X491769D01*
X502632Y335472D01*
X514579D01*
X514580Y335471D01*
X520615Y332972D01*
X544231D01*
X558789Y339002D01*
X605423D01*
X607303Y340882D01*
X619867D01*
X621747Y339002D01*
X676891D01*
X687058Y343212D01*
X805794D01*
X897104Y381034D01*
X912384Y396314D01*
X936257Y453947D01*
Y456672D01*
X937447Y457862D01*
G01X225735Y26474D02*
X226925Y27664D01*
Y41907D01*
X232761Y47743D01*
X242650Y71615D01*
Y80381D01*
X230200Y110438D01*
Y185195D01*
X233641Y193502D01*
X237817Y197678D01*
X277682Y214191D01*
X283488Y228206D01*
X318436Y242682D01*
X401307D01*
X409431Y246048D01*
X417378Y257945D01*
Y273511D01*
X438860Y325375D01*
X440373Y326888D01*
X448971Y330447D01*
X456732Y331992D01*
X491566D01*
X502429Y336492D01*
X514783D01*
X520818Y333992D01*
X544028D01*
X558586Y340022D01*
X605000D01*
X606880Y341902D01*
X620290D01*
X622170Y340022D01*
X676688D01*
X686855Y344232D01*
X805591D01*
X896526Y381899D01*
X911519Y396892D01*
X935237Y454150D01*
Y456672D01*
X934047Y457862D01*
G01X229131Y50646D02*
X227941Y51836D01*
Y53249D01*
X227942Y53250D01*
X229990Y58192D01*
X232037Y63134D01*
X234115Y65212D01*
X236610Y71231D01*
Y75793D01*
X227320Y110828D01*
Y185091D01*
X231667Y195586D01*
X235800Y199719D01*
X275338Y216097D01*
X281124Y230064D01*
X318540Y245562D01*
X398145D01*
X407294Y249351D01*
X411026Y254944D01*
X411025D01*
X414758Y260538D01*
Y274744D01*
X437226Y328985D01*
X439390Y330429D01*
X452412Y334375D01*
X509751Y342872D01*
X571730D01*
X592982Y347099D01*
X805662D01*
X894984Y384097D01*
X923257Y452354D01*
Y461822D01*
X924447Y463012D01*
G01X225731Y50646D02*
X226921Y51836D01*
Y53453D01*
X231172Y63712D01*
X233250Y65790D01*
X235590Y71435D01*
Y75660D01*
X226300Y110695D01*
Y185294D01*
X230802Y196164D01*
X235222Y200584D01*
X274557Y216878D01*
X280343Y230845D01*
X318337Y246582D01*
X397942D01*
X406617Y250175D01*
X413738Y260848D01*
Y274947D01*
X436402Y329662D01*
X438949Y331362D01*
X452188Y335373D01*
X509675Y343892D01*
X571629D01*
X592881Y348119D01*
X805459D01*
X894203Y384878D01*
X922237Y452557D01*
Y461822D01*
X921047Y463012D01*
G01X901230Y531612D02*
X902420Y532802D01*
Y533962D01*
X900820Y535562D01*
X898720D01*
X896920Y533762D01*
Y530612D01*
X894760Y528452D01*
X886444D01*
X729937Y559582D01*
X425422D01*
X418406Y562488D01*
X299460Y681435D01*
Y689402D01*
X296800Y692062D01*
X293521D01*
X285526Y695373D01*
X282752Y699526D01*
X281390Y704021D01*
X277149Y708262D01*
X264714D01*
X254650Y718326D01*
Y733753D01*
X257637Y748788D01*
X259004Y752088D01*
X262453Y757249D01*
X262455Y757253D01*
X263040Y758663D01*
Y780204D01*
X261989Y782745D01*
X252716Y792018D01*
X245586Y794972D01*
X241916Y798641D01*
X240910Y801067D01*
Y917202D01*
X241744Y919214D01*
X242649Y920121D01*
X246572Y922740D01*
X260145Y929997D01*
X299045Y941802D01*
X309103Y943548D01*
X328943D01*
G01X904630Y531612D02*
X903440Y532802D01*
Y534385D01*
X901243Y536582D01*
X898297D01*
X895900Y534185D01*
Y531035D01*
X894337Y529472D01*
X886545D01*
X885477Y529685D01*
X730038Y560602D01*
X425625D01*
X422304Y561978D01*
X418984Y563353D01*
X300480Y681858D01*
Y689825D01*
X297223Y693082D01*
X293724D01*
X286203Y696198D01*
X283685Y699967D01*
X282292Y704562D01*
X277572Y709282D01*
X265137D01*
X255670Y718749D01*
Y733652D01*
X258619Y748490D01*
X259909Y751604D01*
X263360Y756769D01*
X264060Y758454D01*
Y780407D01*
X262854Y783323D01*
X253294Y792883D01*
X246164Y795837D01*
X242781Y799220D01*
X241930Y801271D01*
Y916998D01*
X242609Y918636D01*
X243300Y919328D01*
X247097Y921864D01*
X260538Y929049D01*
X299281Y940807D01*
X309191Y942528D01*
X328943D01*
G01X888130Y532612D02*
X889320Y533802D01*
Y536697D01*
X885936Y540081D01*
X878759Y541508D01*
X732317Y563232D01*
X427454D01*
X421687Y565621D01*
X303980Y683328D01*
Y690983D01*
X298838Y696125D01*
X293788D01*
X287826Y698592D01*
X286038Y701269D01*
X284513Y706291D01*
X278852Y711952D01*
X266272D01*
X258600Y719624D01*
Y734374D01*
X261356Y748226D01*
X261978Y749736D01*
X266202Y756051D01*
X266760Y757402D01*
Y783557D01*
X264489Y789042D01*
X259383Y794145D01*
X251548Y799380D01*
X248926Y800468D01*
X247799Y801594D01*
X247420Y802510D01*
Y865226D01*
X248111Y865917D01*
Y913913D01*
X249317Y916820D01*
X258711Y923097D01*
X258708Y923096D01*
X299009Y937505D01*
X303278Y938354D01*
X328893D01*
G01X891530Y532612D02*
X890340Y533802D01*
Y537120D01*
X890191Y537269D01*
X886439Y541022D01*
X878934Y542514D01*
X732393Y564252D01*
X427657D01*
X422265Y566486D01*
X305000Y683751D01*
Y691406D01*
X299261Y697145D01*
X293991D01*
X288503Y699417D01*
X286971Y701710D01*
X285415Y706832D01*
X279275Y712972D01*
X266695D01*
X259620Y720047D01*
Y734273D01*
X262337Y747929D01*
X262883Y749253D01*
X267107Y755568D01*
X267780Y757199D01*
Y783760D01*
X265354Y789620D01*
X260034Y794938D01*
X252032Y800285D01*
X249504Y801334D01*
X248664Y802172D01*
X248440Y802713D01*
Y864803D01*
X249131Y865494D01*
Y913709D01*
X250141Y916143D01*
X259170Y922177D01*
X289370Y932974D01*
X289983Y932684D01*
X291397Y933189D01*
X291687Y933804D01*
X293099Y934308D01*
X293713Y934018D01*
X295127Y934523D01*
X295417Y935137D01*
X299282Y936519D01*
X303379Y937334D01*
X328893D01*
G01X284233Y26474D02*
X283044Y27663D01*
Y29807D01*
X286049Y32812D01*
X302479D01*
X308938Y35487D01*
X313427Y39976D01*
X314808Y43310D01*
X336540Y65038D01*
Y133439D01*
X343200Y149518D01*
X349272Y155590D01*
X362723Y161162D01*
X395445D01*
X417287Y170209D01*
X434885Y187807D01*
X443660Y208993D01*
Y284282D01*
X452751Y306214D01*
X460110Y313573D01*
X472348Y318642D01*
X585497D01*
X588667Y315472D01*
X592433D01*
X594775Y317814D01*
X598687Y319435D01*
X627076Y325082D01*
X673718D01*
X691167Y332309D01*
X798499D01*
X902066Y375207D01*
X921108Y394249D01*
X938075Y435213D01*
X946259Y447459D01*
X973540Y474739D01*
Y480505D01*
X971294Y482751D01*
X969476D01*
X968286Y483941D01*
G01X280833Y26474D02*
X280834D01*
X282024Y27664D01*
Y30230D01*
X285626Y33832D01*
X302276D01*
X308360Y36352D01*
X312562Y40554D01*
X313943Y43888D01*
X335520Y65461D01*
Y133642D01*
X342335Y150096D01*
X348694Y156455D01*
X362520Y162182D01*
X395242D01*
X416709Y171074D01*
X434020Y188385D01*
X442640Y209196D01*
Y284486D01*
X451886Y306792D01*
X459532Y314438D01*
X472145Y319662D01*
X585920D01*
X589090Y316492D01*
X592010D01*
X594197Y318679D01*
X598389Y320416D01*
X626975Y326102D01*
X673515D01*
X690964Y333329D01*
X798296D01*
X901488Y376072D01*
X920243Y394827D01*
X937170Y435697D01*
X945466Y448110D01*
X960696Y463338D01*
Y464031D01*
X961828Y465163D01*
X962521D01*
X963652Y466294D01*
Y466987D01*
X964784Y468119D01*
X965477D01*
X966608Y469250D01*
Y469943D01*
X967740Y471075D01*
X968433D01*
X969564Y472206D01*
Y472899D01*
X970696Y474031D01*
X971389D01*
X972520Y475162D01*
Y480082D01*
X970871Y481731D01*
X969476D01*
X968286Y480541D01*
G01X284230Y50646D02*
X284229D01*
X283039Y51836D01*
Y52572D01*
X287449Y56982D01*
X293297D01*
X295087Y55192D01*
X317430D01*
X322590Y57329D01*
X332840Y67579D01*
Y134021D01*
X340114Y151582D01*
X347208Y158676D01*
X361996Y164802D01*
X394533D01*
X412479Y172235D01*
X432933Y192689D01*
X439804Y209281D01*
Y293969D01*
X441710Y298569D01*
X441712Y298573D01*
X445538Y304299D01*
X445537D01*
X449365Y310025D01*
X456170Y316831D01*
X470448Y322745D01*
X490792Y326792D01*
X573434D01*
X591882Y334352D01*
X608277D01*
X609727Y332902D01*
X617243D01*
X618393Y334052D01*
X620305D01*
X623623Y332682D01*
X680050D01*
X692960Y338029D01*
X802794D01*
X900001Y378293D01*
X917754Y396046D01*
X944257Y460029D01*
Y461822D01*
X945447Y463012D01*
G01X280830Y50646D02*
X282019Y51835D01*
Y52995D01*
X287026Y58002D01*
X293720D01*
X295510Y56212D01*
X317227D01*
X322012Y58194D01*
X331820Y68002D01*
Y134224D01*
X339249Y152160D01*
X346630Y159541D01*
X361793Y165822D01*
X394330D01*
X411901Y173100D01*
X432068Y193267D01*
X438784Y209484D01*
Y294172D01*
X440805Y299053D01*
X448572Y310676D01*
X455592Y317696D01*
X470150Y323726D01*
X490691Y327812D01*
X573233D01*
X591681Y335372D01*
X608700D01*
X610150Y333922D01*
X616820D01*
X617970Y335072D01*
X620508D01*
X623826Y333702D01*
X679847D01*
X692757Y339049D01*
X802591D01*
X899423Y379158D01*
X916889Y396624D01*
X943237Y460232D01*
Y461822D01*
X942047Y463012D01*
G01X278150Y1653897D02*
X276308Y1652055D01*
X275134D01*
X273837Y1650758D01*
Y1640589D01*
X282165Y1632262D01*
Y1632261D01*
X284799Y1630995D01*
X284798D01*
X379090Y1620506D01*
X384697Y1615143D01*
X389060Y1600249D01*
Y1594735D01*
X387842Y1593517D01*
G01X278150Y1649173D02*
X276288Y1651035D01*
X275557D01*
X274857Y1650335D01*
Y1641012D01*
X277524Y1638345D01*
X278203D01*
X279265Y1637283D01*
Y1636605D01*
X282764Y1633106D01*
X285084Y1631990D01*
X288810Y1631576D01*
X289340Y1632000D01*
X290832Y1631834D01*
X291256Y1631303D01*
X292746Y1631138D01*
X293276Y1631562D01*
X294768Y1631396D01*
X295192Y1630865D01*
X379546Y1621482D01*
X385600Y1615692D01*
X390080Y1600396D01*
Y1594854D01*
X391417Y1593517D01*
G01X278150Y1668070D02*
Y1668069D01*
X280001Y1666218D01*
X281146D01*
X282560Y1664804D01*
Y1642093D01*
X286731Y1637921D01*
X379909Y1627558D01*
X390110Y1617802D01*
X394521Y1602738D01*
X395118Y1602413D01*
X395551Y1600934D01*
X395225Y1600338D01*
X395746Y1598558D01*
X400124Y1594180D01*
X402820D01*
X404030Y1595390D01*
G01X278150Y1663346D02*
X279992Y1665188D01*
X280733D01*
X281540Y1664381D01*
Y1641670D01*
X286262Y1636946D01*
X379453Y1626582D01*
X389207Y1617253D01*
X394245Y1600053D01*
X394246Y1600050D01*
X394840Y1598021D01*
X399701Y1593160D01*
X402860D01*
X404030Y1591990D01*
G01X387930Y1585155D02*
X389150Y1586375D01*
Y1590109D01*
X387842Y1591417D01*
G01X391330Y1585155D02*
X390170Y1586315D01*
Y1590170D01*
X391417Y1591417D01*
G01X485480Y107972D02*
X484335Y109117D01*
X483320D01*
X482210Y108007D01*
Y105222D01*
X482700Y104732D01*
Y103232D01*
X482210Y102742D01*
Y101242D01*
X482700Y100752D01*
Y99252D01*
X482210Y98762D01*
Y76196D01*
X485982Y67090D01*
X491750Y61322D01*
X492443D01*
X493505Y60260D01*
Y59567D01*
X494565Y58507D01*
X495258D01*
X496320Y57445D01*
Y56752D01*
X497380Y55692D01*
X498073D01*
X499135Y54630D01*
Y53937D01*
X504209Y48863D01*
X509232Y46782D01*
X531616D01*
X551009Y54814D01*
X561988Y65793D01*
X567207Y78392D01*
X588107Y99292D01*
X610778Y108682D01*
X623845D01*
X634909Y113265D01*
X642228Y120584D01*
X646484Y130857D01*
X653216Y140931D01*
X654350Y143667D01*
Y152734D01*
X700402Y198786D01*
X713267Y204116D01*
X721438Y205741D01*
X728377Y208618D01*
X772160Y232020D01*
X787255Y242107D01*
X794689Y244362D01*
X850820D01*
X893492Y262037D01*
X903632Y272177D01*
X913537Y276280D01*
X937886Y281125D01*
X953246Y287487D01*
X988491Y322732D01*
X1110037D01*
X1130220Y331092D01*
X1298474D01*
X1346686Y351062D01*
X1358012D01*
X1361308Y349697D01*
X1395020Y315985D01*
X1395922Y313807D01*
X1396563Y313542D01*
X1397137Y312155D01*
X1396872Y311515D01*
X1398021Y308741D01*
X1398662Y308475D01*
X1399236Y307089D01*
X1398971Y306448D01*
X1403127Y296412D01*
X1409288Y265439D01*
Y239616D01*
X1409778Y239126D01*
Y237626D01*
X1409288Y237136D01*
Y235636D01*
X1409778Y235146D01*
Y233646D01*
X1409288Y233156D01*
Y231656D01*
X1409778Y231166D01*
Y229666D01*
X1409288Y229176D01*
Y227530D01*
X1407054Y225296D01*
Y224603D01*
X1405993Y223542D01*
X1405300D01*
X1402650Y220892D01*
Y217522D01*
X1404320Y215852D01*
X1405820D01*
X1406310Y216342D01*
X1407810D01*
X1408300Y215852D01*
X1410159D01*
X1410649Y216342D01*
X1412149D01*
X1412639Y215852D01*
X1417580D01*
X1419820Y218092D01*
Y218828D01*
X1418630Y220018D01*
G01X485480Y111282D02*
X484335Y110137D01*
X482897D01*
X481190Y108430D01*
Y75993D01*
X485117Y66512D01*
X503631Y47998D01*
X509029Y45762D01*
X531819D01*
X551587Y53949D01*
X562853Y65215D01*
X568072Y77814D01*
X588685Y98427D01*
X610981Y107662D01*
X624048D01*
X635487Y112400D01*
X643093Y120006D01*
X647389Y130373D01*
X654121Y140447D01*
X655370Y143463D01*
Y152311D01*
X700980Y197921D01*
X713565Y203135D01*
X721736Y204760D01*
X728814Y207694D01*
X772685Y231144D01*
X787696Y241174D01*
X794841Y243342D01*
X851023D01*
X894070Y261172D01*
X904210Y271312D01*
X913835Y275299D01*
X938184Y280144D01*
X953824Y286622D01*
X988914Y321712D01*
X1110240D01*
X1130423Y330072D01*
X1298677D01*
X1346889Y350042D01*
X1357809D01*
X1360730Y348832D01*
X1394155Y315407D01*
X1402146Y296114D01*
X1408268Y265338D01*
Y227953D01*
X1401630Y221315D01*
Y217099D01*
X1403897Y214832D01*
X1418003D01*
X1420840Y217669D01*
Y218828D01*
X1422030Y220018D01*
G01X913394Y521662D02*
X914570Y522838D01*
Y531424D01*
X911369Y539147D01*
X905064Y545451D01*
X777408Y570843D01*
X763139Y576753D01*
X763140D01*
X748778Y582702D01*
X706099Y625383D01*
X675183Y671652D01*
X642680Y750119D01*
Y775506D01*
X639527Y783115D01*
X632987Y789655D01*
Y910322D01*
X630014Y913295D01*
X622908Y918044D01*
X618742Y922210D01*
X617993D01*
X616988Y923215D01*
Y923964D01*
X614970Y925982D01*
X612732Y926910D01*
X608710D01*
X608230Y926430D01*
X606690D01*
X606210Y926910D01*
X602290D01*
X601810Y926430D01*
X600270D01*
X599790Y926910D01*
X597707D01*
X591252Y929583D01*
X590625Y929323D01*
X589238Y929897D01*
X588978Y930525D01*
X582618Y933159D01*
X541617D01*
G01X916794Y521662D02*
X915590Y522866D01*
Y531628D01*
X912234Y539725D01*
X905567Y546392D01*
X777706Y571824D01*
X749356Y583567D01*
X706892Y626034D01*
X676088Y672136D01*
X643700Y750322D01*
Y775709D01*
X640392Y783693D01*
X634007Y790078D01*
Y910745D01*
X632976Y911777D01*
X630665Y914088D01*
X623559Y918837D01*
X615548Y926847D01*
X612936Y927930D01*
X597910D01*
X582821Y934179D01*
X541617D01*
G01X901829Y512730D02*
X900667Y513892D01*
X898525D01*
X896560Y515857D01*
Y518813D01*
X897321Y520647D01*
X900174Y523503D01*
X905713Y527202D01*
X907951Y529930D01*
X909190Y532921D01*
Y534864D01*
X908518Y536485D01*
X903959Y541044D01*
X901925Y541886D01*
X778000Y566535D01*
X745551Y579977D01*
X702148Y623378D01*
X694529Y634782D01*
X671680Y668975D01*
X638940Y748019D01*
Y774335D01*
X634096Y779180D01*
X631817Y784681D01*
X626750Y789748D01*
Y870673D01*
X617400Y880023D01*
Y896939D01*
X610847Y903492D01*
X605337D01*
X581418Y927411D01*
X548837D01*
G01X901829Y516130D02*
X900611Y514912D01*
X898948D01*
X897580Y516280D01*
Y518609D01*
X898186Y520069D01*
X900825Y522710D01*
X906406Y526438D01*
X908836Y529400D01*
X910210Y532718D01*
Y535067D01*
X909383Y537063D01*
X904537Y541909D01*
X902222Y542867D01*
X778298Y567516D01*
X746129Y580842D01*
X702941Y624029D01*
X672585Y669459D01*
X639960Y748222D01*
Y774758D01*
X634961Y779758D01*
X632682Y785259D01*
X627770Y790171D01*
Y871096D01*
X618420Y880446D01*
Y897362D01*
X611270Y904512D01*
X605760D01*
X591160Y919112D01*
Y919861D01*
X590155Y920866D01*
X589406D01*
X588402Y921870D01*
Y922619D01*
X587397Y923624D01*
X586648D01*
X581841Y928431D01*
X548837D01*
G01X736710Y603842D02*
X735540Y605012D01*
X732984D01*
X710567Y627428D01*
X710511Y627511D01*
X681311Y671211D01*
X647520Y752792D01*
Y780794D01*
X645802Y784942D01*
X642360Y788383D01*
Y925226D01*
X638103Y929483D01*
X638078Y929493D01*
X628902Y933295D01*
X600940D01*
X587797Y938739D01*
X542167D01*
G01X736710Y607242D02*
X735500Y606032D01*
X733407D01*
X724366Y615073D01*
Y615823D01*
X723361Y616828D01*
X722611D01*
X711360Y628079D01*
X682216Y671695D01*
X648540Y752995D01*
Y780997D01*
X646667Y785520D01*
X643380Y788806D01*
Y925649D01*
X638593Y930437D01*
X638468D01*
X629105Y934315D01*
X601143D01*
X588000Y939759D01*
X542167D01*
G01X491284Y101473D02*
X490244Y100433D01*
X488741D01*
X487300Y98992D01*
Y88372D01*
X487951Y86800D01*
X487952Y86798D01*
X495521Y68531D01*
X503214Y60838D01*
X520611Y53632D01*
X538562D01*
X541906Y55017D01*
X545363Y58474D01*
X550230Y70223D01*
X583044Y103037D01*
X607324Y113102D01*
X624682D01*
X632685Y116416D01*
X637697Y121428D01*
X639292Y129454D01*
X648624Y151988D01*
X693603Y196967D01*
X698551Y208911D01*
X713163Y214964D01*
X713638Y215059D01*
X719131D01*
X735701Y218355D01*
X750050Y224299D01*
X751726Y225141D01*
X785749Y245540D01*
X795041Y248112D01*
X850674D01*
X890818Y264740D01*
X901145Y275067D01*
X912345Y279706D01*
X937196Y284650D01*
X950447Y290139D01*
X986720Y326412D01*
X1109722D01*
X1129905Y334772D01*
X1298159D01*
X1346371Y354742D01*
X1359707D01*
X1362973Y353389D01*
X1399611Y316751D01*
X1412808Y284892D01*
Y249625D01*
X1417657Y237917D01*
X1424380Y231194D01*
X1426790Y225376D01*
Y217382D01*
X1414484Y205076D01*
X1413806D01*
X1412716Y203986D01*
Y203308D01*
X1410650Y201242D01*
X1406820D01*
X1406340Y201722D01*
X1404800D01*
X1404320Y201242D01*
X1402780D01*
X1402300Y201722D01*
X1400760D01*
X1400280Y201242D01*
X1398630D01*
X1398150Y201722D01*
X1396610D01*
X1396130Y201242D01*
X1374168D01*
X1362850Y189924D01*
G01X491284Y98373D02*
X490244Y99413D01*
X489164D01*
X488320Y98569D01*
Y96352D01*
X488800Y95872D01*
Y94372D01*
X488320Y93892D01*
Y92392D01*
X488800Y91912D01*
Y90412D01*
X488320Y89932D01*
Y88575D01*
X488894Y87190D01*
X489522Y86930D01*
X490096Y85543D01*
X489836Y84916D01*
X490410Y83531D01*
X491038Y83271D01*
X491612Y81884D01*
X491352Y81257D01*
X496386Y69109D01*
X503792Y61703D01*
X520814Y54652D01*
X538358D01*
X541328Y55882D01*
X544498Y59052D01*
X549365Y70801D01*
X582466Y103902D01*
X607120Y114122D01*
X624479D01*
X632107Y117281D01*
X636756Y121931D01*
X638310Y129752D01*
X647759Y152566D01*
X692738Y197545D01*
X697770Y209692D01*
X712865Y215945D01*
X713537Y216079D01*
X719030D01*
X735403Y219336D01*
X749625Y225227D01*
X751233Y226036D01*
X785343Y246486D01*
X794902Y249132D01*
X850471D01*
X890240Y265605D01*
X900567Y275932D01*
X912047Y280687D01*
X936898Y285631D01*
X949869Y291004D01*
X986297Y327432D01*
X1109519D01*
X1129702Y335792D01*
X1297956D01*
X1346168Y355762D01*
X1359910D01*
X1363551Y354254D01*
X1400476Y317329D01*
X1413828Y285095D01*
Y249828D01*
X1418522Y238495D01*
X1425245Y231772D01*
X1427810Y225579D01*
Y216959D01*
X1411073Y200222D01*
X1374592D01*
X1363572Y189202D01*
G01X493384Y101473D02*
X494350Y100507D01*
X497585D01*
X497774Y100696D01*
X498487D01*
G01X493384Y98373D02*
X494498Y99487D01*
X497585D01*
X497754Y99318D01*
X498487D01*
G01X487580Y107972D02*
X488730Y109122D01*
X490347D01*
X493082Y106387D01*
X497585D01*
X497764Y106208D01*
X498487D01*
G01X487580Y111282D02*
X488720Y110142D01*
X490770D01*
X493505Y107407D01*
X497585D01*
X497764Y107586D01*
X498487D01*
G01X518380Y98012D02*
Y97812D01*
X517450Y96882D01*
X515822D01*
X512197Y100507D01*
X509045D01*
X508856Y100696D01*
X508133D01*
G01X518380Y94882D02*
X517400Y95862D01*
X515399D01*
X511774Y99487D01*
X509035D01*
X508866Y99318D01*
X508133D01*
G01X517115Y107550D02*
X515782Y108883D01*
X514026D01*
X511530Y106387D01*
X509035D01*
G01X517115Y111060D02*
X515958Y109903D01*
X513603D01*
X511107Y107407D01*
X509035D01*
G01X525900Y107375D02*
X527285Y108760D01*
X529922D01*
X533370Y105312D01*
Y90830D01*
X532890Y90350D01*
Y88810D01*
X533370Y88330D01*
Y86790D01*
X532890Y86310D01*
Y84770D01*
X533370Y84290D01*
Y82750D01*
X532890Y82270D01*
Y80730D01*
X533370Y80250D01*
Y78710D01*
X532890Y78230D01*
Y76690D01*
X533370Y76210D01*
Y74670D01*
X535105Y70481D01*
Y61012D01*
X533915Y59822D01*
G01X520480Y98012D02*
X521510Y96982D01*
X526145D01*
X527310Y98147D01*
G01X520480Y94882D02*
X520490D01*
X521570Y95962D01*
X526095D01*
X527310Y94747D01*
G01X520265Y107550D02*
X521510Y108795D01*
X524480D01*
X525900Y107375D01*
G01Y111125D02*
X524590Y109815D01*
X521510D01*
X520265Y111060D01*
G01X525900Y111125D02*
X527245Y109780D01*
X530345D01*
X534390Y105735D01*
Y74873D01*
X536125Y70684D01*
Y61012D01*
X537315Y59822D01*
G01X1410370Y138742D02*
X1409180Y139932D01*
Y142667D01*
X1405785Y146062D01*
X1402354Y147483D01*
Y147484D01*
X1396312Y149986D01*
X1396310Y149987D01*
X1376670Y158122D01*
X1364740Y170052D01*
Y183831D01*
X1374161Y193252D01*
X1420733D01*
X1445280Y217799D01*
Y223576D01*
X1443647Y226021D01*
X1431149Y236278D01*
X1422104Y245323D01*
X1418368Y254341D01*
Y286126D01*
X1404147Y320458D01*
X1366365Y358240D01*
X1361241Y360362D01*
X1345406D01*
X1297196Y340392D01*
X1128942D01*
X1108759Y332032D01*
X984330D01*
X947049Y294751D01*
X935571Y289997D01*
X910722Y285053D01*
X895460Y278732D01*
X885133Y268405D01*
X867628Y261155D01*
X867627Y261154D01*
X850120Y253902D01*
X794146D01*
X776874Y248663D01*
X750340Y230934D01*
X746224Y228734D01*
X734176Y223742D01*
X703114D01*
X699971Y222440D01*
X690158Y212627D01*
X682210Y193439D01*
X643600Y154829D01*
X635989Y136454D01*
X632161Y132626D01*
X590721Y115459D01*
X583718Y111262D01*
X571725Y101422D01*
Y101419D01*
X554911Y87623D01*
X549260Y81972D01*
Y80562D01*
X548070Y79372D01*
G01X541370Y88752D02*
X542870Y87252D01*
Y83892D01*
X542192Y83214D01*
Y72626D01*
X541002Y71436D01*
G01X545450Y88752D02*
X543890Y87192D01*
Y83469D01*
X543212Y82791D01*
Y72626D01*
X544402Y71436D01*
G01X541370Y91902D02*
X542900Y93432D01*
Y95329D01*
X546110Y98539D01*
Y100647D01*
G01X553063Y109171D02*
Y107689D01*
X553286Y107466D01*
Y105715D01*
X548218Y100647D01*
X546110D01*
G01X548942Y97821D02*
X546835D01*
X543920Y94906D01*
Y93432D01*
X545450Y91902D01*
G01X554637Y109171D02*
Y107569D01*
X554306Y107238D01*
Y105292D01*
X548942Y99928D01*
Y97821D01*
G01X1406970Y138742D02*
X1408160Y139932D01*
Y142244D01*
X1405207Y145197D01*
X1401964Y146540D01*
X1401337Y146280D01*
X1399913Y146869D01*
X1399653Y147497D01*
X1398231Y148086D01*
X1397604Y147826D01*
X1396180Y148416D01*
X1395921Y149044D01*
X1393686Y149969D01*
X1393059Y149709D01*
X1391635Y150299D01*
X1391375Y150927D01*
X1387027Y152727D01*
X1386400Y152468D01*
X1384976Y153057D01*
X1384716Y153685D01*
X1376092Y157257D01*
X1363720Y169629D01*
Y184254D01*
X1373738Y194272D01*
X1420310D01*
X1444260Y218222D01*
Y223266D01*
X1442882Y225328D01*
X1430463Y235521D01*
X1421239Y244745D01*
X1417348Y254138D01*
Y285923D01*
X1403282Y319880D01*
X1365787Y357375D01*
X1361038Y359342D01*
X1345609D01*
X1297399Y339372D01*
X1129145D01*
X1108962Y331012D01*
X984753D01*
X947627Y293886D01*
X935869Y289016D01*
X911020Y284072D01*
X896038Y277867D01*
X885711Y267540D01*
X868206Y260290D01*
X868205Y260289D01*
X850323Y252882D01*
X794298D01*
X777315Y247730D01*
X750865Y230058D01*
X746661Y227810D01*
X734379Y222722D01*
X703318D01*
X700549Y221575D01*
X691023Y212049D01*
X683075Y192861D01*
X644465Y154251D01*
X636854Y135876D01*
X632739Y131761D01*
X595228Y116222D01*
X594963Y115581D01*
X593391Y114930D01*
X592751Y115195D01*
X591181Y114545D01*
X584307Y110425D01*
X572699Y100901D01*
X572632Y100225D01*
X571440Y99247D01*
X570765Y99314D01*
X570766Y99313D01*
X568978Y97846D01*
X568977Y97847D01*
X568911Y97171D01*
X567719Y96193D01*
X567044Y96260D01*
Y96259D01*
X565328Y94851D01*
Y94852D01*
X565262Y94176D01*
X564070Y93198D01*
X563395Y93265D01*
X561844Y91992D01*
X561778Y91317D01*
X560586Y90339D01*
X559911Y90405D01*
X555597Y86866D01*
X550280Y81549D01*
Y80562D01*
X551470Y79372D01*
G01X553063Y114683D02*
Y116285D01*
X553394Y116616D01*
Y119386D01*
X554430Y121885D01*
Y122628D01*
X554890Y123739D01*
X565265Y134114D01*
X570531Y136295D01*
X576994Y137582D01*
X595444D01*
X598746Y138950D01*
X599430Y140601D01*
Y157484D01*
X603362Y166977D01*
X609782Y173397D01*
Y176112D01*
X611980Y178310D01*
X614399D01*
X615573Y179484D01*
G01X554637Y114683D02*
Y116165D01*
X554414Y116388D01*
Y119182D01*
X555450Y121681D01*
Y122425D01*
X555755Y123161D01*
X556468Y123874D01*
X557161D01*
X558223Y124936D01*
Y125629D01*
X559283Y126689D01*
X559976D01*
X561038Y127751D01*
Y128444D01*
X562098Y129504D01*
X562791D01*
X563853Y130566D01*
Y131259D01*
X565843Y133249D01*
X570829Y135314D01*
X577095Y136562D01*
X579419D01*
X579909Y136072D01*
X581409D01*
X581899Y136562D01*
X595647D01*
X599527Y138169D01*
X600450Y140398D01*
Y157281D01*
X604227Y166399D01*
X610802Y172974D01*
Y175689D01*
X612403Y177290D01*
X614724D01*
X615572Y176442D01*
G01X659877Y188372D02*
X658387Y189862D01*
X650713D01*
X648355Y189393D01*
Y189394D01*
X647978Y188828D01*
X646467Y188528D01*
X645902Y188905D01*
X640184Y187767D01*
Y187768D01*
X639807Y187202D01*
X638295Y186902D01*
X637731Y187279D01*
X636901Y187114D01*
X631606Y184921D01*
X631346Y184293D01*
X629922Y183704D01*
X629295Y183964D01*
X627873Y183375D01*
X625170Y180672D01*
Y176272D01*
X626330Y175112D01*
X627393D01*
X628195Y175914D01*
G01X659871Y192372D02*
X658381Y190882D01*
X650612D01*
X636604Y188096D01*
X627295Y184240D01*
X624150Y181095D01*
Y175849D01*
X625907Y174092D01*
X626990D01*
X628194Y172888D01*
Y172872D01*
G01X1360385Y193979D02*
X1372298Y205892D01*
X1389597D01*
X1397070Y213365D01*
Y223331D01*
X1401170Y227431D01*
Y230819D01*
X1395800Y236189D01*
Y282943D01*
X1394316Y290402D01*
X1389480Y302078D01*
Y305222D01*
X1388990Y305712D01*
Y307212D01*
X1389480Y307702D01*
Y312762D01*
X1383684Y318558D01*
X1382992D01*
X1381895Y319655D01*
Y320347D01*
X1380799Y321443D01*
X1380107D01*
X1379010Y322540D01*
Y323232D01*
X1377914Y324328D01*
X1377222D01*
X1376125Y325425D01*
Y326117D01*
X1375029Y327213D01*
X1374337D01*
X1373240Y328310D01*
Y329002D01*
X1357680Y344562D01*
X1345526D01*
X1298690Y325162D01*
X1130435D01*
X1108949Y316262D01*
X989930D01*
X956108Y282440D01*
X940044Y275786D01*
X915896Y270982D01*
X906863Y267242D01*
X897157Y257536D01*
X874483Y248143D01*
X874482Y248142D01*
X851808Y238752D01*
X795623D01*
X752543Y195672D01*
X737860D01*
X723290Y181102D01*
X713210D01*
X707090Y174982D01*
X684464D01*
X660540Y151058D01*
Y141731D01*
X657720Y134922D01*
X652610Y129811D01*
X651654Y128380D01*
X643430Y108528D01*
Y97087D01*
X643920Y96597D01*
Y95047D01*
X643430Y94557D01*
Y93007D01*
X643920Y92517D01*
Y90967D01*
X643430Y90477D01*
Y88927D01*
X643920Y88437D01*
Y86887D01*
X643430Y86397D01*
Y83422D01*
X641180Y81172D01*
Y78477D01*
X641670Y77987D01*
Y76437D01*
X641180Y75947D01*
Y74397D01*
X641670Y73907D01*
Y72357D01*
X641180Y71867D01*
Y69392D01*
X646440Y64132D01*
X647132D01*
X648229Y63035D01*
Y62343D01*
X649325Y61247D01*
X650017D01*
X651114Y60150D01*
Y59458D01*
X652210Y58362D01*
Y54577D01*
X652700Y54087D01*
Y52537D01*
X652210Y52047D01*
Y49232D01*
X652700Y48742D01*
Y47242D01*
X652210Y46752D01*
Y44817D01*
X652700Y44327D01*
Y42777D01*
X652210Y42287D01*
Y41510D01*
X653044Y39497D01*
X655257Y36186D01*
X656545Y34897D01*
X657237D01*
X658334Y33800D01*
Y33108D01*
X659430Y32012D01*
X663792D01*
X664715Y32935D01*
Y35032D01*
X663561Y36186D01*
G01X1361107Y193257D02*
X1372722Y204872D01*
X1390020D01*
X1398090Y212942D01*
Y222908D01*
X1402190Y227008D01*
Y231242D01*
X1396820Y236612D01*
Y283044D01*
X1395297Y290700D01*
X1390500Y302281D01*
Y313185D01*
X1358103Y345582D01*
X1345323D01*
X1298487Y326182D01*
X1130232D01*
X1108746Y317282D01*
X989507D01*
X955530Y283305D01*
X939746Y276767D01*
X915598Y271964D01*
X906285Y268107D01*
X896579Y258401D01*
X851605Y239772D01*
X795200D01*
X752120Y196692D01*
X737437D01*
X722867Y182122D01*
X712787D01*
X706667Y176002D01*
X684041D01*
X659520Y151481D01*
Y141934D01*
X656855Y135500D01*
X651817Y130462D01*
X650749Y128864D01*
X642410Y108731D01*
Y83845D01*
X640160Y81595D01*
Y68969D01*
X651190Y57939D01*
Y41307D01*
X652140Y39014D01*
X654464Y35535D01*
X659007Y30992D01*
X664215D01*
X665735Y32512D01*
Y35033D01*
X666889Y36187D01*
G01X663561Y38286D02*
X664715Y39440D01*
Y42156D01*
X663543Y43328D01*
G01X659877Y188372D02*
X661367Y189862D01*
X670382D01*
X674447Y191546D01*
X679685Y196784D01*
X687381Y215363D01*
X696140Y224122D01*
X702513Y226762D01*
X733573D01*
X740518Y229639D01*
X752309Y235940D01*
X775408Y251375D01*
X795541Y257482D01*
X850757D01*
X870602Y265702D01*
X872035Y268386D01*
X874609Y278537D01*
X879579Y290534D01*
X879578D01*
X880220Y290799D01*
X880794Y292185D01*
X880528Y292826D01*
X881102Y294211D01*
X881773Y294488D01*
X882362Y295912D01*
X882097Y296552D01*
X882686Y297974D01*
X883327Y298239D01*
X883916Y299663D01*
X883651Y300303D01*
X884723Y302892D01*
X885364Y303158D01*
X885953Y304581D01*
X885688Y305221D01*
X886719Y307710D01*
X886769Y307832D01*
X887410Y308097D01*
X887999Y309521D01*
X887734Y310161D01*
X898938Y337210D01*
X909987Y348259D01*
X924070Y354092D01*
X935217D01*
X947857Y348856D01*
X955094Y341619D01*
X970103Y335402D01*
X1109001D01*
X1129305Y343812D01*
X1297557D01*
X1344876Y363412D01*
X1362676D01*
X1367924Y361238D01*
X1407217Y321945D01*
X1421388Y287733D01*
Y261021D01*
X1424377Y253805D01*
X1444266Y233916D01*
X1448470Y223767D01*
Y216638D01*
X1444774Y207716D01*
X1430840Y193782D01*
X1430147D01*
X1429085Y192720D01*
Y192027D01*
X1426590Y189532D01*
X1425060D01*
X1424570Y190022D01*
X1423070D01*
X1422580Y189532D01*
X1378837D01*
X1367830Y178525D01*
Y174041D01*
X1368491Y172447D01*
X1368492Y172446D01*
X1369152Y170851D01*
X1374493Y165510D01*
X1402478Y153922D01*
X1405839D01*
X1407029Y152732D01*
G01Y156132D02*
X1405839Y154942D01*
X1402681D01*
X1401296Y155515D01*
X1401030Y156157D01*
X1399643Y156730D01*
X1399003Y156465D01*
X1375071Y166375D01*
X1370017Y171429D01*
X1368850Y174245D01*
Y178102D01*
X1379260Y188512D01*
X1382470D01*
X1382960Y188022D01*
X1384460D01*
X1384950Y188512D01*
X1427013D01*
X1445639Y207138D01*
X1449490Y216435D01*
Y223970D01*
X1445131Y234494D01*
X1425242Y254383D01*
X1422408Y261224D01*
Y287936D01*
X1408082Y322523D01*
X1368502Y362103D01*
X1362879Y364432D01*
X1344673D01*
X1297354Y344832D01*
X1129102D01*
X1108798Y336422D01*
X970306D01*
X955672Y342484D01*
X948435Y349721D01*
X935420Y355112D01*
X923867D01*
X909409Y349124D01*
X898073Y337788D01*
X880352Y295006D01*
X880321Y294993D01*
X873638Y278859D01*
X871076Y268757D01*
X869874Y266505D01*
X850554Y258502D01*
X795389D01*
X774967Y252308D01*
X751784Y236816D01*
X740081Y230563D01*
X733370Y227782D01*
X702310D01*
X695562Y224987D01*
X686516Y215941D01*
X678820Y197362D01*
X673869Y192411D01*
X670179Y190882D01*
X661361D01*
X659871Y192372D01*
G01X666889Y38287D02*
X665735Y39441D01*
Y42120D01*
X666943Y43328D01*
G01X670612Y47264D02*
X671680Y48332D01*
Y51007D01*
X670080Y52607D01*
G01X674012Y47264D02*
X672700Y48576D01*
Y51227D01*
X674080Y52607D01*
G01X670080Y55757D02*
X671570Y57247D01*
Y60066D01*
X673343Y61839D01*
X677070Y63382D01*
X725159D01*
X730229Y65483D01*
X752778Y67702D01*
X761091D01*
X764313Y66369D01*
X775880Y54802D01*
X807524D01*
X856293Y64503D01*
X862667Y67143D01*
X864120Y68596D01*
Y68882D01*
X862930Y70072D01*
G01X674080Y55757D02*
X672590Y57247D01*
Y59643D01*
X673921Y60974D01*
X677273Y62362D01*
X725362D01*
X730480Y64482D01*
X752829Y66682D01*
X760888D01*
X763735Y65504D01*
X775457Y53782D01*
X807625D01*
X856591Y63522D01*
X863245Y66278D01*
X865140Y68173D01*
Y68882D01*
X866330Y70072D01*
G01X720360Y-20516D02*
X723041Y-19800D01*
G01X720360Y-22484D02*
X723041Y-23200D01*
G01X732793Y71436D02*
X733983Y72626D01*
Y73391D01*
X732501Y74873D01*
G01X736193Y71436D02*
X735003Y72626D01*
Y73362D01*
X736514Y74873D01*
X736601D01*
G01X733879Y83664D02*
X735394Y82149D01*
Y81936D01*
X734782Y80459D01*
X734099Y79776D01*
Y78665D01*
X733457Y78023D01*
X732501D01*
G01X733879Y83664D02*
X735394Y85179D01*
Y85953D01*
X736491Y87050D01*
X742312D01*
X748594Y84448D01*
X751623Y81419D01*
X758879Y78413D01*
X776990Y60302D01*
X810935D01*
X845772Y78923D01*
X856702Y89853D01*
X868180Y117564D01*
Y129383D01*
X871339Y137011D01*
X878048Y143720D01*
X882809Y145692D01*
X1013530D01*
X1019663Y143150D01*
X1029104Y133709D01*
X1030801Y129611D01*
X1035072Y125340D01*
X1149862Y77792D01*
X1153303D01*
X1169403Y71123D01*
X1183710Y56816D01*
X1188379Y54882D01*
X1258059D01*
X1260510Y55897D01*
X1269597D01*
X1277226Y52737D01*
X1344231D01*
X1377783Y66635D01*
X1416294Y105146D01*
X1418792Y111177D01*
X1418532Y111804D01*
X1419121Y113228D01*
X1419750Y113488D01*
X1420593Y115525D01*
X1420334Y116152D01*
X1420923Y117576D01*
X1421551Y117836D01*
X1422740Y120707D01*
Y128582D01*
X1422260Y129062D01*
Y130602D01*
X1422740Y131082D01*
Y135222D01*
X1422260Y135702D01*
Y137242D01*
X1422740Y137722D01*
Y141782D01*
X1422260Y142262D01*
Y143802D01*
X1422740Y144282D01*
Y148762D01*
X1422260Y149242D01*
Y150782D01*
X1422740Y151262D01*
Y155572D01*
X1422260Y156052D01*
Y157592D01*
X1422740Y158072D01*
Y161132D01*
X1422260Y161612D01*
Y163152D01*
X1422740Y163632D01*
Y167402D01*
X1422260Y167882D01*
Y169422D01*
X1422740Y169902D01*
Y171442D01*
X1420052Y174130D01*
X1406508D01*
X1405988Y173610D01*
Y172874D01*
X1407178Y171684D01*
G01X736601Y78023D02*
X735761D01*
X735119Y78665D01*
Y79353D01*
X735647Y79881D01*
X736414Y81733D01*
Y82199D01*
X737929Y83714D01*
G01D02*
X736414Y85229D01*
Y85530D01*
X736914Y86030D01*
X742109D01*
X748016Y83583D01*
X751045Y80554D01*
X758301Y77548D01*
X776567Y59282D01*
X811191D01*
X846387Y78094D01*
X857567Y89275D01*
X869200Y117361D01*
Y129180D01*
X872204Y136433D01*
X878626Y142855D01*
X883012Y144672D01*
X1013326D01*
X1019085Y142285D01*
X1028239Y133131D01*
X1029936Y129033D01*
X1034494Y124475D01*
X1149659Y76772D01*
X1153100D01*
X1168825Y70258D01*
X1183132Y55951D01*
X1188176Y53862D01*
X1258262D01*
X1260713Y54877D01*
X1269394D01*
X1277023Y51717D01*
X1344434D01*
X1378361Y65770D01*
X1417159Y104568D01*
X1423760Y120503D01*
Y171865D01*
X1420475Y175150D01*
X1406085D01*
X1404968Y174033D01*
Y172874D01*
X1403778Y171684D01*
G01X837320Y7516D02*
X840001Y6800D01*
G01X837320Y9484D02*
X840001Y10200D01*
G01X922879Y531976D02*
X924073Y530782D01*
X925701D01*
X927996Y533077D01*
X928353D01*
G01X922879Y528576D02*
X924055Y529752D01*
X925839D01*
X927840Y527751D01*
X928276D01*
G01X1327646Y537321D02*
X1326902D01*
X1325010Y539213D01*
X1320763D01*
X1303128Y531908D01*
X1280973Y509753D01*
X1252072Y497782D01*
X1002777Y448194D01*
X974477Y439610D01*
X954597Y419730D01*
X939205D01*
X937810Y421125D01*
Y425030D01*
X938137Y425820D01*
X939038Y426721D01*
X939869D01*
X941059Y427911D01*
G01X1327723Y542647D02*
X1327226D01*
X1324812Y540233D01*
X1320560D01*
X1302550Y532773D01*
X1280395Y510618D01*
X1251774Y498763D01*
X1002529Y449185D01*
X973936Y440512D01*
X971187Y437763D01*
X970494D01*
X969432Y436701D01*
Y436008D01*
X968372Y434948D01*
X967679D01*
X966617Y433886D01*
Y433193D01*
X965434Y432010D01*
X964741D01*
X963679Y430948D01*
Y430255D01*
X962619Y429195D01*
X961926D01*
X960864Y428133D01*
Y427440D01*
X959804Y426380D01*
X959111D01*
X958049Y425318D01*
Y424625D01*
X956989Y423565D01*
X956296D01*
X955234Y422503D01*
Y421810D01*
X954174Y420750D01*
X951039D01*
X950549Y421240D01*
X949049D01*
X948559Y420750D01*
X947059D01*
X946569Y421240D01*
X945069D01*
X944579Y420750D01*
X939628D01*
X938830Y421548D01*
Y424827D01*
X939002Y425242D01*
X939461Y425701D01*
X939869D01*
X941059Y424511D01*
G01X933773Y530479D02*
Y530609D01*
X931503Y532879D01*
Y533077D01*
G01X930731Y530479D02*
X930963D01*
X932100Y529342D01*
Y528425D01*
X931426Y527751D01*
G01X941050Y532252D02*
X939760Y530962D01*
X938580D01*
X936465Y533077D01*
X934653D01*
G01X941050Y528852D02*
X939960Y529942D01*
X938430D01*
X936239Y527751D01*
X934576D01*
G01X946727Y507952D02*
X947917Y506762D01*
X950020D01*
X951020Y507762D01*
Y510504D01*
X949647Y517406D01*
Y529708D01*
X969169Y576838D01*
X993625Y628570D01*
X1073550Y708494D01*
X1084632Y713084D01*
X1136879D01*
X1161754Y723388D01*
X1172585Y734219D01*
X1179646Y751271D01*
X1180223Y752133D01*
X1184320Y762025D01*
Y779585D01*
X1186500Y784848D01*
Y941785D01*
X1188542Y943827D01*
X1200492Y948777D01*
X1206252Y954537D01*
Y955230D01*
X1207342Y956320D01*
X1208035D01*
X1209917Y958202D01*
Y958895D01*
X1211007Y959985D01*
X1211700D01*
X1218656Y966941D01*
X1219962Y967482D01*
X1222928D01*
X1229098Y964927D01*
X1235012Y959013D01*
X1238143Y957716D01*
X1261948Y952981D01*
X1289669D01*
X1300244Y948601D01*
X1305297Y943548D01*
X1306033D01*
G01X946727Y504552D02*
X947917Y505742D01*
X950443D01*
X952040Y507339D01*
Y510605D01*
X950667Y517507D01*
Y529505D01*
X970102Y576425D01*
X994472Y627973D01*
X1074128Y707629D01*
X1084835Y712064D01*
X1137082D01*
X1162332Y722523D01*
X1173450Y733641D01*
X1180551Y750787D01*
X1181127Y751649D01*
X1185340Y761822D01*
Y779382D01*
X1187520Y784645D01*
Y941362D01*
X1189120Y942962D01*
X1201070Y947912D01*
X1219234Y966076D01*
X1220165Y966462D01*
X1222725D01*
X1228520Y964062D01*
X1234434Y958148D01*
X1237845Y956735D01*
X1261847Y951961D01*
X1289466D01*
X1299666Y947736D01*
X1304874Y942528D01*
X1306033D01*
G01X954420Y514652D02*
X954494D01*
X955684Y513462D01*
X959270D01*
X962978Y514998D01*
X963244Y515639D01*
X964667Y516228D01*
X965308Y515963D01*
X972098Y518774D01*
X993190Y522971D01*
X1049790Y528546D01*
X1206114Y559640D01*
X1254680D01*
X1344507Y596849D01*
X1344508D01*
X1355366Y607707D01*
X1405661Y641090D01*
X1425294Y649082D01*
X1445179Y658712D01*
X1452584Y661778D01*
X1458502Y662955D01*
X1463060D01*
X1467203Y664212D01*
X1478818Y671973D01*
X1491496Y690950D01*
X1531325Y730779D01*
X1543568Y760334D01*
X1563100Y779866D01*
Y900958D01*
X1562207Y903113D01*
X1560231Y905089D01*
X1559538D01*
X1558448Y906179D01*
Y906872D01*
X1557360Y907960D01*
X1556667D01*
X1555578Y909049D01*
Y909742D01*
X1552930Y912390D01*
X1552237D01*
X1551148Y913479D01*
Y914172D01*
X1549626Y915694D01*
X1548933D01*
X1547843Y916784D01*
Y917477D01*
X1546755Y918565D01*
X1546062D01*
X1544973Y919654D01*
Y920347D01*
X1543535Y921785D01*
X1542842D01*
X1541753Y922874D01*
Y923567D01*
X1539551Y925769D01*
X1538858D01*
X1537768Y926859D01*
Y927552D01*
X1536680Y928640D01*
X1531592Y930748D01*
X1530952Y930483D01*
X1529528Y931072D01*
X1529263Y931713D01*
X1524940Y933504D01*
X1519159D01*
X1519155Y933508D01*
X1518207D01*
G01X954420Y511252D02*
X955610Y512442D01*
X959473D01*
X972396Y517793D01*
X993340Y521960D01*
X1049940Y527535D01*
X1206215Y558620D01*
X1254883D01*
X1345086Y595984D01*
X1356016Y606913D01*
X1381079Y623549D01*
Y623548D01*
X1406141Y640183D01*
X1425709Y648149D01*
X1445597Y657781D01*
X1452882Y660796D01*
X1458603Y661935D01*
X1463212D01*
X1467644Y663279D01*
X1479554Y671237D01*
X1492289Y690299D01*
X1532190Y730201D01*
X1544433Y759756D01*
X1564120Y779443D01*
Y901161D01*
X1563072Y903691D01*
X1537258Y929505D01*
X1525143Y934524D01*
X1519020D01*
X1519016Y934528D01*
X1518207D01*
G01X954390Y527596D02*
X955580Y526406D01*
Y525247D01*
X956515Y524312D01*
X979404D01*
X1040073Y530288D01*
X1070186Y536277D01*
Y536280D01*
X1200823Y562262D01*
X1253295D01*
X1343164Y599488D01*
X1352864Y609187D01*
X1404017Y643361D01*
X1415805Y648242D01*
X1427824Y653219D01*
X1449831Y671278D01*
X1454723Y673305D01*
X1461811D01*
X1467156Y674926D01*
X1480488Y683836D01*
X1529153Y732503D01*
X1541529Y762379D01*
X1559330Y780180D01*
Y900590D01*
X1558740Y902015D01*
X1537638Y923117D01*
X1524919Y928386D01*
X1523286Y930019D01*
X1521159Y930900D01*
X1519020D01*
X1519015Y930895D01*
X1518207D01*
G01X957790Y527596D02*
X956600Y526406D01*
Y525670D01*
X956938Y525332D01*
X979353D01*
X1039923Y531299D01*
X1042955Y531902D01*
X1043339Y532479D01*
X1044851Y532779D01*
X1045427Y532394D01*
X1048059Y532917D01*
X1048444Y533494D01*
X1049956Y533795D01*
X1050532Y533410D01*
X1053556Y534011D01*
X1053941Y534588D01*
X1055453Y534889D01*
X1056029Y534504D01*
X1058567Y535008D01*
X1058952Y535586D01*
X1060464Y535886D01*
X1061040Y535501D01*
X1063078Y535906D01*
X1063463Y536483D01*
X1064974Y536783D01*
X1065550Y536398D01*
X1067515Y536788D01*
X1067900Y537366D01*
X1069412Y537666D01*
X1069988Y537281D01*
X1200722Y563282D01*
X1253092D01*
X1342586Y600353D01*
X1352213Y609980D01*
X1403533Y644266D01*
X1427294Y654104D01*
X1449300Y672163D01*
X1454520Y674325D01*
X1461659D01*
X1466715Y675859D01*
X1479837Y684629D01*
X1528288Y733081D01*
X1540664Y762957D01*
X1558310Y780603D01*
Y900387D01*
X1557875Y901437D01*
X1557431Y901881D01*
X1556738D01*
X1555649Y902970D01*
Y903663D01*
X1554286Y905026D01*
X1553593D01*
X1552503Y906116D01*
Y906809D01*
X1551415Y907897D01*
X1550722D01*
X1549632Y908987D01*
Y909680D01*
X1548544Y910768D01*
X1547851D01*
X1546761Y911858D01*
Y912551D01*
X1545673Y913639D01*
X1544980D01*
X1543890Y914729D01*
Y915422D01*
X1542802Y916510D01*
X1542109D01*
X1541019Y917600D01*
Y918293D01*
X1539931Y919381D01*
X1539238D01*
X1538148Y920471D01*
Y921164D01*
X1537060Y922252D01*
X1534783Y923195D01*
X1534143Y922930D01*
X1532719Y923519D01*
X1532454Y924160D01*
X1529546Y925365D01*
X1528906Y925099D01*
X1527482Y925689D01*
X1527217Y926330D01*
X1524341Y927521D01*
X1522708Y929154D01*
X1520956Y929880D01*
X1519066D01*
X1519061Y929875D01*
X1518207D01*
G01X963930Y533362D02*
X965120Y534552D01*
Y539088D01*
X968623Y556697D01*
X997776Y627079D01*
X1076449Y705752D01*
X1085363Y709444D01*
X1137605D01*
X1163817Y720302D01*
X1175672Y732157D01*
X1182839Y749457D01*
X1183479Y750415D01*
X1187960Y761235D01*
Y777652D01*
X1188357Y778608D01*
X1193471Y783724D01*
X1194280Y785674D01*
Y938621D01*
X1196573Y940915D01*
X1201564Y944250D01*
X1205142Y947827D01*
X1211547Y950482D01*
X1222131D01*
X1228883Y947682D01*
X1291890D01*
X1294925Y946425D01*
X1303101Y938249D01*
X1306033D01*
G01X967330Y533362D02*
X966140Y534552D01*
Y538987D01*
X969604Y556399D01*
X998641Y626501D01*
X1077027Y704887D01*
X1085566Y708424D01*
X1137808D01*
X1164395Y719437D01*
X1176537Y731579D01*
X1183744Y748973D01*
X1184384Y749931D01*
X1188980Y761032D01*
Y777448D01*
X1189222Y778029D01*
X1194336Y783146D01*
X1195300Y785470D01*
Y938198D01*
X1197224Y940122D01*
X1202215Y943457D01*
X1205720Y946962D01*
X1211751Y949462D01*
X1221927D01*
X1228679Y946662D01*
X1270030D01*
X1270520Y946172D01*
X1272020D01*
X1272510Y946662D01*
X1274010D01*
X1274500Y946172D01*
X1276000D01*
X1276490Y946662D01*
X1291687D01*
X1294347Y945560D01*
X1302678Y937229D01*
X1306033D01*
G01X983580Y-20516D02*
X980899Y-19800D01*
G01X983580Y-22484D02*
X980899Y-23200D01*
G01X983580Y7516D02*
X980899Y6800D01*
G01X983580Y9484D02*
X980899Y10200D01*
G01X1029752Y-30527D02*
X1032433Y-29811D01*
G01X1029752Y-32495D02*
X1032433Y-33211D01*
G01X1029752Y-12495D02*
X1032433Y-13211D01*
G01X1029752Y-10527D02*
X1032433Y-9811D01*
G01X1029752Y9473D02*
X1030188D01*
X1030616Y9045D01*
X1045627D01*
X1047721Y7289D01*
X1049223Y-1229D01*
X1049824Y-1650D01*
X1054640Y-801D01*
X1055063Y-198D01*
X1051321Y21017D01*
X1052229Y22310D01*
X1057878Y23307D01*
X1059171Y22399D01*
X1063320Y-1124D01*
X1063921Y-1546D01*
X1068737Y-697D01*
X1069160Y-94D01*
X1065456Y20904D01*
X1066364Y22197D01*
X1072013Y23194D01*
X1073306Y22286D01*
X1077417Y-1020D01*
X1078018Y-1442D01*
X1082834Y-593D01*
X1083257Y10D01*
X1079594Y20777D01*
X1080502Y22072D01*
X1086151Y23069D01*
X1087443Y22161D01*
X1091514Y-916D01*
X1092115Y-1338D01*
X1096931Y-489D01*
X1097354Y114D01*
X1093662Y21045D01*
X1094570Y22338D01*
X1100219Y23335D01*
X1101512Y22427D01*
X1105611Y-812D01*
X1106212Y-1234D01*
X1111028Y-385D01*
X1111451Y218D01*
X1107767Y21102D01*
X1108675Y22394D01*
X1114323Y23390D01*
X1115617Y22485D01*
X1119737Y-877D01*
X1120339Y-1299D01*
X1125155Y-450D01*
X1125577Y153D01*
X1121878Y21126D01*
X1122770Y22397D01*
X1128457Y23400D01*
X1129728Y22508D01*
X1133848Y-858D01*
X1134450Y-1280D01*
X1139266Y-431D01*
X1139688Y172D01*
X1135989Y21147D01*
X1136881Y22418D01*
X1142568Y23421D01*
X1143839Y22529D01*
X1148029Y-1238D01*
X1148632Y-1660D01*
X1153448Y-811D01*
X1153869Y-210D01*
X1150079Y21280D01*
X1150971Y22551D01*
X1156658Y23554D01*
X1157929Y22662D01*
X1162084Y-903D01*
X1162687Y-1327D01*
Y-1326D01*
X1167502Y-477D01*
X1167925Y125D01*
X1164210Y21186D01*
X1165102Y22457D01*
X1170789Y23460D01*
X1172060Y22568D01*
X1176181Y-799D01*
X1176783Y-1221D01*
X1181598Y-372D01*
X1182020Y231D01*
X1178299Y21339D01*
X1179188Y22613D01*
X1184876Y23615D01*
X1186170Y22710D01*
X1190274Y-556D01*
X1190875Y-978D01*
X1195691Y-129D01*
X1196114Y474D01*
X1192477Y21099D01*
X1193383Y22393D01*
X1199032Y23390D01*
X1200326Y22483D01*
X1204400Y-621D01*
X1205002Y-1043D01*
X1209818Y-194D01*
X1210240Y408D01*
X1206579Y21173D01*
X1207469Y22445D01*
X1213156Y23447D01*
X1214427Y22557D01*
X1218511Y-602D01*
X1219113Y-1024D01*
X1223929Y-175D01*
X1224351Y428D01*
X1220702Y21123D01*
X1221592Y22395D01*
X1227279Y23397D01*
X1228551Y22507D01*
X1232692Y-982D01*
X1233295Y-1404D01*
X1238111Y-555D01*
X1238532Y46D01*
X1234814Y21131D01*
X1235704Y22403D01*
X1241391Y23405D01*
X1242663Y22515D01*
X1246747Y-649D01*
X1247350Y-1071D01*
X1252165Y-221D01*
X1252587Y381D01*
X1248911Y21228D01*
X1249801Y22500D01*
X1255488Y23502D01*
X1256760Y22612D01*
X1260843Y-543D01*
X1261446Y-965D01*
X1266261Y-116D01*
X1266683Y487D01*
X1263015Y21289D01*
X1263907Y22560D01*
X1269595Y23563D01*
X1270866Y22671D01*
X1272926Y10983D01*
X1274910Y8999D01*
X1292040D01*
X1292514Y9473D01*
X1292972D01*
G01X1029752Y7505D02*
X1030210D01*
X1030730Y8025D01*
X1045255D01*
X1046781Y6746D01*
X1048291Y-1823D01*
X1049585Y-2728D01*
X1055233Y-1733D01*
X1056142Y-438D01*
X1052400Y20777D01*
X1052822Y21378D01*
X1057638Y22228D01*
X1058239Y21806D01*
X1062388Y-1718D01*
X1063682Y-2624D01*
X1069330Y-1629D01*
X1070239Y-334D01*
X1066535Y20664D01*
X1066957Y21265D01*
X1071773Y22115D01*
X1072374Y21693D01*
X1076485Y-1614D01*
X1077779Y-2520D01*
X1083427Y-1525D01*
X1084336Y-230D01*
X1080673Y20538D01*
X1081095Y21140D01*
X1085911Y21990D01*
X1086511Y21568D01*
X1090582Y-1510D01*
X1091876Y-2416D01*
X1097524Y-1421D01*
X1098433Y-126D01*
X1094741Y20805D01*
X1095163Y21406D01*
X1099979Y22256D01*
X1100580Y21834D01*
X1104679Y-1406D01*
X1105973Y-2312D01*
X1111621Y-1317D01*
X1112530Y-22D01*
X1108846Y20862D01*
X1109268Y21462D01*
X1114084Y22312D01*
X1114685Y21891D01*
X1118805Y-1470D01*
X1120099Y-2378D01*
X1125748Y-1382D01*
X1126656Y-87D01*
X1122957Y20886D01*
X1123363Y21465D01*
X1128217Y22321D01*
X1128796Y21915D01*
X1132916Y-1451D01*
X1134210Y-2359D01*
X1139860Y-1363D01*
X1140766Y-67D01*
X1137068Y20907D01*
X1137474Y21486D01*
X1142328Y22342D01*
X1142907Y21936D01*
X1147097Y-1832D01*
X1148393Y-2738D01*
X1154042Y-1743D01*
X1154947Y-449D01*
X1151158Y21040D01*
X1151564Y21619D01*
X1156418Y22475D01*
X1156997Y22069D01*
X1161152Y-1499D01*
X1162448Y-2405D01*
X1168096Y-1409D01*
X1169003Y-114D01*
X1165289Y20946D01*
X1165695Y21525D01*
X1170549Y22381D01*
X1171128Y21975D01*
X1175249Y-1393D01*
X1176544Y-2299D01*
X1182192Y-1304D01*
X1183098Y-8D01*
X1179377Y21101D01*
X1179782Y21681D01*
X1184637Y22537D01*
X1185238Y22116D01*
X1189342Y-1150D01*
X1190636Y-2056D01*
X1196284Y-1061D01*
X1197193Y234D01*
X1193555Y20860D01*
X1193977Y21461D01*
X1198793Y22311D01*
X1199394Y21890D01*
X1203468Y-1214D01*
X1204763Y-2122D01*
X1210411Y-1126D01*
X1211319Y169D01*
X1207657Y20934D01*
X1208063Y21513D01*
X1212917Y22369D01*
X1213495Y21963D01*
X1217579Y-1195D01*
X1218874Y-2103D01*
X1224523Y-1107D01*
X1225429Y189D01*
X1221780Y20884D01*
X1222186Y21463D01*
X1227040Y22319D01*
X1227619Y21913D01*
X1231760Y-1576D01*
X1233056Y-2482D01*
X1238705Y-1487D01*
X1239610Y-193D01*
X1235892Y20892D01*
X1236298Y21471D01*
X1241152Y22327D01*
X1241731Y21921D01*
X1245815Y-1243D01*
X1247111Y-2149D01*
X1252759Y-1153D01*
X1253666Y142D01*
X1249989Y20989D01*
X1250395Y21568D01*
X1255249Y22424D01*
X1255828Y22018D01*
X1259911Y-1137D01*
X1261207Y-2043D01*
X1266855Y-1048D01*
X1267761Y248D01*
X1264094Y21049D01*
X1264500Y21628D01*
X1269355Y22484D01*
X1269934Y22078D01*
X1271977Y10489D01*
X1274487Y7979D01*
X1292062D01*
X1292536Y7505D01*
X1292972D01*
G01Y-30527D02*
X1290291Y-29811D01*
G01X1292972Y-32495D02*
X1290291Y-33211D01*
G01X1292972Y-12495D02*
X1290291Y-13211D01*
G01X1292972Y-10527D02*
X1290291Y-9811D01*
G01X1307677Y322996D02*
X1308867Y321806D01*
Y312103D01*
X1319517Y286400D01*
X1322482Y283435D01*
X1328196Y281068D01*
X1329321Y279943D01*
X1330570Y276928D01*
Y261621D01*
X1328983Y257790D01*
Y255612D01*
X1327633Y254262D01*
G01X1311077Y322996D02*
X1309887Y321806D01*
Y312306D01*
X1320382Y286978D01*
X1323060Y284300D01*
X1328774Y281933D01*
X1330186Y280521D01*
X1331590Y277131D01*
Y261418D01*
X1330003Y257587D01*
Y255612D01*
X1330013Y255602D01*
Y255482D01*
X1331233Y254262D01*
G01X1327633Y252162D02*
X1328923Y250872D01*
Y249590D01*
X1327505Y246164D01*
Y242276D01*
G01X1331233Y252162D02*
X1329943Y250872D01*
Y249387D01*
X1328525Y245961D01*
Y242276D01*
G01X1319618Y318073D02*
X1318428Y316883D01*
Y313876D01*
X1332758Y299546D01*
Y290200D01*
X1332876Y289612D01*
X1336154Y281697D01*
Y273132D01*
X1338700Y266985D01*
Y263856D01*
X1339990Y262566D01*
G01X1325080Y323902D02*
X1326270Y322712D01*
Y313150D01*
X1343694Y295726D01*
Y289721D01*
X1339704Y283748D01*
Y276505D01*
X1344000Y266133D01*
Y258970D01*
X1342418Y255150D01*
Y250180D01*
X1341472Y249234D01*
Y246656D01*
X1340182Y245366D01*
G01X1316218Y318073D02*
X1317408Y316883D01*
Y313453D01*
X1331738Y299123D01*
Y290099D01*
X1331882Y289377D01*
X1331873Y289366D01*
X1335134Y281494D01*
Y272929D01*
X1337680Y266782D01*
Y263856D01*
X1336390Y262566D01*
G01X1328480Y323902D02*
X1327290Y322712D01*
Y313573D01*
X1344714Y296149D01*
Y289411D01*
X1344542Y289153D01*
Y289154D01*
X1340724Y283438D01*
Y276708D01*
X1345020Y266336D01*
Y258767D01*
X1343438Y254947D01*
Y249757D01*
X1342492Y248811D01*
Y246656D01*
X1343782Y245366D01*
G01X1330101Y540049D02*
X1330796Y539354D01*
Y537321D01*
G01X1339071Y-30527D02*
X1341752Y-29811D01*
G01X1339071Y-32495D02*
X1341752Y-33211D01*
G01X1339071Y-10527D02*
X1341752Y-9811D01*
G01X1339071Y-12495D02*
X1341752Y-13211D01*
G01X1339071Y7505D02*
X1339529D01*
X1340003Y7979D01*
X1352998D01*
X1355561Y10539D01*
X1353724Y20915D01*
X1354145Y21516D01*
X1358962Y22366D01*
X1359570Y21939D01*
X1363660Y-1255D01*
X1364956Y-2161D01*
X1370604Y-1166D01*
X1371510Y130D01*
X1367766Y21366D01*
X1368188Y21968D01*
X1373004Y22817D01*
X1373604Y22396D01*
X1377757Y-1150D01*
X1379051Y-2056D01*
X1384699Y-1061D01*
X1385608Y234D01*
X1381862Y21471D01*
X1382284Y22072D01*
X1387100Y22922D01*
X1387701Y22501D01*
X1391883Y-1214D01*
X1393177Y-2122D01*
X1398826Y-1126D01*
X1399734Y169D01*
X1395970Y21510D01*
X1396376Y22089D01*
X1401230Y22945D01*
X1401809Y22539D01*
X1405994Y-1195D01*
X1407288Y-2103D01*
X1412938Y-1107D01*
X1413844Y189D01*
X1410081Y21530D01*
X1410487Y22109D01*
X1415341Y22965D01*
X1415920Y22559D01*
X1420175Y-1576D01*
X1421471Y-2482D01*
X1427120Y-1487D01*
X1428025Y-193D01*
X1424176Y21635D01*
X1424582Y22214D01*
X1429436Y23070D01*
X1430015Y22664D01*
X1434230Y-1243D01*
X1435526Y-2149D01*
X1441174Y-1153D01*
X1442081Y142D01*
X1438347Y21313D01*
X1438753Y21892D01*
X1443607Y22748D01*
X1444186Y22342D01*
X1448327Y-1137D01*
X1449622Y-2043D01*
X1455270Y-1048D01*
X1456176Y248D01*
X1452405Y21638D01*
X1452811Y22217D01*
X1457666Y23073D01*
X1458245Y22667D01*
X1460392Y10489D01*
X1462902Y7979D01*
X1484421D01*
X1484895Y7505D01*
X1485331D01*
G01X1339071Y9473D02*
X1339507D01*
X1339981Y8999D01*
X1352575D01*
X1354463Y10885D01*
X1352645Y21154D01*
X1353551Y22448D01*
X1359201Y23444D01*
X1360502Y22533D01*
X1364592Y-661D01*
X1365195Y-1083D01*
X1370010Y-234D01*
X1370432Y369D01*
X1366688Y21605D01*
X1367594Y22900D01*
X1373243Y23896D01*
X1374536Y22990D01*
X1378689Y-557D01*
X1379290Y-978D01*
X1384106Y-129D01*
X1384529Y474D01*
X1380784Y21710D01*
X1381690Y23004D01*
X1387339Y24001D01*
X1388633Y23094D01*
X1392815Y-621D01*
X1393417Y-1043D01*
X1398233Y-194D01*
X1398655Y408D01*
X1394892Y21749D01*
X1395782Y23021D01*
X1401469Y24023D01*
X1402741Y23133D01*
X1406926Y-602D01*
X1407528Y-1024D01*
X1412344Y-175D01*
X1412766Y428D01*
X1409003Y21769D01*
X1409893Y23041D01*
X1415580Y24043D01*
X1416852Y23153D01*
X1421107Y-982D01*
X1421710Y-1404D01*
X1426526Y-555D01*
X1426947Y46D01*
X1423098Y21874D01*
X1423988Y23146D01*
X1429675Y24148D01*
X1430947Y23258D01*
X1435162Y-649D01*
X1435765Y-1071D01*
X1440580Y-221D01*
X1441002Y381D01*
X1437269Y21552D01*
X1438159Y22824D01*
X1443846Y23826D01*
X1445118Y22936D01*
X1449258Y-543D01*
X1449861Y-965D01*
X1454676Y-116D01*
X1455098Y487D01*
X1451327Y21877D01*
X1452217Y23149D01*
X1452634Y23223D01*
Y23222D01*
X1457906Y24152D01*
X1459177Y23260D01*
X1461341Y10983D01*
X1463325Y8999D01*
X1484399D01*
X1484873Y9473D01*
X1485331D01*
G01X1341019Y233349D02*
Y240381D01*
X1341500Y240862D01*
Y241948D01*
X1340182Y243266D01*
G01X1346665Y233032D02*
Y234021D01*
X1348812Y240022D01*
Y247115D01*
X1349720Y249308D01*
Y249938D01*
X1351048Y251266D01*
G01X1349258Y228512D02*
X1350438Y229692D01*
X1354403Y239262D01*
X1356012Y240871D01*
Y241976D01*
X1357302Y243266D01*
G01X1345645Y233032D02*
Y234202D01*
X1346365Y236213D01*
X1346072Y236834D01*
X1346597Y238303D01*
X1347219Y238596D01*
X1347792Y240199D01*
Y247318D01*
X1348700Y249511D01*
Y250014D01*
X1347448Y251266D01*
G01X1339990Y260466D02*
X1338600Y259076D01*
Y253476D01*
X1334412Y243366D01*
Y240934D01*
X1335402Y238546D01*
X1336400Y237549D01*
X1337054Y235970D01*
Y235262D01*
X1338246Y231333D01*
X1338290Y231289D01*
Y230929D01*
G01X1336390Y260466D02*
X1337580Y259276D01*
Y253679D01*
X1333392Y243569D01*
Y240730D01*
X1334537Y237968D01*
X1335535Y236971D01*
X1336034Y235767D01*
Y235110D01*
X1337270Y231036D01*
Y230929D01*
G01X1342039Y233349D02*
Y236374D01*
X1342524Y236859D01*
Y238419D01*
X1342039Y238904D01*
Y239958D01*
X1342520Y240439D01*
Y242004D01*
X1343782Y243266D01*
G01X1348536Y229234D02*
X1349574Y230272D01*
X1350406Y232282D01*
X1350144Y232916D01*
X1350741Y234358D01*
X1351375Y234620D01*
X1351972Y236061D01*
X1351710Y236695D01*
X1352307Y238137D01*
X1352941Y238399D01*
X1353538Y239840D01*
X1354992Y241294D01*
Y241976D01*
X1353702Y243266D01*
G01X1351048Y253366D02*
X1349758Y254656D01*
Y268515D01*
X1352644Y275483D01*
Y283120D01*
X1352412Y284293D01*
X1350184Y289668D01*
Y300222D01*
X1333955Y316451D01*
Y331426D01*
X1335145Y332616D01*
G01X1357302Y245366D02*
X1356078Y246590D01*
Y267959D01*
X1363354Y285547D01*
Y295687D01*
X1340241Y318800D01*
Y321503D01*
X1341431Y322693D01*
G01X1331745Y332616D02*
X1332935Y331426D01*
Y316028D01*
X1349164Y299799D01*
Y289465D01*
X1351430Y283995D01*
X1351624Y283019D01*
Y275686D01*
X1348738Y268718D01*
Y254656D01*
X1347448Y253366D01*
G01X1353702Y245366D02*
X1355058Y246722D01*
Y268162D01*
X1362334Y285750D01*
Y295264D01*
X1339221Y318377D01*
Y321503D01*
X1338031Y322693D01*
G01X1345424Y328981D02*
X1346614Y327791D01*
Y320680D01*
X1373224Y294070D01*
Y279225D01*
X1363622Y264853D01*
X1361723Y258593D01*
Y254639D01*
X1360450Y253366D01*
G01X1333143Y540049D02*
Y540469D01*
X1330965Y542647D01*
X1330873D01*
G01X1340420Y538422D02*
X1339220Y539622D01*
X1337860D01*
X1335559Y537321D01*
X1333946D01*
G01X1340420Y541822D02*
X1339240Y540642D01*
X1337840D01*
X1335835Y542647D01*
X1334023D01*
G01X1363198Y229113D02*
X1361375D01*
X1360709Y228447D01*
X1359702Y228030D01*
X1357205Y225533D01*
G01X1360652Y231659D02*
Y229833D01*
X1360131Y229312D01*
X1359122Y228894D01*
X1356483Y226255D01*
G01X1362136Y233143D02*
X1363962D01*
X1367500Y236681D01*
Y239572D01*
X1368300Y241504D01*
Y246788D01*
X1368060Y247367D01*
Y255017D01*
X1371095Y262345D01*
X1370830Y262986D01*
X1371404Y264372D01*
X1372045Y264638D01*
X1373380Y267860D01*
Y268867D01*
X1375433Y273823D01*
X1378274Y278071D01*
Y296163D01*
X1352990Y321447D01*
Y324142D01*
X1352510Y324622D01*
Y326122D01*
X1352990Y326602D01*
Y336653D01*
X1351800Y337843D01*
G01X1353751Y226996D02*
X1355597Y228842D01*
X1359241Y237640D01*
X1359832Y238231D01*
X1362022Y239139D01*
X1363212Y240329D01*
Y247673D01*
X1362691Y248931D01*
Y249933D01*
X1364024Y251266D01*
X1364050D01*
G01X1375626Y256280D02*
X1374336Y254990D01*
X1373529D01*
X1372600Y254061D01*
Y248509D01*
X1373300Y246819D01*
Y242026D01*
X1372144Y236214D01*
Y233503D01*
X1359581Y220940D01*
X1358181D01*
G01X1353029Y227718D02*
X1354733Y229422D01*
X1358376Y238218D01*
X1359254Y239096D01*
X1361444Y240004D01*
X1362192Y240752D01*
Y247470D01*
X1361671Y248728D01*
Y250045D01*
X1360450Y251266D01*
G01X1375626Y252680D02*
X1374336Y253970D01*
X1373952D01*
X1373620Y253638D01*
Y248712D01*
X1374320Y247022D01*
Y241925D01*
X1373164Y236113D01*
Y233080D01*
X1360004Y219920D01*
X1358181D01*
G01X1348824Y328981D02*
X1347634Y327791D01*
Y321103D01*
X1374244Y294493D01*
Y278915D01*
X1364555Y264412D01*
X1362743Y258441D01*
Y254662D01*
X1364039Y253366D01*
X1364050D01*
G01X1355200Y337843D02*
X1354010Y336653D01*
Y321870D01*
X1379294Y296586D01*
Y277761D01*
X1376338Y273339D01*
X1374400Y268663D01*
Y267657D01*
X1369080Y254814D01*
Y247571D01*
X1369320Y246992D01*
Y241301D01*
X1368520Y239369D01*
Y236258D01*
X1364682Y232420D01*
Y230597D01*
G01X1358371Y332275D02*
X1359561Y331085D01*
Y321439D01*
X1382914Y298086D01*
X1384490Y294281D01*
X1384224Y293640D01*
X1384798Y292254D01*
X1385440Y291988D01*
X1386013Y290603D01*
X1385748Y289962D01*
X1386322Y288576D01*
X1386963Y288310D01*
X1387537Y286925D01*
X1387271Y286284D01*
X1387845Y284898D01*
X1388487Y284632D01*
X1389060Y283247D01*
X1388795Y282607D01*
X1389369Y281220D01*
X1390010Y280955D01*
X1390700Y279288D01*
Y267362D01*
X1384000Y260662D01*
X1382031Y255909D01*
X1381112Y254990D01*
X1379016D01*
X1377726Y256280D01*
G01X1361771Y332275D02*
X1360581Y331085D01*
Y321862D01*
X1383779Y298664D01*
X1391720Y279491D01*
Y266939D01*
X1384865Y260084D01*
X1382896Y255331D01*
X1381535Y253970D01*
X1379016D01*
X1377726Y252680D01*
G01X1376991Y176430D02*
X1375801Y177620D01*
Y178356D01*
X1377477Y180032D01*
X1441180D01*
X1446720Y185572D01*
X1462646D01*
X1469925Y180707D01*
X1489261Y134022D01*
X1527161Y96122D01*
X1531523D01*
X1532870Y97469D01*
Y98972D01*
X1534060Y100162D01*
G01X1373591Y176430D02*
X1374781Y177620D01*
Y178779D01*
X1377054Y181052D01*
X1440757D01*
X1446297Y186592D01*
X1462956D01*
X1470750Y181384D01*
X1486680Y142920D01*
X1490126Y134600D01*
X1522740Y101986D01*
X1523419D01*
X1524494Y100911D01*
Y100232D01*
X1527584Y97142D01*
X1531100D01*
X1531850Y97892D01*
Y98972D01*
X1530660Y100162D01*
G01X1471460Y633402D02*
X1470270Y634592D01*
Y637510D01*
X1474923Y648742D01*
X1485818Y666918D01*
X1488211Y674808D01*
X1495075Y686259D01*
X1535756Y726941D01*
X1548285Y757185D01*
Y757186D01*
X1568730Y777631D01*
Y903389D01*
X1567360Y906696D01*
X1539874Y934182D01*
X1526599Y939679D01*
X1526519Y939759D01*
X1518777D01*
G01X1468060Y633402D02*
X1469250Y634592D01*
Y637713D01*
X1474009Y649202D01*
X1484878Y667334D01*
X1487271Y675224D01*
X1494264Y686892D01*
X1534891Y727519D01*
X1547420Y757764D01*
X1567710Y778054D01*
Y903186D01*
X1566495Y906118D01*
X1564513Y908100D01*
X1563820D01*
X1562758Y909162D01*
Y909855D01*
X1560957Y911656D01*
X1560278D01*
X1559188Y912746D01*
Y913425D01*
X1558100Y914513D01*
X1557421D01*
X1556331Y915603D01*
Y916282D01*
X1555095Y917518D01*
X1554416D01*
X1553326Y918608D01*
Y919287D01*
X1551660Y920953D01*
X1550981D01*
X1549891Y922043D01*
Y922722D01*
X1548075Y924538D01*
X1547396D01*
X1546306Y925628D01*
Y926307D01*
X1545010Y927603D01*
X1544331D01*
X1543241Y928693D01*
Y929372D01*
X1542153Y930460D01*
X1541474D01*
X1540384Y931550D01*
Y932229D01*
X1539296Y933317D01*
X1526202Y938739D01*
X1518777D01*
G01X1485331Y-30527D02*
X1482650Y-29811D01*
G01X1485331Y-32495D02*
X1482650Y-33211D01*
G01X1485331Y-10527D02*
X1482650Y-9811D01*
G01X1485331Y-12495D02*
X1482650Y-13211D01*
G01X1931395Y602868D02*
X1927425D01*
X1926902Y603391D01*
Y1194401D01*
X1927569Y1195068D01*
X1931395D01*
G01X1921395D02*
X1925205D01*
X1925882Y1194391D01*
Y603385D01*
X1925365Y602868D01*
X1921395D01*
G54D104*
X1281389Y294768D03*
Y289368D03*
G54D113*
X1881720Y988279D03*
X1886720Y1001463D03*
X1876720D03*
X1875836Y1303980D03*
X1885836D03*
X1880836Y1317164D03*
X1881211Y1350983D03*
X1886211Y1364167D03*
X1876211D03*
X1876165Y1669023D03*
X1886165D03*
X1881165Y1682207D03*
X1902608Y988322D03*
X1897608Y1001506D03*
X1898086Y1305044D03*
X1903086Y1318228D03*
X1902682Y1351295D03*
X1897682Y1364479D03*
X1902402Y1683256D03*
X1897402Y1670072D03*
X1907608Y1001506D03*
X1908086Y1305044D03*
X1907682Y1364479D03*
X1907402Y1670072D03*
X1930200Y1349548D03*
X1935200Y1362732D03*
X1925200D03*
X1929695Y1683220D03*
X1924695Y1670036D03*
X1934695D03*
X1951178Y1349597D03*
X1946178Y1362781D03*
X1950484Y1683497D03*
X1945484Y1670313D03*
X1967697Y1362790D03*
X1956178Y1362781D03*
X1966555Y1669946D03*
X1955484Y1670313D03*
X1972697Y1349606D03*
X1977697Y1362790D03*
X1976555Y1669946D03*
X1971555Y1683130D03*
X1993618Y1349897D03*
X1988618Y1363081D03*
X1998618D03*
X1998147Y1669691D03*
X1988147D03*
X1993147Y1682875D03*
G54D11*
G01X159474Y1320753D02*
X163176D01*
G01X155772D02*
X159474D01*
G01Y1317051D02*
Y1320753D01*
G01Y1328627D02*
Y1332329D01*
G01X155772Y1328627D02*
X159474D01*
G01D02*
X163176D01*
G01X146390Y1504240D02*
X146700D01*
X148250Y1502690D01*
X410072D01*
X449846Y1542464D01*
X460547D01*
X463207Y1545124D01*
Y1547543D01*
G01X230359Y461683D02*
X216843D01*
X212951Y465575D01*
X201884D01*
X191596Y455287D01*
Y435108D01*
X187371Y430883D01*
G01X183847Y1320778D02*
X187549D01*
G01X180145D02*
X183847D01*
G01Y1317076D02*
Y1320778D01*
G01Y1328652D02*
Y1332354D01*
G01X180145Y1328652D02*
X183847D01*
G01D02*
X187549D01*
G01X208247Y1320778D02*
X211949D01*
G01X204545D02*
X208247D01*
G01Y1317076D02*
Y1320778D01*
G01Y1328652D02*
Y1332354D01*
G01X204545Y1328652D02*
X208247D01*
G01D02*
X211949D01*
G01X354145Y290591D02*
Y285820D01*
X351030Y282705D01*
X261738D01*
X231472Y312971D01*
Y354792D01*
X226800Y359464D01*
G01X271587Y579874D02*
X275289Y583576D01*
G01X271587Y587278D02*
X275289Y583576D01*
G01X271587Y604033D02*
X275289Y607735D01*
G01X271587Y611437D02*
X275289Y607735D01*
G01X271680Y635640D02*
X272319Y634859D01*
X275289Y631889D01*
G01X271587Y628187D02*
X275289Y631889D01*
G01X271587Y652341D02*
X275289Y656043D01*
G01X266550Y672558D02*
X270252Y676260D01*
G01D02*
X273954Y672558D01*
G01X271587Y659745D02*
X275289Y656043D01*
G01X270252Y676260D02*
X273954Y679962D01*
G01X270252Y676260D02*
X268643Y681242D01*
G01X266550Y696712D02*
X270252Y700414D01*
G01Y696712D02*
Y700414D01*
G01D02*
X266550D01*
G01X275289Y583576D02*
X278991Y587278D01*
G01X275289Y583576D02*
X278991Y579874D01*
G01X275289Y607735D02*
X278991Y611437D01*
G01X275289Y607735D02*
X278991Y604033D01*
G01X275289Y631889D02*
X278991Y635591D01*
G01X275289Y631889D02*
X278991Y628187D01*
G01X275289Y656043D02*
X278991Y659745D01*
G01X275289Y656043D02*
X278991Y652341D01*
G01X305612Y622530D02*
X307380Y620762D01*
Y619662D01*
X311742Y615300D01*
Y603342D01*
X335659Y579425D01*
Y422462D01*
X342559Y415562D01*
X401820D01*
X417279Y400103D01*
X469459D01*
X475900Y393662D01*
Y385962D01*
X473100Y383162D01*
Y369162D01*
X474900Y367362D01*
X479015D01*
X480515Y368862D01*
X490720D01*
G01X303723Y1353316D02*
Y1353144D01*
X304395Y1352472D01*
X306207D01*
G01X335679Y1330518D02*
X336523Y1329674D01*
X338300D01*
G01X367694Y1317092D02*
X367807D01*
X368551Y1316348D01*
X372428D01*
G01X384195Y1239083D02*
X387897Y1242785D01*
G01D02*
X391599Y1246487D01*
G01X384195D02*
X387897Y1242785D01*
G01D02*
X391599Y1239083D01*
G01X379622Y1350844D02*
X383224Y1354446D01*
G01D02*
X386826Y1358048D01*
G01X379622D02*
X383224Y1354446D01*
G01D02*
X386826Y1350844D01*
G01X399935Y1317092D02*
X400314Y1316713D01*
X405156D01*
G01X408595Y1239083D02*
X412297Y1242785D01*
G01D02*
X415999Y1246487D01*
G01X408595D02*
X412297Y1242785D01*
G01D02*
X415999Y1239083D01*
G01X409388Y1350844D02*
X412990Y1354446D01*
G01D02*
X416592Y1358048D01*
G01X409388D02*
X412990Y1354446D01*
G01D02*
X416592Y1350844D01*
G01X432917Y1239083D02*
X436619Y1242785D01*
G01D02*
X440321Y1246487D01*
G01X432917D02*
X436619Y1242785D01*
G01D02*
X440321Y1239083D01*
G01X432063Y1317092D02*
X433001Y1316154D01*
X436701D01*
G01X439724Y1350844D02*
X443326Y1354446D01*
G01D02*
X446928Y1358048D01*
G01X439724D02*
X443326Y1354446D01*
G01D02*
X446928Y1350844D01*
G01X457317Y1239083D02*
X461019Y1242785D01*
G01D02*
X464721Y1246487D01*
G01X457317D02*
X461019Y1242785D01*
G01D02*
X464721Y1239083D01*
G01X464191Y1317092D02*
X465167Y1316116D01*
X468790D01*
G01X469098Y1350360D02*
X472700Y1353962D01*
G01X469098Y1357564D02*
X472700Y1353962D01*
G01X454998Y1376060D02*
X458600Y1379662D01*
G01D02*
X462202Y1383264D01*
G01X454998D02*
X458600Y1379662D01*
G01D02*
X462202Y1376060D01*
G01X475508Y359266D02*
X485299Y349475D01*
X547532D01*
X553251Y355194D01*
X609411D01*
X624216Y369999D01*
X675500D01*
X678053Y372552D01*
X691780D01*
X694333Y369999D01*
X741937D01*
X759820Y387882D01*
X783470D01*
X793800Y398212D01*
X795520D01*
G01X506720Y368862D02*
X506530Y368672D01*
X501040D01*
X495943Y373769D01*
X479410D01*
X476585Y370944D01*
Y370727D01*
G01X481717Y1239083D02*
X485419Y1242785D01*
G01D02*
X489121Y1246487D01*
G01X481717D02*
X485419Y1242785D01*
G01D02*
X489121Y1239083D01*
G01X472700Y1353962D02*
X476302Y1357564D01*
G01X472700Y1353962D02*
X476302Y1350360D01*
G01X523670Y368892D02*
Y367252D01*
X521048Y364630D01*
X494952D01*
X490720Y368862D01*
G01X496319Y1330493D02*
X496344D01*
X497314Y1329523D01*
X501013D01*
G01X505720Y398362D02*
X506720Y397362D01*
Y368862D01*
G01X521720Y398362D02*
Y370842D01*
X523670Y368892D01*
G01X528447Y1353316D02*
X529291Y1352472D01*
X533423D01*
G01X526478Y1439952D02*
X529225Y1437205D01*
G01X523731D02*
X526478Y1439952D01*
G01X523731Y1442699D02*
X526478Y1439952D01*
G01D02*
X529225Y1442699D01*
G01X584795Y233362D02*
X585081Y233076D01*
Y225733D01*
X580710Y221362D01*
X579245D01*
G01X673093Y1316778D02*
Y1320778D01*
G01D02*
X677093D01*
G01X669093D02*
X673093D01*
G01Y1328652D02*
Y1332354D01*
G01X669391Y1328652D02*
X673093D01*
G01D02*
X676795D01*
G01X693466Y1320803D02*
X697466D01*
G01X693764Y1328677D02*
X697466D01*
G01X682160Y1548040D02*
Y1546190D01*
X745612Y1482738D01*
X1038982D01*
X1066462Y1510218D01*
Y1520088D01*
G01X697466Y1316803D02*
Y1320803D01*
G01D02*
X701466D01*
G01X697466Y1328677D02*
Y1332379D01*
G01Y1328677D02*
X701168D01*
G01X721866Y1316803D02*
Y1320803D01*
G01D02*
X725866D01*
G01X717866D02*
X721866D01*
G01Y1328677D02*
Y1332379D01*
G01X718164Y1328677D02*
X721866D01*
G01D02*
X725568D01*
G01X890422Y333879D02*
X880992D01*
X869625Y322512D01*
X786800D01*
X782350Y318062D01*
X772450D01*
X768000Y322512D01*
X754161D01*
X744247Y312598D01*
G01X827114Y115223D02*
X820042Y122295D01*
X808459D01*
X799712Y113548D01*
X787186D01*
X770722Y97084D01*
Y84044D01*
X767004Y80326D01*
X762285D01*
X759610Y83001D01*
Y89296D01*
X760627Y90313D01*
Y95923D01*
X760127Y96423D01*
X757693D01*
G01Y100653D02*
Y131391D01*
X751220Y137864D01*
G01X757693Y96423D02*
Y100653D01*
G01X821720Y523082D02*
X856275D01*
X857195Y522162D01*
G01X821720Y523082D02*
X818058D01*
X817350Y523790D01*
Y529470D01*
X819050Y531170D01*
X833290D01*
X834674Y529786D01*
X840990D01*
G01X848709Y156752D02*
X859790D01*
X861896Y158858D01*
X877396D01*
X881396Y162858D01*
X910631D01*
X915762Y167989D01*
X919468D01*
X931583Y180104D01*
X969939D01*
X984382Y165661D01*
X996000D01*
X999208Y168869D01*
X1032288D01*
X1040331Y176912D01*
X1081570D01*
X1093067Y165415D01*
Y158668D01*
X1134898Y116837D01*
Y105292D01*
X1139055Y101135D01*
X1140242D01*
G01X1097098Y255660D02*
X1100800Y259362D01*
G01D02*
X1104502Y263064D01*
G01X1097098D02*
X1100800Y259362D01*
G01D02*
X1104502Y255660D01*
G01X1096998Y279960D02*
X1100700Y283662D01*
G01D02*
X1104402Y287364D01*
G01X1096998D02*
X1100700Y283662D01*
G01D02*
X1104402Y279960D01*
G01X1131100Y1353386D02*
Y1357088D01*
G01D02*
X1134802D01*
G01X1127398D02*
X1131100D01*
G01Y1364962D02*
Y1368664D01*
G01X1127398Y1364962D02*
X1131100D01*
G01D02*
X1134802D01*
G01X1151798Y1357088D02*
X1155500D01*
G01X1151798Y1364962D02*
X1155500D01*
G01Y1353386D02*
Y1357088D01*
G01D02*
X1159202D01*
G01X1155500Y1364962D02*
Y1368664D01*
G01Y1364962D02*
X1159202D01*
G01X1179900Y1353386D02*
Y1357088D01*
G01D02*
X1183602D01*
G01X1176198D02*
X1179900D01*
G01Y1364962D02*
Y1368664D01*
G01X1176198Y1364962D02*
X1179900D01*
G01D02*
X1183602D01*
G01X1276820Y58142D02*
X1274886Y60076D01*
X1240465D01*
X1238943Y61598D01*
X1227010D01*
X1225595Y60183D01*
X1189393D01*
G01X1258883Y280558D02*
X1256707Y282734D01*
X1256702Y282735D01*
X1202842D01*
X1187013Y266906D01*
Y238972D01*
G01X1239045Y224062D02*
X1237479Y225628D01*
X1220897D01*
X1212352Y217083D01*
Y213155D01*
X1203200Y204003D01*
Y202514D01*
G01X1436232Y344176D02*
X1399507Y380901D01*
X1300571D01*
X1299265Y379595D01*
X1243589D01*
G01X1358907Y681262D02*
Y687995D01*
X1371527Y700615D01*
X1391167D01*
X1408417Y717865D01*
X1426522D01*
G01X1360336Y1239083D02*
X1364038Y1242785D01*
G01D02*
X1367740Y1246487D01*
G01X1360336D02*
X1364038Y1242785D01*
G01D02*
X1367740Y1239083D01*
G01X1355763Y1350344D02*
X1359365Y1353946D01*
G01D02*
X1362967Y1357548D01*
G01X1355763D02*
X1359365Y1353946D01*
G01D02*
X1362967Y1350344D01*
G01X1384736Y1239083D02*
X1388438Y1242785D01*
G01D02*
X1392140Y1246487D01*
G01X1384736D02*
X1388438Y1242785D01*
G01D02*
X1392140Y1239083D01*
G01X1385529Y1350344D02*
X1389131Y1353946D01*
G01D02*
X1392733Y1357548D01*
G01X1385529D02*
X1389131Y1353946D01*
G01D02*
X1392733Y1350344D01*
G01X1409058Y1239083D02*
X1412760Y1242785D01*
G01D02*
X1416462Y1246487D01*
G01X1409058D02*
X1412760Y1242785D01*
G01D02*
X1416462Y1239083D01*
G01X1440272Y712575D02*
Y711490D01*
X1437787Y709005D01*
X1430147D01*
X1426997Y712155D01*
Y717390D01*
X1426522Y717865D01*
G01X1415865Y1350344D02*
X1419467Y1353946D01*
G01D02*
X1423069Y1357548D01*
G01X1415865D02*
X1419467Y1353946D01*
G01D02*
X1423069Y1350344D01*
G01X1433458Y1239083D02*
X1437160Y1242785D01*
G01D02*
X1440862Y1246487D01*
G01X1433458D02*
X1437160Y1242785D01*
G01D02*
X1440862Y1239083D01*
G01X1430598Y1375760D02*
X1434200Y1379362D01*
G01D02*
X1437802Y1382964D01*
G01X1430598D02*
X1434200Y1379362D01*
G01D02*
X1437802Y1375760D01*
G01X1457858Y1239083D02*
X1461560Y1242785D01*
G01D02*
X1465262Y1246487D01*
G01X1457858D02*
X1461560Y1242785D01*
G01D02*
X1465262Y1239083D01*
G01X1445631Y1350344D02*
X1449233Y1353946D01*
G01D02*
X1452835Y1357548D01*
G01X1445631D02*
X1449233Y1353946D01*
G01D02*
X1452835Y1350344D01*
G01X1640526Y203614D02*
X1643080Y206168D01*
Y241246D01*
X1626619Y257707D01*
X1612594D01*
X1534861Y335440D01*
Y347183D01*
X1526959Y355085D01*
X1481015D01*
X1476600Y359500D01*
Y381052D01*
X1485600Y390052D01*
Y413162D01*
X1483900Y414862D01*
Y418362D01*
X1484900Y419362D01*
Y427482D01*
X1484805Y427577D01*
G01X1509539Y308467D02*
Y307065D01*
X1510425Y306179D01*
Y300124D01*
X1508558Y298257D01*
Y291175D01*
G01X1502956Y1435630D02*
Y1439530D01*
G01D02*
X1506856D01*
G01X1499056D02*
X1502956D01*
G01X1640526Y203614D02*
X1615506D01*
X1607443Y195551D01*
X1602669D01*
X1599640Y192522D01*
X1556890D01*
X1551230Y198182D01*
Y213202D01*
X1553491Y215463D01*
Y220661D01*
X1550500Y223652D01*
Y233981D01*
X1522786Y261695D01*
Y262558D01*
G01X1554753Y628860D02*
X1545682D01*
X1540377Y634165D01*
G01X1553312Y636815D02*
X1556454D01*
X1557869Y635400D01*
Y629965D01*
X1556764Y628860D01*
X1554753D01*
G01X1564768Y708159D02*
X1560710Y704101D01*
Y677374D01*
X1553312Y669976D01*
Y636815D01*
G01X1573298Y596060D02*
X1577000Y599762D01*
G01X1573298Y603464D02*
X1577000Y599762D01*
G01X1573298Y624262D02*
X1577000D01*
G01X1573298Y645060D02*
X1577000Y648762D01*
G01X1573298Y652464D02*
X1577000Y648762D01*
G01X1573298Y669460D02*
X1577000Y673162D01*
G01X1573298Y676864D02*
X1577000Y673162D01*
G01X1573298Y693960D02*
X1577000Y697662D01*
G01X1573298Y701364D02*
X1577000Y697662D01*
G01X1573298Y718460D02*
X1577000Y722162D01*
G01D02*
X1573298Y725864D01*
G01X1577000Y599762D02*
X1580702Y603464D01*
G01X1577000Y599762D02*
X1580702Y596060D01*
G01X1577000Y624262D02*
Y627964D01*
G01Y624262D02*
X1580702D01*
G01X1577000Y648762D02*
X1580702Y652464D01*
G01X1577000Y648762D02*
X1580702Y645060D01*
G01X1577000Y673162D02*
X1580702Y676864D01*
G01X1577000Y673162D02*
X1580702Y669460D01*
G01X1577000Y697662D02*
X1580702Y701364D01*
G01X1577000Y697662D02*
X1580702Y693960D01*
G01X1577000Y722162D02*
X1580702Y725864D01*
G01X1577000Y722162D02*
X1580702Y718460D01*
G01X1717987Y569705D02*
X1682244D01*
X1679471Y566932D01*
X1638601D01*
X1631671Y560002D01*
X1602980D01*
G01X1724431Y1336311D02*
X1618408D01*
X1608010Y1346709D01*
Y1424219D01*
X1609867Y1426076D01*
X1614927D01*
G01X1717619Y165909D02*
X1708041D01*
X1702906Y171044D01*
Y174270D01*
X1693008Y184168D01*
X1659972D01*
X1640526Y203614D01*
G01X1662447Y480619D02*
X1639200Y503866D01*
Y552361D01*
X1650809Y563970D01*
X1672808D01*
X1682724Y559862D01*
X1735239D01*
X1779097Y603720D01*
Y671014D01*
X1791888Y683805D01*
G01X1634259Y1354374D02*
X1637961D01*
G01X1630557D02*
X1634259D01*
G01Y1350672D02*
Y1354374D01*
G01Y1362248D02*
Y1365950D01*
G01X1630557Y1362248D02*
X1634259D01*
G01D02*
X1637961D01*
G01X1653380Y517421D02*
Y512711D01*
X1659629Y506462D01*
X1689429D01*
X1691129Y504762D01*
Y501697D01*
G01X1654930Y1354399D02*
X1658632D01*
G01X1654930Y1362273D02*
X1658632D01*
G01Y1354399D02*
X1662334D01*
G01X1658632Y1350697D02*
Y1354399D01*
G01Y1362273D02*
Y1365975D01*
G01Y1362273D02*
X1662334D01*
G01X1683032Y1354399D02*
X1686734D01*
G01X1679330D02*
X1683032D01*
G01Y1350697D02*
Y1354399D01*
G01Y1362273D02*
Y1365975D01*
G01X1679330Y1362273D02*
X1683032D01*
G01D02*
X1686734D01*
G01X1769790Y194789D02*
X1772537Y192042D01*
G01X1767043Y197536D02*
X1769790Y194789D01*
G01D02*
X1772537Y197536D01*
G01X1767043Y192042D02*
X1769790Y194789D01*
G01Y204632D02*
X1773392D01*
G01X1766188D02*
X1769790D01*
G01D02*
Y208234D01*
G01X1799350Y194789D02*
X1802097Y192042D01*
G01X1796603Y197536D02*
X1799350Y194789D01*
G01D02*
X1802097Y197536D01*
G01X1796603Y192042D02*
X1799350Y194789D01*
G01Y204632D02*
X1802952D01*
G01X1795748D02*
X1799350D01*
G01D02*
Y208234D01*
G01X1795561Y1524729D02*
Y1516791D01*
X1801915Y1510437D01*
X1809747D01*
X3010Y63308D03*
Y123308D03*
Y163308D03*
Y183308D03*
Y203308D03*
Y223308D03*
Y243308D03*
Y263308D03*
Y283308D03*
Y303308D03*
X10884Y321693D03*
Y341693D03*
Y361693D03*
Y381693D03*
Y401693D03*
Y421693D03*
Y441693D03*
Y461693D03*
Y481693D03*
Y501693D03*
Y521693D03*
Y661693D03*
Y681693D03*
Y701693D03*
Y721693D03*
Y741693D03*
Y781693D03*
Y801693D03*
Y821693D03*
Y841693D03*
Y861693D03*
Y881693D03*
Y901693D03*
Y921693D03*
Y941693D03*
Y961693D03*
Y981693D03*
Y1001693D03*
Y1021693D03*
Y1041693D03*
Y1061693D03*
Y1081693D03*
Y1101693D03*
Y1121693D03*
Y1141693D03*
Y1161693D03*
Y1181693D03*
Y1201693D03*
Y1221693D03*
Y1241693D03*
Y1401693D03*
Y1421693D03*
Y1441693D03*
Y1461693D03*
Y1481693D03*
Y1501693D03*
Y1521693D03*
Y1541693D03*
Y1561693D03*
Y1581693D03*
X17371Y49388D03*
X26054Y195148D03*
X25752Y203274D03*
X24754Y220220D03*
X24814Y236472D03*
X22223Y388057D03*
X29509Y398132D03*
X16420Y420662D03*
X26615Y670036D03*
X26500Y672862D03*
Y675862D03*
X24700Y765600D03*
X27300Y764200D03*
X27520Y1245162D03*
X20188Y1599396D03*
X28601Y1617541D03*
Y1637541D03*
Y1657541D03*
Y1677541D03*
X37371Y49388D03*
X30795Y213358D03*
X35600Y227380D03*
X30795Y227366D03*
X41492Y290637D03*
X36000Y295952D03*
X33105Y304972D03*
X42809Y360862D03*
X35740Y363337D03*
X39410Y384582D03*
X39226Y395346D03*
X33020Y382822D03*
X43020Y382942D03*
X41933Y395652D03*
X36524Y398013D03*
X45182Y426310D03*
X45960Y428806D03*
X30680Y438142D03*
X45034Y449106D03*
X45812Y451602D03*
X38220Y589862D03*
Y592862D03*
Y595862D03*
X33020Y595232D03*
X32720Y598402D03*
X34790Y666595D03*
X31390D03*
X38470Y688122D03*
Y683122D03*
Y680622D03*
Y685622D03*
Y693122D03*
Y690622D03*
Y695622D03*
X34899Y711400D03*
X45700Y724100D03*
X45800Y726874D03*
X43841Y1248688D03*
X44833Y1659909D03*
Y1656759D03*
X54593Y19183D03*
X58379Y69340D03*
X60379Y66844D03*
Y71836D03*
X60692Y87118D03*
X62731Y305426D03*
X46834Y360862D03*
X55190D03*
X59322Y360702D03*
X51114Y360862D03*
X61340Y384362D03*
X61250Y396142D03*
X49250Y396332D03*
X49400Y384392D03*
X47618Y413113D03*
X62833Y410047D03*
X53406Y402862D03*
X47619Y421155D03*
X62808Y418425D03*
X50138Y426310D03*
X60393D03*
X49360Y428806D03*
X61171D03*
X47619Y418655D03*
X47618Y415613D03*
X54762Y444993D03*
X53800Y435451D03*
X49990Y449106D03*
X49212Y451602D03*
X48400Y586000D03*
X59500Y738700D03*
X58658Y754145D03*
X55177Y1322328D03*
X55277Y1326068D03*
X56799Y1520094D03*
Y1524094D03*
Y1528094D03*
Y1532094D03*
Y1536094D03*
Y1544094D03*
Y1548094D03*
Y1552094D03*
Y1540094D03*
Y1556094D03*
Y1560094D03*
X54333Y1604359D03*
X59833D03*
X54333Y1613359D03*
X50333D03*
X46994Y1663165D03*
X50900Y1677775D03*
X57833Y1671809D03*
X69058Y3010D03*
X79047Y23978D03*
X74091D03*
X72091Y25974D03*
X73020Y37106D03*
Y28406D03*
X65937Y28403D03*
X73020Y48720D03*
Y40020D03*
X65937Y48720D03*
X67335Y69340D03*
X65335Y66844D03*
Y71836D03*
X65648Y87118D03*
X71379Y72844D03*
Y77836D03*
X76335Y72844D03*
Y77836D03*
X78335Y75340D03*
X69379D03*
X77165Y278798D03*
Y295798D03*
Y286262D03*
Y303262D03*
X63429Y360702D03*
X67681D03*
X77220Y379022D03*
Y381522D03*
X68020Y395222D03*
X65349Y426310D03*
X75516Y420319D03*
Y424319D03*
X64571Y428806D03*
X75516Y436519D03*
X68365Y443677D03*
X64150Y434972D03*
X63540Y438802D03*
X72610Y441262D03*
Y444762D03*
X77000Y485362D03*
X74550Y487812D03*
X74340Y663422D03*
X76365Y699244D03*
X78080Y701832D03*
X72315Y717414D03*
X64325Y715674D03*
X63930Y739300D03*
X73759Y754726D03*
X73865Y763164D03*
X68315Y765664D03*
X73759Y759246D03*
X72485Y1304152D03*
X75485D03*
X78485D03*
X72485Y1307152D03*
X75485D03*
X69485Y1304152D03*
Y1307152D03*
X75485Y1316152D03*
X72485Y1313152D03*
Y1310152D03*
X75485Y1313152D03*
Y1310152D03*
X69485D03*
X69809Y1333918D03*
Y1331418D03*
Y1336418D03*
X72809Y1333918D03*
Y1331418D03*
Y1336418D03*
X75809Y1333918D03*
Y1331418D03*
Y1336418D03*
X72909Y1339938D03*
X79009Y1340238D03*
X75909Y1339938D03*
X73027Y1347925D03*
X73059Y1345138D03*
X72987Y1342535D03*
X75909Y1342438D03*
X79009Y1342738D03*
Y1345238D03*
X78977Y1348025D03*
X75859Y1348138D03*
Y1345138D03*
X75564Y1509952D03*
X78120Y1512936D03*
Y1521336D03*
X76680Y1530482D03*
X72774Y1549669D03*
Y1546519D03*
X75922Y1564874D03*
Y1556474D03*
X73429Y1570008D03*
X78415D03*
X66906Y1598324D03*
X77040Y1601102D03*
X64410Y1599102D03*
X66906Y1603280D03*
X65120Y1609909D03*
X65520Y1615972D03*
X64410Y1602502D03*
X77833Y1678902D03*
X73833Y1674252D03*
X69833Y1678582D03*
X73832Y1689362D03*
X77833Y1689162D03*
X89058Y3010D03*
X81196Y17042D03*
Y22034D03*
X86152Y17042D03*
Y22034D03*
X95369Y17042D03*
Y22034D03*
X79196Y19538D03*
X88152D03*
X93369D03*
X88264Y23978D03*
X93220D03*
X86264Y25974D03*
X95220D03*
X81047D03*
X94279Y37106D03*
Y28406D03*
X87193Y37106D03*
Y28406D03*
X80106Y37106D03*
Y28406D03*
X94279Y48720D03*
Y40020D03*
X87193Y48720D03*
Y40020D03*
X80106Y48720D03*
Y40020D03*
X80379Y69340D03*
X89335D03*
X82379Y66844D03*
Y71836D03*
X87335Y66844D03*
Y71836D03*
X91379Y75340D03*
X93379Y72844D03*
Y77836D03*
X90700Y282762D03*
Y300262D03*
X87520Y395865D03*
Y391391D03*
Y382219D03*
X85826Y424319D03*
Y428319D03*
X83320Y445212D03*
X82661Y449604D03*
X94439Y450081D03*
X81505Y447377D03*
X79400Y482862D03*
X89859Y628246D03*
X86459D03*
X80460Y655672D03*
X83100Y649762D03*
X82961Y657111D03*
X87565Y670441D03*
X83250Y665428D03*
X84470Y668702D03*
X86433Y688160D03*
X81285Y689804D03*
X84035Y697604D03*
X94473Y698926D03*
X79451Y699517D03*
X93547Y692260D03*
X82735Y717949D03*
X87865Y714394D03*
X85165D03*
X81225Y715854D03*
X79635Y717949D03*
X85835Y718049D03*
X85095Y722164D03*
X95849Y716358D03*
X91610Y721414D03*
X82357Y737803D03*
X84623Y741249D03*
X93295Y762019D03*
X81966Y759246D03*
X85877Y759275D03*
X93485Y1304152D03*
X87485D03*
X90485D03*
X93485Y1307152D03*
X84485Y1304152D03*
X81485D03*
X93485Y1318152D03*
Y1315652D03*
Y1310152D03*
Y1313152D03*
X94209Y1337738D03*
X81809Y1340238D03*
X84809D03*
X87809D03*
X90809D03*
X94209D03*
X84809Y1345238D03*
X81809Y1342738D03*
X84809D03*
X81809Y1348238D03*
Y1345238D03*
X84809Y1348238D03*
X87809D03*
Y1345238D03*
Y1342738D03*
X94209D03*
Y1348238D03*
Y1345238D03*
X90809Y1348238D03*
Y1345238D03*
Y1342738D03*
X88520Y1484482D03*
X92071Y1492888D03*
X88520Y1491482D03*
Y1487982D03*
Y1494982D03*
X80649Y1509944D03*
X84274Y1517619D03*
X93544Y1510099D03*
X88459Y1510107D03*
X90998Y1513037D03*
Y1521437D03*
X81038Y1536899D03*
X91538Y1539399D03*
X87500Y1567069D03*
X91500D03*
X84048Y1578008D03*
X90713Y1581852D03*
Y1585852D03*
Y1589852D03*
Y1593867D03*
Y1597867D03*
X81008Y1589872D03*
X90788Y1611821D03*
Y1605867D03*
Y1615821D03*
Y1601867D03*
Y1623821D03*
X84700Y1627000D03*
X90698Y1630362D03*
X90788Y1619821D03*
X90698Y1638362D03*
Y1634362D03*
Y1642362D03*
X90407Y1656672D03*
X88333Y1661334D03*
X81833Y1674526D03*
X86245Y1690362D03*
X81833Y1689162D03*
X94220Y1686622D03*
X86245Y1694362D03*
X86030Y1683092D03*
X92895Y1737108D03*
X109058Y3010D03*
X100325Y17042D03*
Y22034D03*
X109542Y17042D03*
Y22034D03*
X102325Y19538D03*
X107542D03*
X102437Y23978D03*
X107393D03*
X100437Y25974D03*
X109393D03*
X108453Y37106D03*
Y28406D03*
X101366Y37106D03*
Y28406D03*
X108453Y48720D03*
Y40020D03*
X101366Y48720D03*
Y40020D03*
X102379Y69340D03*
X111335D03*
X104379Y66844D03*
Y71836D03*
X109335Y66844D03*
Y71836D03*
X98335Y72844D03*
Y77836D03*
X100335Y75340D03*
X110937Y285495D03*
Y302854D03*
X104220Y400862D03*
X101720D03*
X102060Y493578D03*
X104875Y490980D03*
X102152Y509374D03*
X102334Y500628D03*
X102359Y497374D03*
X102384Y505374D03*
X110464D03*
X102152Y513374D03*
X111087Y520052D03*
X101983Y518100D03*
X99880Y526300D03*
X110060Y515279D03*
X105587Y520727D03*
X106110Y633732D03*
X107489Y630917D03*
X110374Y630879D03*
X108909Y654926D03*
X102909Y648926D03*
Y642926D03*
Y655102D03*
X108909Y642926D03*
X102120Y688650D03*
X102060Y692100D03*
X102420Y697262D03*
X96626Y736187D03*
X110527Y758869D03*
X108465Y1304292D03*
Y1307292D03*
X105475Y1304222D03*
Y1307222D03*
X102485Y1304152D03*
X99485D03*
X96485D03*
X102485Y1307152D03*
X99485D03*
X96485D03*
X108465Y1318292D03*
Y1310292D03*
Y1313292D03*
Y1315792D03*
X105475Y1318222D03*
Y1310222D03*
Y1313222D03*
Y1315722D03*
X99485Y1318152D03*
X96485D03*
Y1315652D03*
Y1310152D03*
Y1313152D03*
X99485Y1310152D03*
Y1313152D03*
Y1315652D03*
X102485Y1318152D03*
Y1310152D03*
Y1313152D03*
Y1315652D03*
X96809Y1340238D03*
Y1345238D03*
Y1348238D03*
Y1342738D03*
X112270Y1518907D03*
X99274Y1526019D03*
Y1529169D03*
X96570Y1546187D03*
X99716Y1567878D03*
X99750Y1559478D03*
Y1565378D03*
Y1561978D03*
X96251Y1577532D03*
X107451Y1574704D03*
X100451D03*
X104318Y1592304D03*
Y1603690D03*
X110200Y1605200D03*
X101500Y1604400D03*
X98738Y1605867D03*
X104318Y1622380D03*
X104430Y1628012D03*
X104318Y1641075D03*
X99980Y1685362D03*
Y1696052D03*
Y1687921D03*
X114498Y17042D03*
Y22034D03*
X123716Y17042D03*
Y22034D03*
X116498Y19538D03*
X121716D03*
X121567Y23978D03*
X116611D03*
X114611Y25974D03*
X123567D03*
X122626Y37106D03*
Y28406D03*
X115539Y37106D03*
Y28406D03*
X122626Y48720D03*
Y40020D03*
X115539Y48720D03*
Y40020D03*
X124379Y69340D03*
X126379Y66844D03*
Y71836D03*
X115379Y72844D03*
Y77836D03*
X120335Y72844D03*
Y77836D03*
X122335Y75340D03*
X113379D03*
X119920Y379362D03*
X125007Y392071D03*
Y388071D03*
X119457D03*
X117597Y488434D03*
X127206Y480216D03*
X125013Y491829D03*
X116171Y485041D03*
X126225Y504368D03*
X120225D03*
Y510368D03*
X112483Y510637D03*
X116411Y497707D03*
X126225Y516368D03*
X120225D03*
X115793Y528188D03*
X112393D03*
X123257Y547506D03*
X119087D03*
X115060D03*
X111920Y632922D03*
X114540Y633032D03*
X117750Y633232D03*
X120440Y633347D03*
X121400Y638062D03*
X127313Y649765D03*
X114909Y654926D03*
Y648926D03*
Y642926D03*
X125890Y644163D03*
X122329Y654660D03*
X122280Y651934D03*
X124431Y649570D03*
X118021Y669409D03*
X127738Y659226D03*
X122575Y671930D03*
X118019Y661371D03*
X124737Y735726D03*
X118737D03*
X121737D03*
Y738726D03*
X118737D03*
X124737D03*
X120220Y1324662D03*
X120267Y1327697D03*
X127366Y1535855D03*
X112749Y1524594D03*
Y1532594D03*
Y1528594D03*
X127366Y1541874D03*
Y1547935D03*
X112749Y1540594D03*
Y1544594D03*
Y1548594D03*
Y1536594D03*
Y1552594D03*
Y1564594D03*
Y1560594D03*
Y1556594D03*
X117707Y1553759D03*
X116798Y1586288D03*
Y1598572D03*
X125033Y1589352D03*
X123230Y1597350D03*
X116798Y1617262D03*
Y1635303D03*
X117220Y1680287D03*
X127195Y1670362D03*
X117795Y1698862D03*
X127195Y1688362D03*
Y1692362D03*
X114645Y1698862D03*
X117220Y1683437D03*
X127195Y1708362D03*
Y1700362D03*
X117255Y1730422D03*
X125082Y1727092D03*
X123394Y1723472D03*
X112895Y1737108D03*
X129058Y3010D03*
X128672Y17042D03*
Y22034D03*
X130672Y19538D03*
X129713Y37106D03*
Y28406D03*
Y48720D03*
Y40020D03*
X133335Y69340D03*
X131335Y66844D03*
Y71836D03*
X137379Y72844D03*
Y77836D03*
X142335Y72844D03*
Y77836D03*
X135379Y75340D03*
X136301Y179095D03*
X141520Y181462D03*
X139720Y179162D03*
X143470Y184012D03*
X143340Y204622D03*
X133590Y212382D03*
X129394Y278875D03*
X129375Y274800D03*
X129394Y306236D03*
X140974Y396885D03*
X135220Y397071D03*
X140974Y401885D03*
Y399385D03*
X142166Y490835D03*
X135006Y487753D03*
X132225Y504368D03*
Y510368D03*
X141325Y503806D03*
X141462Y507600D03*
X141329Y510487D03*
X141220Y498810D03*
X132401Y516368D03*
X133160Y532002D03*
X132600Y540472D03*
X130057Y636103D03*
X133467Y634531D03*
X130067Y650213D03*
X134205Y643603D03*
X128193Y662015D03*
X128275Y665515D03*
X129600Y669400D03*
X131330Y665740D03*
X142960Y690807D03*
X140460D03*
X142754Y698811D03*
X140254D03*
X142778Y706835D03*
X140278D03*
X140326Y721660D03*
X142826D03*
X132967Y760525D03*
X141470Y1359100D03*
X140142Y1392545D03*
Y1396275D03*
X129670Y1563160D03*
X140104Y1560136D03*
X129627Y1556360D03*
X129586Y1553759D03*
X129813Y1604367D03*
X130533Y1622321D03*
X129533Y1637862D03*
X138492Y1717592D03*
X139080Y1731398D03*
X141642Y1717592D03*
X132895Y1737108D03*
X149058Y3010D03*
X159582Y17042D03*
Y22034D03*
X157582Y19538D03*
X152477Y23978D03*
X157433D03*
X150477Y25974D03*
X159433D03*
X158492Y37106D03*
Y28406D03*
X151405Y37106D03*
Y28406D03*
X147924Y28258D03*
X158492Y48720D03*
Y40020D03*
X151405Y48720D03*
Y40020D03*
X148784Y48720D03*
X146379Y69340D03*
X155335D03*
X148379Y66844D03*
Y71836D03*
X153335Y66844D03*
Y71836D03*
X158583Y75340D03*
X144335D03*
X147901Y188852D03*
X145720Y186462D03*
Y202862D03*
Y206362D03*
X156670Y344542D03*
X159170D03*
X158110Y376172D03*
X149371Y423383D03*
Y419383D03*
Y427383D03*
Y439383D03*
Y431383D03*
Y435383D03*
Y443383D03*
X159125Y448664D03*
X153360Y449112D03*
X152171Y490615D03*
X149557Y494353D03*
X150113Y488487D03*
X149472Y502810D03*
X149486Y498810D03*
X149472Y506810D03*
X160000Y510052D03*
X152470Y495383D03*
X149518Y522810D03*
X149512Y514810D03*
X150800Y512021D03*
X153737Y514893D03*
X149504Y519881D03*
X154647Y521783D03*
X147141Y698811D03*
X147435Y690807D03*
X149861Y698831D03*
X150155Y690807D03*
X156685Y706836D03*
X153965Y706816D03*
X153879Y721660D03*
X156469D03*
X147031Y706835D03*
X149621D03*
X149669Y721660D03*
X147079D03*
X150877Y757969D03*
X151277Y1339183D03*
X153877D03*
X156477D03*
X156417Y1336343D03*
X151217Y1336393D03*
X153817D03*
X156417Y1333843D03*
X151217Y1333893D03*
X153817D03*
X151277Y1346883D03*
X153877D03*
X151277Y1349383D03*
X153877D03*
X156477Y1346883D03*
Y1349383D03*
Y1344383D03*
X151277D03*
X153877D03*
X156477Y1341883D03*
X151277D03*
X153877D03*
X154477Y1360797D03*
X159898Y1360790D03*
X148663Y1378607D03*
X151163D03*
Y1383807D03*
Y1381207D03*
X148663Y1386407D03*
X151163D03*
X148663Y1383807D03*
Y1381207D03*
X147307Y1404745D03*
X149568Y1395145D03*
Y1397695D03*
X152684Y1403451D03*
X152806Y1414175D03*
X157490Y1421454D03*
X154990D03*
X159858Y1409361D03*
X155858Y1406669D03*
Y1409390D03*
X157530Y1432124D03*
X155030D03*
X157530Y1424124D03*
X155030D03*
X157530Y1429124D03*
X155030Y1426624D03*
Y1429124D03*
X157530Y1426624D03*
Y1435124D03*
X155030D03*
X157530Y1437754D03*
X155030D03*
X144748Y1514878D03*
X149728D03*
X146390Y1504240D03*
X153600Y1505600D03*
X154581Y1520981D03*
X158570D03*
X153271Y1540961D03*
X153138Y1549032D03*
X147067Y1545985D03*
X150502Y1572021D03*
X145522D03*
X159107Y1571364D03*
X157441Y1581932D03*
X155180Y1619872D03*
X156070Y1695702D03*
X144854Y1702389D03*
X154803Y1708532D03*
X145745Y1712362D03*
X155145Y1713517D03*
X155100Y1723262D03*
X152895Y1737108D03*
X169058Y3010D03*
X164538Y17042D03*
Y22034D03*
X173755Y17042D03*
Y22034D03*
X166538Y19538D03*
X171755D03*
X166650Y23978D03*
X171606D03*
X164650Y25974D03*
X173606D03*
X172665Y37106D03*
Y28406D03*
X165579Y37106D03*
Y28406D03*
X172665Y48720D03*
Y40020D03*
X165579Y48720D03*
Y40020D03*
X169583Y69340D03*
X171583Y66844D03*
Y71836D03*
X176539Y66844D03*
Y71836D03*
X165539Y72844D03*
X160583D03*
Y77836D03*
X165539D03*
X167539Y75340D03*
X174327Y230928D03*
X164830Y344542D03*
X161670D03*
X171180Y401885D03*
X163900Y409362D03*
X172507Y417205D03*
X163926Y439397D03*
Y435383D03*
X175640Y453779D03*
X172632Y454095D03*
X163132Y493299D03*
X165176Y500782D03*
X162750Y512502D03*
X166986Y575918D03*
X176393Y575189D03*
X173793D03*
X176393Y572689D03*
X173793D03*
X171293D03*
Y575189D03*
X173793Y577790D03*
X171293D03*
X176393D03*
X176651Y596883D03*
Y594163D03*
X173878Y597027D03*
Y594307D03*
X176651Y599603D03*
X173878Y599747D03*
X161126Y721660D03*
X161078Y706835D03*
X163626Y721660D03*
X163578Y706835D03*
X170877Y1333783D03*
Y1336383D03*
X176077Y1333783D03*
X173477D03*
X176077Y1336383D03*
X173477D03*
X170907Y1339233D03*
X176107D03*
X173507D03*
X170877Y1341883D03*
X176077D03*
X173477D03*
Y1349383D03*
Y1346883D03*
Y1344383D03*
X176077D03*
Y1346883D03*
Y1349383D03*
X170877D03*
Y1346883D03*
Y1344383D03*
X162398Y1360790D03*
X164898D03*
X172807Y1360797D03*
X174932Y1378797D03*
Y1381397D03*
X176358Y1403669D03*
X176258Y1400669D03*
X173892Y1402749D03*
Y1405649D03*
X162693Y1411529D03*
X160490Y1421454D03*
X164000Y1408862D03*
X162257Y1406594D03*
X160530Y1432124D03*
Y1424124D03*
Y1429124D03*
Y1426624D03*
Y1435124D03*
Y1437754D03*
X165500Y1440362D03*
X173727Y1452134D03*
Y1448734D03*
X170570Y1509250D03*
X168900Y1520510D03*
X163920D03*
X161321Y1540858D03*
X161374Y1549073D03*
X166476Y1572464D03*
X171456D03*
X173331Y1579399D03*
X172099Y1588141D03*
X166529Y1707678D03*
X166661Y1721211D03*
X172895Y1737108D03*
X166761Y1732967D03*
X189058Y3010D03*
X178711Y17042D03*
Y22034D03*
X180711Y19538D03*
X179752Y37106D03*
Y28406D03*
X186120Y24162D03*
X188620D03*
X179752Y48720D03*
Y40020D03*
X191583Y69340D03*
X178539D03*
X182583Y72844D03*
Y77836D03*
X187539Y72844D03*
Y77836D03*
X189539Y75340D03*
X180583D03*
X186457Y393071D03*
Y385071D03*
Y389071D03*
X190880Y383012D03*
Y387162D03*
Y391082D03*
X178375Y396571D03*
X186457Y405071D03*
X192220Y408662D03*
Y412162D03*
X184490Y402203D03*
X181845Y401071D03*
X177871Y421383D03*
Y425383D03*
X191305Y430216D03*
X187532Y421387D03*
X177871Y430883D03*
Y443383D03*
X187371D03*
X180740Y437562D03*
X184550Y435712D03*
X187371Y440742D03*
X188221Y454048D03*
X184147Y447078D03*
X187371Y447172D03*
X177871D03*
X181994Y453932D03*
X180640Y447172D03*
X185211Y453942D03*
X185191Y502439D03*
X187490Y568752D03*
X186793Y575189D03*
X184193D03*
X186793Y572689D03*
X184193D03*
X181593Y575189D03*
X178993D03*
X181593Y572689D03*
X178993D03*
X189293Y575189D03*
X186793Y577790D03*
X184193D03*
X189293D03*
X181593D03*
X178993D03*
X181651Y596883D03*
X179151D03*
X186796Y594195D03*
Y596915D03*
X184151Y596883D03*
X179151Y594163D03*
X181651D03*
X184151D03*
X181651Y599603D03*
X179151D03*
X186796Y599635D03*
X184151Y599603D03*
X190977Y669718D03*
X190800Y675662D03*
X191976Y684326D03*
X189800Y705062D03*
X186720Y737862D03*
X180720D03*
X183720D03*
Y734862D03*
X180720D03*
X186720D03*
X185835Y757057D03*
X188978Y756855D03*
X191602Y756839D03*
X189377Y1333783D03*
X191977D03*
X189377Y1336383D03*
X191977D03*
X191947Y1339263D03*
X189347D03*
X189377Y1349383D03*
X191977D03*
X189377Y1346883D03*
X191977D03*
Y1344383D03*
X189377D03*
X191977Y1341883D03*
X189377D03*
X184215Y1361072D03*
X181403Y1361115D03*
X192620Y1360797D03*
X188233Y1387027D03*
Y1379227D03*
Y1381827D03*
Y1384427D03*
X183283Y1387987D03*
X185633Y1387027D03*
X180672Y1387987D03*
X185633Y1379227D03*
X180672Y1380187D03*
X183283D03*
X177532Y1378797D03*
X185633Y1384427D03*
Y1381827D03*
X180672Y1382787D03*
Y1385387D03*
X183283Y1382787D03*
Y1385387D03*
X177421Y1383997D03*
X177532Y1381397D03*
X182653Y1404535D03*
X187711Y1395170D03*
Y1397670D03*
X190827Y1403451D03*
X180977Y1396173D03*
X178458Y1399269D03*
Y1402169D03*
Y1405069D03*
X192767Y1413725D03*
X185643Y1413945D03*
X188211Y1406691D03*
X186165Y1422589D03*
X183135Y1419784D03*
X180510Y1420258D03*
X177510D03*
X186135Y1419784D03*
X183165Y1422589D03*
X177510Y1423278D03*
X180510D03*
X183075Y1430424D03*
Y1425424D03*
Y1427924D03*
X186075Y1430424D03*
Y1425424D03*
Y1427924D03*
X183075Y1432924D03*
X186075D03*
X185895Y1535462D03*
Y1539723D03*
Y1544029D03*
Y1548487D03*
Y1552875D03*
X192600Y1557360D03*
X185895Y1557875D03*
X189600Y1566300D03*
X187400Y1568132D03*
X176793Y1585173D03*
X192529Y1728947D03*
X183822Y1720517D03*
X187542Y1729092D03*
X192895Y1737108D03*
X209058Y3010D03*
X203716Y17042D03*
Y22034D03*
X208672Y17042D03*
Y22034D03*
X201716Y19538D03*
X201567Y23978D03*
X196611D03*
X194611Y25974D03*
X203567D03*
X208784D03*
X202626Y28406D03*
Y37106D03*
X195539Y28406D03*
Y37106D03*
X202626Y40020D03*
Y48720D03*
X195539Y40020D03*
Y48720D03*
X200539Y69340D03*
X193583Y66844D03*
Y71836D03*
X198539Y66844D03*
Y71836D03*
X204717Y72844D03*
Y77836D03*
X202717Y75340D03*
X195050Y412055D03*
X199047Y428626D03*
X199139Y422882D03*
X199149Y425755D03*
Y420255D03*
Y414755D03*
X195050Y417465D03*
X199149Y436755D03*
Y442255D03*
Y431255D03*
X196215Y447565D03*
X199149Y453255D03*
Y447755D03*
X197650Y455712D03*
X199149Y468255D03*
X208200Y493510D03*
X196526Y567825D03*
X202338Y568746D03*
X201392Y574271D03*
X198336D03*
X195888Y581071D03*
X194515Y583433D03*
X199164Y582481D03*
X200654Y578271D03*
X201622Y581009D03*
X202262Y592305D03*
X205162D03*
X197423Y601496D03*
X194059Y604901D03*
X202338Y602746D03*
X201392Y608271D03*
X203892Y594471D03*
X202492Y596571D03*
X208292D03*
X206892Y594371D03*
X205392Y596571D03*
X204610Y605097D03*
X195888Y615071D03*
X194515Y617433D03*
X200654Y612271D03*
X201622Y615009D03*
X194059Y638901D03*
X197423Y635496D03*
X202338Y636746D03*
X203892Y628471D03*
X202492Y630571D03*
X202262Y626305D03*
X208292Y630571D03*
X206892Y628371D03*
X205162Y626305D03*
X205392Y630571D03*
X204610Y639097D03*
X194515Y651433D03*
X195888Y649071D03*
X201392Y642271D03*
X199164Y650481D03*
X201622Y649009D03*
X198336Y642271D03*
X205320Y667562D03*
X207620Y671262D03*
X198420Y672662D03*
X198495Y669487D03*
X205392Y664571D03*
X205162Y660305D03*
X206892Y662371D03*
X202262Y660305D03*
X202492Y664571D03*
X203892Y662471D03*
X208292Y664571D03*
X194858Y684348D03*
X196049Y678195D03*
X194196Y687061D03*
X193332Y678195D03*
X207129Y690027D03*
X203199Y690006D03*
X197086Y686326D03*
X203179Y693626D03*
X207140Y693636D03*
X195735Y696469D03*
X198235Y698969D03*
Y696469D03*
X200735Y698969D03*
Y696469D03*
X207140Y738462D03*
X205220Y736562D03*
X201220Y736662D03*
X203660Y731802D03*
X199720Y732862D03*
X206720Y731862D03*
X199220Y739362D03*
X207602Y756855D03*
X199602D03*
X195602Y756839D03*
X203602Y756855D03*
X208977Y1336383D03*
Y1333783D03*
X194577D03*
Y1336383D03*
X209007Y1339263D03*
X194547D03*
X208977Y1341883D03*
X194577Y1349383D03*
Y1346883D03*
Y1344383D03*
X208977D03*
Y1346883D03*
Y1349383D03*
X194577Y1341883D03*
X203441Y1360790D03*
X198041D03*
X200941D03*
X201071Y1412173D03*
X198001Y1409361D03*
X193941Y1407029D03*
X200797Y1409605D03*
X200492Y1406686D03*
X193941Y1409750D03*
X195966Y1542863D03*
X207229Y1631181D03*
X193410Y1711606D03*
X205582Y1700867D03*
X196443Y1722197D03*
X204600Y1733022D03*
X217889Y17042D03*
Y22034D03*
X222845Y17042D03*
Y22034D03*
X210672Y19538D03*
X215889D03*
X224845D03*
X215740Y23978D03*
X210784D03*
X217740Y25974D03*
X223886Y28406D03*
Y37106D03*
X216799Y28406D03*
Y37106D03*
X209713Y28406D03*
Y37106D03*
X223886Y40020D03*
Y48720D03*
X216799Y40020D03*
Y48720D03*
X209713Y40020D03*
Y48720D03*
X215717Y66844D03*
Y71836D03*
X220673Y66844D03*
Y71836D03*
X213717Y69340D03*
X222673D03*
X209673Y72844D03*
Y77836D03*
X211673Y75340D03*
X224717D03*
X225407Y321831D03*
X223330Y426467D03*
X220843Y430004D03*
X209530Y426192D03*
X217770Y428262D03*
X220874Y442079D03*
X209579Y457222D03*
Y462235D03*
X224064Y568113D03*
X221464D03*
X210391Y567981D03*
X224064Y602113D03*
X221464D03*
X223403Y596820D03*
Y594220D03*
X212891Y601981D03*
X210391D03*
X223403Y630820D03*
Y628220D03*
X224064Y636113D03*
X221464D03*
X210391Y635981D03*
X212891D03*
X223403Y664820D03*
X217510Y668712D03*
X225167Y672006D03*
X222567D03*
X219967D03*
X217367D03*
X210320Y671262D03*
X211348Y688087D03*
Y685287D03*
X214100Y687376D03*
Y690376D03*
Y684376D03*
Y681376D03*
Y678376D03*
X211348Y690787D03*
Y693587D03*
X214100Y693576D03*
X224506Y698138D03*
Y700738D03*
X221906Y698138D03*
Y700738D03*
X219306D03*
Y698138D03*
X224900Y713293D03*
X209720Y731862D03*
X211220Y740362D03*
X220033Y756844D03*
X211602Y756855D03*
X216842Y756865D03*
X214177Y1336383D03*
X211577D03*
X214177Y1333783D03*
X211577D03*
X214207Y1339263D03*
X211607D03*
X214177Y1341883D03*
X211577D03*
X214177Y1349383D03*
Y1346883D03*
Y1344383D03*
X211577D03*
Y1346883D03*
Y1349383D03*
X215824Y1361199D03*
X211350Y1360797D03*
X218960Y1388312D03*
X213075Y1381558D03*
X217133Y1384055D03*
X214425Y1384058D03*
X215675Y1381558D03*
X218175D03*
X213075Y1378958D03*
X215675D03*
X218175D03*
X219752Y1405499D03*
Y1401999D03*
Y1398599D03*
X214201Y1404169D03*
X212035Y1402899D03*
X214101Y1401169D03*
X216554Y1399264D03*
Y1402164D03*
Y1405064D03*
X212035Y1405799D03*
X224137Y1414345D03*
X224077Y1416975D03*
X224350Y1432032D03*
X219587Y1435402D03*
X217469Y1454725D03*
X219587Y1443402D03*
Y1439402D03*
X220869Y1454725D03*
X209820Y1631142D03*
X210593Y1714017D03*
X212120Y1703062D03*
X212684Y1720307D03*
X212895Y1737108D03*
X229058Y3010D03*
X233339Y17662D03*
X238063Y37162D03*
X230972Y28406D03*
Y37106D03*
X229135Y26474D03*
X225735D03*
X235701Y39570D03*
X230972Y48720D03*
Y40020D03*
X229131Y50646D03*
X225731D03*
X226717Y72844D03*
Y77836D03*
X231673Y72844D03*
Y77836D03*
X233673Y75340D03*
X238297Y129703D03*
X233800Y162692D03*
X237539Y174266D03*
X234902Y174047D03*
X226800Y359464D03*
X228550Y420412D03*
X231864Y568113D03*
X229264D03*
X226664D03*
X238393Y570490D03*
X240993D03*
X229264Y602113D03*
X226664D03*
X226003Y594220D03*
Y596820D03*
X228603Y594220D03*
Y596820D03*
X231864Y602113D03*
X233803Y594220D03*
Y596820D03*
X231203Y594220D03*
Y596820D03*
X238393Y604490D03*
X240993D03*
Y596820D03*
X238393D03*
X240993Y594220D03*
X238393D03*
X226003Y628220D03*
Y630820D03*
X228603Y628220D03*
Y630820D03*
X231864Y636113D03*
X233803Y628220D03*
Y630820D03*
X231203Y628220D03*
Y630820D03*
X229264Y636113D03*
X226664D03*
X238393Y638490D03*
X240993D03*
Y630820D03*
X238393D03*
X240993Y628220D03*
X238393D03*
X228603Y664820D03*
X233803D03*
X231203D03*
X226003D03*
X230367Y672006D03*
X227767D03*
X227106Y698138D03*
Y700738D03*
X227430Y719772D03*
X238940Y716652D03*
X230864Y1254295D03*
X249058Y3010D03*
X243490Y23002D03*
X253000Y28362D03*
X256500D03*
X249500D03*
X242220Y39362D03*
X246220D03*
X250220D03*
X254050Y39422D03*
X248820Y48962D03*
X252320D03*
X255820D03*
X257520Y51562D03*
X254020D03*
X250520D03*
X247720Y71862D03*
X244300Y59762D03*
X249885Y69623D03*
X245220Y67862D03*
X247720Y75862D03*
X251797Y100843D03*
X248097Y92143D03*
X247897Y100543D03*
X244822Y115543D03*
Y111543D03*
X253878Y111771D03*
X252195Y144320D03*
X243892Y140912D03*
X242255Y162512D03*
X257256Y156727D03*
X252000Y395400D03*
X257434Y415896D03*
X256695Y461117D03*
X249300Y510362D03*
X253800Y515362D03*
X249860Y518222D03*
X254713Y518465D03*
X245700Y513262D03*
X250100Y521783D03*
X246400Y563162D03*
X256885Y574805D03*
X254385D03*
X256855Y571995D03*
X251885Y574805D03*
X249800Y563262D03*
X254355Y589235D03*
X256855D03*
X251855D03*
X256855Y605995D03*
X251885Y608805D03*
X257643Y594220D03*
X255043D03*
Y596820D03*
X257643D03*
X256885Y608805D03*
X254385D03*
X256855Y603495D03*
X251855Y623265D03*
X254355D03*
X256855D03*
Y639995D03*
Y637495D03*
X257643Y628220D03*
X255043D03*
Y630820D03*
X257643D03*
X256885Y642805D03*
X254385D03*
X251855Y657265D03*
X251885Y642805D03*
X254355Y657265D03*
X256855D03*
X257643Y662220D03*
X255043D03*
Y664820D03*
X257643D03*
X253819Y675567D03*
X253849Y678077D03*
X256419Y675567D03*
X256449Y678077D03*
X251219Y675567D03*
X251249Y678077D03*
X248649D03*
X248989Y698827D03*
X249019Y693767D03*
X251589Y698827D03*
X251649Y696277D03*
X254189Y698827D03*
X251619Y693767D03*
X256849Y696277D03*
X256789Y698827D03*
X256819Y693767D03*
X254249Y696277D03*
X254219Y693767D03*
X248300Y703862D03*
X242460Y716652D03*
X253057Y755345D03*
X245487Y755435D03*
X251187Y1255025D03*
X252895Y1737108D03*
X269058Y3010D03*
X260000Y28362D03*
X263280Y35312D03*
X272600Y27182D03*
X271600Y40162D03*
X259320Y48962D03*
X261020Y51562D03*
X263520D03*
X261820Y48962D03*
X264740Y49182D03*
X266497Y69536D03*
Y72036D03*
X264720Y56362D03*
Y60362D03*
Y64362D03*
X266597Y77526D03*
Y80026D03*
X261420Y100662D03*
X264920D03*
X268420D03*
X262920Y97962D03*
X266420D03*
X269920D03*
X272361Y120243D03*
X270364Y118415D03*
X261387Y133783D03*
X258257D03*
X266975Y140107D03*
X272800Y140162D03*
X264578Y151203D03*
Y155203D03*
X260100Y159562D03*
X260700Y218662D03*
X268940Y217982D03*
X263580Y218627D03*
X270745Y207562D03*
X265500Y227862D03*
X263000D03*
X260500Y227362D03*
Y224862D03*
X265343Y244460D03*
X270240Y245332D03*
X271821Y251962D03*
X267759D03*
X258746Y407842D03*
X260807Y424403D03*
X259224Y419532D03*
X272029Y443735D03*
X259869Y431039D03*
X264055Y574505D03*
X264025Y571995D03*
X261555Y574505D03*
X261525Y571995D03*
X264055Y566935D03*
X263995Y569485D03*
X261495D03*
X261555Y566935D03*
X266555Y574505D03*
X266525Y571995D03*
X266495Y569485D03*
X266555Y566935D03*
X269055Y574505D03*
X269025Y571995D03*
X268995Y569485D03*
X269055Y566935D03*
X261465Y592115D03*
X261525Y589565D03*
X264025D03*
X263965Y592115D03*
X266525Y589565D03*
X266465Y592115D03*
X269025Y589565D03*
X268965Y592115D03*
X264025Y605995D03*
X261525D03*
X264055Y608505D03*
X261555D03*
X261435Y597175D03*
X261495Y594625D03*
X263995D03*
X263935Y597175D03*
X266525Y605995D03*
X266555Y608505D03*
X266435Y597175D03*
X266495Y594625D03*
X261525Y603495D03*
X264025D03*
X266525D03*
X269025Y605995D03*
X269055Y608505D03*
X268935Y597175D03*
X268995Y594625D03*
X269025Y603495D03*
X261495Y621055D03*
X263995D03*
X261525Y623565D03*
X264025D03*
X263995Y611055D03*
X261495D03*
X266495Y621055D03*
X266525Y623565D03*
X266495Y611055D03*
X268995Y621055D03*
X269025Y623565D03*
X268995Y611055D03*
X261525Y639995D03*
X264025D03*
X261525Y637495D03*
X266525Y639995D03*
X269025D03*
X264025Y637495D03*
X266525D03*
X269025D03*
X263965Y626115D03*
X261465D03*
X266465D03*
X268965D03*
X261495Y655055D03*
X263995D03*
X261525Y657565D03*
X264025D03*
X263995Y645055D03*
X264055Y642505D03*
X261495Y645055D03*
X261555Y642505D03*
X266495Y655055D03*
X266525Y657565D03*
X266495Y645055D03*
X266555Y642505D03*
X268995Y655055D03*
X269025Y657565D03*
X268995Y645055D03*
X269055Y642505D03*
X261465Y660115D03*
X263965D03*
X266465D03*
X268965D03*
X259049Y678077D03*
X259019Y675567D03*
X259419Y693767D03*
X259389Y698827D03*
X259449Y696277D03*
X269600Y715792D03*
X274247Y727165D03*
X273046Y735662D03*
X270100Y727262D03*
X264000Y726262D03*
X266700Y730962D03*
X270322Y740207D03*
X274270Y746602D03*
X271570Y746422D03*
X265997Y747535D03*
X272208Y768516D03*
X271057Y765525D03*
X272895Y1737108D03*
X289058Y3010D03*
X285900Y23962D03*
X286071Y28406D03*
X278984D03*
X284233Y26474D03*
X280833D03*
X287952Y39984D03*
X286071Y48720D03*
X286500Y52462D03*
X278984Y48720D03*
X284230Y50646D03*
X280830D03*
X287800Y60062D03*
X279277Y99183D03*
X285357Y105003D03*
X288557D03*
X280857Y107303D03*
X285857Y115603D03*
X282857D03*
X280857Y109903D03*
X289557Y121803D03*
X275797Y129592D03*
X283953Y152503D03*
X280687Y140746D03*
X283053Y139728D03*
X288520Y157062D03*
X282640Y214102D03*
X279740Y205962D03*
X276890Y249022D03*
X289920Y248652D03*
X286920D03*
X282420D03*
X286481Y251962D03*
X281077D03*
X276491D03*
X289274Y290662D03*
X284515D03*
X276500Y444862D03*
X274850Y442562D03*
X279500Y455362D03*
X277578Y509039D03*
X284482Y569548D03*
Y566022D03*
X286582Y630757D03*
Y637809D03*
Y634283D03*
X287819Y691097D03*
X284287Y716015D03*
X277046Y725709D03*
Y735442D03*
X284358Y732562D03*
X287820Y727962D03*
X278520Y738072D03*
X283350Y728483D03*
X279507Y727025D03*
X285046Y737964D03*
X281046Y737938D03*
X275210Y738102D03*
X290077Y739735D03*
X287607Y754962D03*
X277046Y746702D03*
X281046D03*
X285046D03*
X289047Y760245D03*
X291520Y12762D03*
X291660Y21642D03*
X295520Y12762D03*
X302610Y26362D03*
X292060Y24472D03*
X304927Y24654D03*
X304972Y28362D03*
X298720Y40017D03*
X306720Y39982D03*
X292590Y53982D03*
X306570Y50222D03*
X290720Y40017D03*
X294720D03*
X295524Y52092D03*
X301310Y52482D03*
X292942Y67513D03*
Y71499D03*
X305747Y64013D03*
Y61113D03*
X293447Y78573D03*
X293452Y82483D03*
Y85983D03*
X303047Y79373D03*
X299947Y79273D03*
X299657Y92503D03*
X301183Y107103D03*
Y110003D03*
Y112803D03*
X301751Y127466D03*
Y124466D03*
Y121466D03*
X302891Y141811D03*
X296478Y149203D03*
X296800Y139762D03*
X294553Y153819D03*
X306000Y165662D03*
X296478Y158703D03*
X306730Y173842D03*
X304651Y251962D03*
X291759D03*
X306736Y290662D03*
X302765D03*
X298184D03*
X293763D03*
X298587Y508074D03*
X306087Y569718D03*
X293805Y569397D03*
X305612Y622530D03*
Y625030D03*
X294658Y637809D03*
X305612Y627530D03*
X296405Y630732D03*
Y634132D03*
X295962Y679374D03*
X294679Y688446D03*
X291600Y705162D03*
X298273Y715400D03*
X297087Y721249D03*
X304602Y727968D03*
X293027Y755985D03*
X290680Y745312D03*
X299427Y768265D03*
X303647Y1307981D03*
X303831Y1318566D03*
X303807Y1342225D03*
X303831Y1344866D03*
X303723Y1353316D03*
Y1355853D03*
X304047Y1368565D03*
X304051Y1365453D03*
X306667Y1361597D03*
X302805Y1379941D03*
Y1376541D03*
X296170Y1622852D03*
X292895Y1737108D03*
X309058Y3010D03*
X318651Y22921D03*
X314657Y71803D03*
Y68903D03*
X320057Y85803D03*
X323117Y81168D03*
Y76938D03*
X320057Y88803D03*
X313357Y89503D03*
X313457Y96803D03*
X311057Y107103D03*
Y110003D03*
Y112803D03*
X311758Y124469D03*
Y121469D03*
Y127469D03*
X308175Y144202D03*
X320825Y159062D03*
X308500Y165662D03*
X311200Y165562D03*
X309230Y173842D03*
X309756Y181449D03*
X310970Y195362D03*
X308790Y197622D03*
X319370Y214492D03*
X316370D03*
X319370Y217492D03*
X316370D03*
X306910Y228162D03*
X309910D03*
X306910Y225162D03*
X309910D03*
X313995Y237724D03*
X317981D03*
X320940Y238372D03*
X317129Y251962D03*
X316463Y290662D03*
X314200Y585282D03*
X316080Y578262D03*
X320691Y602448D03*
X321276Y599298D03*
X308605Y629525D03*
Y627025D03*
X319557Y736225D03*
X317967Y746985D03*
X316397Y776125D03*
X320578Y1290197D03*
X323028Y1297967D03*
X320428D03*
Y1295467D03*
X323028D03*
Y1292967D03*
X320428D03*
X321119Y1313108D03*
X317119D03*
X313119D03*
X317979Y1371248D03*
X315221Y1372445D03*
X313841Y1365553D03*
X309841Y1364815D03*
X318051Y1367043D03*
X316579Y1364585D03*
X309841Y1367871D03*
X329535Y49388D03*
X336240Y150738D03*
X332500D03*
X326216Y138787D03*
X326900Y162287D03*
X335285Y210609D03*
X332285D03*
X323420Y207549D03*
X326168Y207580D03*
X334485Y216809D03*
X337000Y216862D03*
X325755Y230719D03*
X338985Y229509D03*
X325855Y227619D03*
X334500Y219362D03*
X337000D03*
X325055Y237219D03*
X328965Y237214D03*
X332465D03*
X329648Y252202D03*
X329002Y290662D03*
X330417Y380482D03*
X330674Y368261D03*
Y365702D03*
X328167Y379073D03*
X336370Y406302D03*
X331760Y705882D03*
X331339Y709313D03*
X328120Y710862D03*
X335677Y715215D03*
X327107Y732665D03*
X335467Y725335D03*
X338097Y736235D03*
X335126Y728323D03*
X327096Y736005D03*
X336446Y746486D03*
X339148Y1269717D03*
X339088Y1272287D03*
X339028Y1274887D03*
X325688Y1290167D03*
X325718Y1287587D03*
X328078Y1288747D03*
X323178Y1290197D03*
X323208Y1287617D03*
X328168Y1280967D03*
X325748Y1284987D03*
X328108Y1286147D03*
X328138Y1283567D03*
X328018Y1291317D03*
X339035Y1280218D03*
X339040Y1277594D03*
X328065Y1299248D03*
X325538Y1297937D03*
Y1292937D03*
Y1295437D03*
X328058Y1293917D03*
X328070Y1296624D03*
X325119Y1313108D03*
X328915Y1337104D03*
X331515D03*
X328915Y1331904D03*
X331515D03*
X328915Y1329304D03*
X331515D03*
X328915Y1334504D03*
X331515D03*
X328915Y1326704D03*
X331515D03*
X328915Y1339704D03*
X335679Y1330518D03*
X334973Y1333353D03*
X338795Y1338799D03*
X338917Y1349488D03*
X336347Y1348353D03*
X336179Y1342753D03*
X332475Y1357945D03*
X327875Y1363945D03*
Y1361045D03*
X330041Y1362315D03*
X329941Y1359315D03*
X332475Y1363345D03*
Y1360445D03*
X332895Y1737108D03*
X349535Y49388D03*
X340440Y120552D03*
X344776Y148462D03*
X342700Y139662D03*
X348100Y185162D03*
X345869Y192716D03*
X345600Y188162D03*
X353145Y219362D03*
X342000Y252612D03*
X354672Y252693D03*
X345164Y314234D03*
X343411Y363143D03*
X345411Y364702D03*
X343411Y375364D03*
X345411Y376923D03*
X343354Y387988D03*
X343720Y400628D03*
X347340Y407462D03*
X348880Y703442D03*
X354100Y720743D03*
X349187Y715485D03*
X352879Y728657D03*
X348037Y728735D03*
X348730Y731698D03*
X344446Y739434D03*
X348000Y755362D03*
X344264Y1272455D03*
X341754Y1272485D03*
X344252Y1269948D03*
X341742Y1269978D03*
X344258Y1267117D03*
X341748Y1267147D03*
X341754Y1274985D03*
X344264Y1274955D03*
X355036Y1272433D03*
Y1269933D03*
X355378Y1262027D03*
X355318Y1264597D03*
X355258Y1267197D03*
X355036Y1274933D03*
X341605Y1280248D03*
X344115Y1280218D03*
X344264Y1277455D03*
X341754Y1277485D03*
X355048Y1277440D03*
X355025Y1280248D03*
X339769Y1299868D03*
X342769D03*
X348804Y1346877D03*
X350470Y1349030D03*
X345969Y1342755D03*
X341969Y1342017D03*
X350179Y1344245D03*
X348707Y1341787D03*
X341969Y1345073D03*
X354850Y1371908D03*
X351850D03*
X349260Y1373418D03*
X351850Y1375408D03*
X354850D03*
X351850Y1378408D03*
X354850D03*
X351850Y1381408D03*
X354850D03*
X349260Y1376918D03*
Y1379918D03*
X349636Y1399601D03*
X352713Y1399336D03*
X355513Y1402306D03*
X352513D03*
X349513D03*
X355325Y1405386D03*
X349463Y1405286D03*
X352463D03*
X355325Y1408386D03*
X346426Y1414401D03*
X352401Y1414432D03*
X355325Y1414386D03*
Y1417386D03*
X352401Y1411432D03*
X355325Y1411386D03*
X352401Y1408432D03*
X349123Y1411376D03*
X349323Y1408406D03*
X349073Y1414356D03*
X346256Y1417301D03*
X352231Y1417332D03*
X348903Y1417256D03*
X352895Y1737108D03*
X363625Y127662D03*
X361800Y122522D03*
X366060Y133912D03*
X363525Y158702D03*
X356250Y216342D03*
X358209Y208169D03*
X361190Y210762D03*
X357303Y213159D03*
X371551Y224862D03*
X367306Y252811D03*
X366498Y290264D03*
X357764Y314234D03*
X357660Y318850D03*
X363750Y369362D03*
X364014Y382304D03*
X364179Y394596D03*
Y392037D03*
X371066Y400628D03*
X369690Y431812D03*
X365970Y444662D03*
X365771Y449480D03*
X359669Y686744D03*
X360470Y705965D03*
X363101Y697348D03*
X359930Y732985D03*
X358902Y736225D03*
X355946Y728800D03*
X359790Y729835D03*
X358902Y743035D03*
Y754945D03*
Y746405D03*
X360927Y757665D03*
X371578Y1248967D03*
X371458Y1254137D03*
X371330Y1256687D03*
X371518Y1251537D03*
X371278Y1259257D03*
X360198Y1269777D03*
X357546Y1272403D03*
Y1269903D03*
X360138Y1272347D03*
X357828Y1264567D03*
X357888Y1261997D03*
X360378Y1264627D03*
X360438Y1262057D03*
X357768Y1267167D03*
X360318Y1267227D03*
X357546Y1274903D03*
X360128Y1274957D03*
X371218Y1261857D03*
X371225Y1267188D03*
X371230Y1264564D03*
X357558Y1277410D03*
X357535Y1280218D03*
X360120Y1277654D03*
X361043Y1306506D03*
X361769Y1300008D03*
X363643Y1306506D03*
X364769Y1300008D03*
X367939Y1303319D03*
Y1305919D03*
Y1308519D03*
X361043Y1314306D03*
Y1316906D03*
X362393Y1319406D03*
X361043Y1309106D03*
Y1311706D03*
X363643Y1316906D03*
Y1314306D03*
Y1309106D03*
Y1311706D03*
X367694Y1317092D03*
X367807Y1319592D03*
X370874Y1335876D03*
X367490Y1332568D03*
X368391Y1328161D03*
X370923Y1325373D03*
X362147Y1336553D03*
X360003Y1338247D03*
X364269Y1338017D03*
X364073Y1334903D03*
X360003Y1341147D03*
X362147Y1339653D03*
X364347Y1340853D03*
X364647Y1371990D03*
X361647D03*
X358647D03*
X367647D03*
X370552Y1372073D03*
X364647Y1375490D03*
X361647D03*
X358647D03*
Y1378490D03*
X370552Y1375573D03*
X367647Y1375490D03*
X355713Y1399336D03*
X361703Y1399386D03*
X364703D03*
X367703D03*
X370703D03*
X358703Y1402386D03*
X361703D03*
X364703D03*
X367703D03*
X370703D03*
X358713Y1399336D03*
X358573Y1405336D03*
X361573D03*
X364573D03*
X367573D03*
X370573D03*
X358703Y1414606D03*
X361703D03*
X364703D03*
X361703Y1417386D03*
X358703D03*
X364703D03*
X367703D03*
Y1414606D03*
X358217Y1411405D03*
X370517Y1414615D03*
X370717Y1417405D03*
X357917Y1408205D03*
X367948Y1531529D03*
X371850Y1534062D03*
X368600Y1543200D03*
X367140Y1645390D03*
X366700Y1649000D03*
X370500Y1654362D03*
X370635Y1675820D03*
X369300Y1680400D03*
Y1682900D03*
X383140Y119822D03*
X375330Y121182D03*
X374981Y131433D03*
X383160Y124322D03*
X383060Y128491D03*
X372530Y122972D03*
X373200Y126052D03*
X376245Y212862D03*
Y217362D03*
Y221362D03*
Y225362D03*
X386120Y220322D03*
X379860Y252162D03*
X379112Y290386D03*
X385720Y323761D03*
X376500Y362736D03*
X377136Y390307D03*
X383060Y403542D03*
X385520Y429262D03*
X373190Y438342D03*
X384510Y438662D03*
X379220Y436362D03*
X376220D03*
X382220D03*
X385730Y460922D03*
X382860Y471122D03*
X379220Y470962D03*
X371970Y683892D03*
X376638Y1248997D03*
X374088Y1248937D03*
X374028Y1251507D03*
X373823Y1256896D03*
X376333Y1256866D03*
X376518Y1254167D03*
X376578Y1251567D03*
X373968Y1254107D03*
X373835Y1259403D03*
X376345Y1259373D03*
X387478Y1248967D03*
X387358Y1254137D03*
X387117Y1256851D03*
X387418Y1251537D03*
X387117Y1259351D03*
X373835Y1261903D03*
Y1264403D03*
X376345Y1261873D03*
Y1264373D03*
X376285Y1267218D03*
X373735Y1267158D03*
X387117Y1261851D03*
X387129Y1264358D03*
X387125Y1267188D03*
X383239Y1286578D03*
X378069Y1286568D03*
X375069D03*
X386239Y1286578D03*
X380842Y1334095D03*
X383549Y1333998D03*
X378097Y1329329D03*
X374097Y1328591D03*
X382307Y1330819D03*
X380835Y1328361D03*
X374097Y1331647D03*
X373552Y1372073D03*
X377025Y1371990D03*
X380025D03*
X373532Y1378598D03*
X373552Y1375573D03*
X380025Y1378490D03*
X377025D03*
X380025Y1375490D03*
X377025D03*
Y1381490D03*
X380025D03*
X383127Y1395610D03*
X376825Y1399386D03*
X379825D03*
X373703D03*
X379825Y1402386D03*
X376825D03*
X373703D03*
X376825Y1405386D03*
X379825D03*
X373573Y1405336D03*
X374027Y1411365D03*
X373703Y1414606D03*
X376825Y1414386D03*
X379825D03*
X376825Y1417386D03*
Y1411386D03*
X379825D03*
X373703Y1417386D03*
X376825Y1408386D03*
X379825D03*
X374307Y1408135D03*
X381060Y1433622D03*
X382489Y1428478D03*
X385667Y1433425D03*
X377830Y1534342D03*
X381120Y1534102D03*
X377720Y1539862D03*
X374720D03*
X374800Y1546400D03*
X385100Y1539700D03*
X381800Y1539600D03*
X381000Y1546500D03*
X384000D03*
X378000Y1546400D03*
X387152Y1582659D03*
X387930Y1585155D03*
X384600Y1595100D03*
X382220Y1591870D03*
X374690Y1631700D03*
X374391Y1648476D03*
X385123Y1639732D03*
X378547D03*
X375550Y1662052D03*
X380170Y1660002D03*
X372640Y1662112D03*
X380077Y1654049D03*
X381068Y1674824D03*
X386824Y1682866D03*
X387760Y1671092D03*
X372009Y1682584D03*
X373320Y1688202D03*
X376610Y1688252D03*
X372895Y1737108D03*
X393830Y62062D03*
X399800Y59662D03*
X403800D03*
X396380Y62742D03*
X402100Y62632D03*
X388735Y117322D03*
X395980Y148272D03*
X390830Y155833D03*
X388965Y215067D03*
Y209949D03*
X388720Y218362D03*
X394720Y206362D03*
X392616Y252162D03*
X392083Y290954D03*
X404215Y291140D03*
X398720Y318643D03*
Y321202D03*
X398661Y323761D03*
X403675Y363081D03*
X390876Y365640D03*
X391195Y368199D03*
X391101Y380939D03*
X403581Y375880D03*
X390843Y378439D03*
X403875Y365640D03*
X404120Y378439D03*
X390730Y394852D03*
X403570Y388874D03*
X404291Y391433D03*
X403700Y402422D03*
X390892Y406863D03*
X391149Y404304D03*
X403720Y405552D03*
X403260Y439352D03*
X391150Y445302D03*
X388720Y430862D03*
X403220Y436362D03*
X396570Y472602D03*
X400080Y472652D03*
X391360Y495712D03*
X402780Y499372D03*
X394860Y518812D03*
X403200Y572622D03*
X398796Y1161570D03*
Y1153070D03*
Y1170070D03*
X403738Y1249027D03*
X403618Y1254197D03*
X403498Y1256747D03*
X403678Y1251597D03*
X392538Y1248997D03*
X389928Y1251507D03*
X389988Y1248937D03*
X389868Y1254107D03*
X392298Y1256717D03*
X392418Y1254167D03*
X389627Y1256821D03*
X392478Y1251567D03*
X392238Y1259287D03*
X389627Y1259321D03*
X403438Y1259317D03*
X392220Y1264594D03*
X392228Y1261897D03*
X389627Y1261821D03*
X389639Y1264328D03*
X389635Y1267158D03*
X392185Y1267218D03*
X403385Y1267248D03*
X403378Y1261917D03*
X403390Y1264624D03*
X396139Y1286708D03*
X399139D03*
X395771Y1303480D03*
X393171D03*
X395771Y1300880D03*
X393171D03*
X395771Y1295680D03*
X393171D03*
X395771Y1298280D03*
X393171D03*
X394521Y1305980D03*
X400067Y1303319D03*
Y1300719D03*
Y1295519D03*
Y1298119D03*
Y1305919D03*
Y1308519D03*
X399935Y1317092D03*
Y1319592D03*
X392131Y1324821D03*
X396397Y1324591D03*
X394197Y1323091D03*
X396397Y1321691D03*
X399673Y1332653D03*
X403130Y1335963D03*
X400073Y1327653D03*
X403051Y1325373D03*
X394297Y1326091D03*
X392131Y1327721D03*
X396397Y1327491D03*
X400926Y1402207D03*
X391249Y1401048D03*
X390934Y1404085D03*
X401079Y1399208D03*
X400926Y1404707D03*
X400919Y1411231D03*
X392517Y1419015D03*
X400991Y1417264D03*
X390934Y1407605D03*
X390914Y1412991D03*
X391370Y1424782D03*
X403125Y1425008D03*
X390687Y1431713D03*
X394067Y1435323D03*
X401244Y1440773D03*
X396822Y1439340D03*
X396921Y1549810D03*
X396768Y1541810D03*
X396946Y1560810D03*
Y1556810D03*
X392108Y1582659D03*
X391330Y1585155D03*
X404030Y1595390D03*
Y1591990D03*
X401812Y1616456D03*
X388220Y1631404D03*
X394910Y1632364D03*
X392550Y1618650D03*
X397406Y1633142D03*
X394910Y1637320D03*
X401740Y1648082D03*
X404240D03*
X404320Y1645452D03*
X401820D03*
X391563Y1640244D03*
X397406Y1636542D03*
X397400Y1641000D03*
X402246Y1671745D03*
X390180Y1668212D03*
X409535Y49388D03*
X412930Y62572D03*
X407970Y59612D03*
X407790Y62652D03*
X415800Y62665D03*
Y67465D03*
X419901Y117491D03*
X411434Y163662D03*
X408284D03*
X407490Y216912D03*
X410996Y218834D03*
X412820Y231922D03*
X405478Y236726D03*
X410090Y241932D03*
X420710Y242482D03*
X405139Y239908D03*
X417765Y252162D03*
X404985D03*
X417218Y291274D03*
X419920Y338162D03*
X416220Y364062D03*
X419012Y368762D03*
X418704Y379201D03*
X416762Y367353D03*
X418602Y394722D03*
X419023Y381760D03*
X418540Y392163D03*
X418982Y407847D03*
X416514Y407028D03*
X417010Y439352D03*
X415130Y480202D03*
X410532Y1153341D03*
X407948Y1153370D03*
Y1161570D03*
X410532Y1161541D03*
X419460Y1161570D03*
Y1153370D03*
X407948Y1169597D03*
X410532D03*
X419460D03*
X406248Y1248997D03*
X408798Y1249057D03*
X408511Y1256866D03*
X406001Y1256896D03*
X406128Y1254167D03*
X408678Y1254227D03*
X406188Y1251567D03*
X419638Y1248967D03*
X419295Y1256851D03*
X419518Y1254137D03*
X419578Y1251537D03*
X419295Y1259351D03*
X408738Y1251627D03*
X408523Y1259373D03*
X406013Y1259403D03*
X419295Y1261851D03*
X419307Y1264358D03*
X419285Y1267188D03*
X408523Y1264373D03*
X406013Y1264403D03*
Y1261903D03*
X408523Y1261873D03*
X405895Y1267218D03*
X408445Y1267278D03*
X416099Y1335568D03*
X414617Y1333473D03*
X410225Y1329329D03*
X406225Y1328591D03*
X414435Y1330819D03*
X412963Y1328361D03*
X406225Y1331647D03*
X422320Y1383862D03*
X414333Y1385292D03*
X412465Y1393878D03*
X419974Y1405289D03*
Y1412789D03*
X420474Y1420289D03*
X410912Y1418177D03*
X408968Y1410427D03*
X411162Y1414126D03*
X407125Y1424978D03*
X419861Y1429718D03*
X422708Y1437560D03*
X416999Y1441908D03*
X404475Y1552452D03*
X407625Y1552572D03*
X419820Y1555862D03*
X405000Y1566670D03*
X419002Y1600306D03*
X406526Y1591212D03*
Y1596168D03*
X412600Y1601000D03*
X406768Y1616456D03*
X408700Y1603500D03*
Y1614300D03*
X408600Y1607400D03*
X411910Y1629170D03*
Y1624214D03*
X414406Y1624992D03*
Y1628392D03*
X410700Y1658460D03*
Y1655310D03*
X410232Y1670244D03*
X409857Y1682767D03*
X429535Y49388D03*
X430655Y58677D03*
X429050Y117491D03*
X430980Y132672D03*
X435340Y122196D03*
X428889Y121515D03*
X428883Y131015D03*
X429780Y149373D03*
Y157466D03*
Y161466D03*
X433695Y214862D03*
X429395Y232562D03*
X426295Y227862D03*
X422210Y221452D03*
X421200Y232562D03*
X423145Y227862D03*
X429395Y240562D03*
X429702Y290763D03*
X425720Y319492D03*
X425249Y338061D03*
X432380Y346522D03*
X422420Y338162D03*
X432006Y363644D03*
X431503Y376642D03*
X431781Y379201D03*
X434006Y365203D03*
X431596Y389604D03*
X433596Y391163D03*
X431920Y405288D03*
X431462Y402729D03*
X424980Y439462D03*
X431570Y435512D03*
X427790Y500862D03*
X427880Y506442D03*
X434343Y504233D03*
Y509733D03*
Y498733D03*
X428510Y515842D03*
X434343Y515233D03*
Y526233D03*
Y520733D03*
X431220Y518133D03*
Y523362D03*
X434620Y535762D03*
X434343Y542733D03*
X434320Y540153D03*
X434343Y547769D03*
Y552769D03*
X436822Y1161570D03*
Y1153370D03*
X431722D03*
Y1161570D03*
X434272Y1153370D03*
Y1161570D03*
X421960D03*
Y1153370D03*
X436822Y1170070D03*
X431722D03*
X434272D03*
X421960Y1169597D03*
X422148Y1248937D03*
X424698Y1248997D03*
X422088Y1251507D03*
X421805Y1256821D03*
X422028Y1254107D03*
X424458Y1256717D03*
X424578Y1254167D03*
X424638Y1251567D03*
X421805Y1259321D03*
X424398Y1259287D03*
X436068Y1248967D03*
X435828Y1256687D03*
X435948Y1254137D03*
X436008Y1251537D03*
X435768Y1259257D03*
X421805Y1261821D03*
X421817Y1264328D03*
X421795Y1267158D03*
X424345Y1267218D03*
X424380Y1264594D03*
X424388Y1261897D03*
X435715Y1267188D03*
X435720Y1264564D03*
X435708Y1261857D03*
X430999Y1286758D03*
X423229D03*
X426229D03*
X433999D03*
X432195Y1303319D03*
Y1305919D03*
X425299Y1303480D03*
X426649Y1305980D03*
X427899Y1303480D03*
X425299Y1295680D03*
X427899D03*
X432195Y1295519D03*
Y1298119D03*
X427899Y1298280D03*
X425299D03*
X432195Y1300719D03*
X427899Y1300880D03*
X425299D03*
X432195Y1308519D03*
X432063Y1317092D03*
Y1319592D03*
X428525Y1321691D03*
X426325Y1323091D03*
X424259Y1324821D03*
X428525Y1324591D03*
X434983Y1335924D03*
X431578Y1332560D03*
X432628Y1327845D03*
X435179Y1325373D03*
X424259Y1327721D03*
X426425Y1326091D03*
X428525Y1327491D03*
X430320Y1383862D03*
X436780Y1387387D03*
X427474Y1405289D03*
X434974D03*
Y1412789D03*
X427474Y1420289D03*
X434974D03*
X433539Y1430613D03*
X433897Y1434670D03*
X427546Y1443411D03*
X433954Y1439029D03*
X424146Y1443411D03*
X436920Y1541562D03*
X422566Y1550046D03*
X435396Y1551810D03*
X432996Y1558322D03*
X434430Y1567562D03*
X424570Y1579466D03*
X423958Y1600306D03*
X428099Y1586282D03*
X435240Y1609200D03*
X433383Y1602629D03*
X428941Y1606441D03*
X424800Y1616600D03*
X436840Y1632682D03*
X436880Y1622442D03*
X430015Y1626608D03*
X433670Y1639562D03*
X426728Y1636495D03*
X432895Y1737108D03*
X449535Y49388D03*
X451418Y78782D03*
X450380Y104647D03*
X453028Y154864D03*
X452500Y213362D03*
Y222362D03*
X442265Y290939D03*
X445964Y314234D03*
X439120Y314562D03*
X448220Y319862D03*
X446000Y339362D03*
X450400Y338812D03*
X455000Y340362D03*
X445944Y359053D03*
X451062Y397262D03*
X447490Y409052D03*
X449420Y424162D03*
X443744Y452462D03*
X451520Y475837D03*
X437520Y484837D03*
X447520D03*
X442853Y542519D03*
X451320Y533562D03*
X442853Y547519D03*
X448276Y1161570D03*
X445776D03*
X443276D03*
X445776Y1153370D03*
X448276D03*
X443276D03*
X448276Y1170069D03*
X445776D03*
X443276D03*
X441128Y1248997D03*
X438578Y1248937D03*
X438518Y1251507D03*
X440858Y1256866D03*
X438348Y1256896D03*
X441008Y1254167D03*
X438458Y1254107D03*
X441068Y1251567D03*
X440870Y1259373D03*
X438360Y1259403D03*
X451642Y1256851D03*
X451878Y1254107D03*
X451642Y1259351D03*
X451938Y1251507D03*
X451998Y1248937D03*
X438360Y1261903D03*
X440870Y1261873D03*
Y1264373D03*
X438360Y1264403D03*
X438225Y1267158D03*
X440775Y1267218D03*
X451642Y1261851D03*
X451654Y1264358D03*
X451645Y1267158D03*
X446944Y1335928D03*
X445153Y1334095D03*
X442353Y1329329D03*
X438353Y1328591D03*
X446563Y1330819D03*
X445091Y1328361D03*
X438353Y1331647D03*
X439391Y1398266D03*
X451048Y1404914D03*
X447110Y1403812D03*
X445339Y1415731D03*
X446230Y1407722D03*
X443850Y1423404D03*
X451080Y1433740D03*
X440164Y1433982D03*
X445294Y1430415D03*
X443715Y1436052D03*
X446258Y1441606D03*
X448079Y1562177D03*
X443910Y1555602D03*
X440019Y1576809D03*
X442128Y1574879D03*
X450020Y1570412D03*
X448328Y1582476D03*
X446020Y1570412D03*
X452020Y1580412D03*
X448740Y1574862D03*
X441308Y1602654D03*
X444458D03*
X437383Y1602629D03*
X442974Y1615615D03*
X447100Y1622562D03*
X447020Y1632632D03*
X451910Y1643282D03*
X437562Y1649770D03*
X442518D03*
X449940Y1647412D03*
X447090Y1647472D03*
X438340Y1652266D03*
X441740D03*
X452895Y1737108D03*
X469535Y49388D03*
X454568Y78782D03*
X462620Y120948D03*
X453346Y149864D03*
X468323Y254562D03*
X465236Y293823D03*
Y296973D03*
X467736Y312938D03*
X460300Y303662D03*
X468490Y340572D03*
X465000Y340362D03*
X453621Y359053D03*
X460800Y358962D03*
X467211Y371902D03*
X459220Y393762D03*
X463500Y383562D03*
X462720Y404762D03*
X465421Y424928D03*
Y428078D03*
X456520Y476337D03*
X461520D03*
X456520Y484837D03*
X460323Y510183D03*
X455326Y520389D03*
X453727Y518036D03*
X457196Y1161570D03*
X459696D03*
X462196D03*
X459696Y1153370D03*
X457196D03*
X462196D03*
X459696Y1170070D03*
X462196D03*
X457196D03*
X456818Y1256687D03*
X454388Y1254077D03*
X454152Y1256821D03*
X456998Y1251537D03*
X456758Y1259257D03*
X454152Y1259321D03*
X468258Y1249107D03*
X468018Y1256827D03*
X468138Y1254277D03*
X468198Y1251677D03*
X467958Y1259397D03*
X457058Y1248967D03*
X454508Y1248907D03*
X454448Y1251477D03*
X456938Y1254137D03*
X456705Y1267188D03*
X454155Y1267128D03*
X456748Y1261867D03*
X456740Y1264564D03*
X454152Y1261821D03*
X454164Y1264328D03*
X467905Y1267328D03*
X467910Y1264704D03*
X467898Y1261997D03*
X460049Y1286978D03*
X463049D03*
X469019Y1286718D03*
X458327Y1303980D03*
X460927D03*
X464427Y1305380D03*
X460927Y1306580D03*
X458327D03*
Y1301380D03*
X460927D03*
X464427Y1300180D03*
Y1302780D03*
X458327Y1296180D03*
X460927D03*
X464427D03*
X458327Y1298780D03*
X460927D03*
X464423Y1308519D03*
X464191Y1317092D03*
Y1319592D03*
X458453Y1323091D03*
X460653Y1321691D03*
Y1324591D03*
X456387Y1324821D03*
X464738Y1333085D03*
X467644Y1335981D03*
X464191Y1327793D03*
X467307Y1325373D03*
X458553Y1326091D03*
X460653Y1327491D03*
X456387Y1327721D03*
X465749Y1401238D03*
X459550Y1401348D03*
X465947Y1398355D03*
X459321Y1393009D03*
X455576Y1409125D03*
Y1417125D03*
X455602Y1412334D03*
X455576Y1420625D03*
Y1427632D03*
Y1424125D03*
X454450Y1433580D03*
X456619Y1431189D03*
X463140Y1451562D03*
X463207Y1547543D03*
X453595Y1551470D03*
X459520Y1546962D03*
X466905Y1567847D03*
X456961Y1559697D03*
X456020Y1580412D03*
X464020D03*
X462079Y1572177D03*
X460020Y1580412D03*
X457220Y1584020D03*
X454661Y1596755D03*
X464160Y1587122D03*
X460200Y1589900D03*
X459779Y1609235D03*
X456510Y1614472D03*
X469488Y1607362D03*
X458414Y1624994D03*
Y1629950D03*
X460910Y1629172D03*
Y1625772D03*
X468040Y1654807D03*
Y1651657D03*
X478240Y55935D03*
Y66575D03*
Y61129D03*
X481880Y147069D03*
X481246Y161364D03*
X475500Y212685D03*
X470900Y234787D03*
X472800Y299462D03*
X478995Y293787D03*
X484800Y307362D03*
X476740Y309272D03*
X479740Y300202D03*
X482720Y360862D03*
X475508Y359266D03*
X476585Y370727D03*
X472720Y391362D03*
X479379Y452445D03*
X479169Y484696D03*
X474169D03*
X484169D03*
X474044Y503725D03*
X473870Y506622D03*
X474220Y572782D03*
X471940Y597532D03*
X478510Y602942D03*
X483030Y1153370D03*
Y1161570D03*
X473698D03*
X471198D03*
X473698Y1153370D03*
X471198D03*
X483030Y1170070D03*
X473698D03*
X471198D03*
X473318Y1249137D03*
X470768Y1249077D03*
X473035Y1256866D03*
X470525Y1256896D03*
X473198Y1254307D03*
X470648Y1254247D03*
X473258Y1251707D03*
X470708Y1251647D03*
X473047Y1259373D03*
X470537Y1259403D03*
X484098Y1248997D03*
X483819Y1256851D03*
X483978Y1254167D03*
X484038Y1251567D03*
X483819Y1259351D03*
X472965Y1267358D03*
X470415Y1267298D03*
X470537Y1261903D03*
X473047Y1261873D03*
Y1264373D03*
X470537Y1264403D03*
X483819Y1261851D03*
X483831Y1264358D03*
X483745Y1267218D03*
X474509Y1286848D03*
X481509D03*
X477509D03*
X484509D03*
X477162Y1334095D03*
X478909Y1336038D03*
X474481Y1329329D03*
X470481Y1328591D03*
X478691Y1330819D03*
X477219Y1328361D03*
X470481Y1331647D03*
X483560Y1401712D03*
X475285Y1395402D03*
X474983Y1400385D03*
X485141Y1405430D03*
X485236Y1417844D03*
X481997Y1409955D03*
X470987Y1409965D03*
X484921Y1413246D03*
X470890Y1435838D03*
X482741Y1438698D03*
X478308Y1439986D03*
X482742Y1441312D03*
X478449Y1448158D03*
X482633Y1449091D03*
Y1446091D03*
X470111Y1548269D03*
X483348Y1548062D03*
X475110Y1548112D03*
X480848Y1548120D03*
X472220Y1626732D03*
X472210Y1618626D03*
X485150Y1624942D03*
X472210Y1622735D03*
X477905Y1663242D03*
X477835Y1673462D03*
X477905Y1667242D03*
X477835Y1677462D03*
Y1685462D03*
X472895Y1737108D03*
X489535Y49347D03*
X488748Y72264D03*
X497002Y88167D03*
X499580Y78442D03*
X489730Y76132D03*
X498330Y96112D03*
X501540Y105152D03*
X498730Y128592D03*
X498630Y140492D03*
X500925Y231262D03*
X489980Y250512D03*
X499096Y252462D03*
X498636Y293123D03*
X489091Y293787D03*
X498636Y296273D03*
X495136Y305398D03*
X501136Y312238D03*
X486861Y309398D03*
X492074Y300306D03*
X486861Y305398D03*
X486710Y313582D03*
X490720Y360862D03*
Y368862D03*
X492970Y409252D03*
X502070Y427937D03*
X488169Y475696D03*
X498169Y484696D03*
X488169D03*
X494193Y550447D03*
X486500Y556212D03*
X491043Y550447D03*
X486608Y1248967D03*
X489158Y1249027D03*
X486329Y1256821D03*
X486488Y1254137D03*
X488918Y1256747D03*
X489038Y1254197D03*
X486548Y1251537D03*
X489098Y1251597D03*
X486329Y1259321D03*
X488858Y1259317D03*
X500228Y1259237D03*
X486329Y1261821D03*
X486341Y1264328D03*
X488840Y1264624D03*
X488848Y1261927D03*
X488805Y1267248D03*
X486255Y1267188D03*
X500138Y1269637D03*
X500150Y1272344D03*
X500198Y1267037D03*
Y1264467D03*
X500168Y1261807D03*
X500150Y1275224D03*
X490759Y1291978D03*
X500150Y1278104D03*
X496451Y1306345D03*
X489555Y1303480D03*
X492155D03*
X490905Y1305980D03*
X492155Y1300880D03*
X489555D03*
X495309Y1300058D03*
X498309D03*
X496220Y1322440D03*
X496451Y1316745D03*
Y1308945D03*
Y1314145D03*
Y1311545D03*
X492878Y1322618D03*
X490678Y1324018D03*
X496319Y1330493D03*
Y1333043D03*
X499435Y1338799D03*
X488539Y1325772D03*
X492878Y1325518D03*
X488539Y1328672D03*
X490778Y1327018D03*
X492878Y1328418D03*
X499458Y1349468D03*
X496319Y1341264D03*
X499818Y1385027D03*
X499859Y1393027D03*
X491156Y1438713D03*
X499541Y1438698D03*
X491142Y1441312D03*
X499542D03*
X491089Y1446091D03*
Y1449091D03*
X499489D03*
Y1446091D03*
X487340Y1641352D03*
X489230Y1643592D03*
X492895Y1737108D03*
X517914Y42257D03*
X517902Y49194D03*
X510815D03*
X517902Y69508D03*
X510815D03*
X503100Y78402D03*
X510030Y78412D03*
X504980Y101752D03*
X516236Y92948D03*
X513586Y92799D03*
X517290Y104252D03*
X503270Y128592D03*
X507320D03*
X503290Y140492D03*
X507360D03*
X515690Y147852D03*
X512500Y209862D03*
X504075Y231262D03*
X512500Y223362D03*
X508000Y237862D03*
Y241862D03*
X503040Y287928D03*
X505900Y311562D03*
X502239Y315404D03*
X510740Y332592D03*
X510720Y360862D03*
X502720D03*
X506720Y368862D03*
X509720Y390362D03*
X505720Y398362D03*
X502260Y397742D03*
X511320Y437962D03*
X513444Y457522D03*
Y473281D03*
X503169Y475671D03*
X514425Y489112D03*
Y495112D03*
X509493Y539819D03*
X516970Y592942D03*
X513025Y615742D03*
X504135Y615612D03*
X505398Y1259377D03*
X502858Y1259257D03*
X502718Y1271417D03*
X505218Y1271447D03*
X505290Y1267254D03*
X505338Y1261947D03*
X505278Y1264547D03*
X502750Y1267134D03*
X502798Y1261827D03*
X502738Y1264427D03*
X502718Y1274114D03*
X505218Y1274144D03*
X515898Y1271447D03*
X515950Y1274144D03*
X505220Y1280054D03*
X502718Y1276994D03*
X505218Y1277024D03*
X502680Y1280054D03*
X515960D03*
X515950Y1277024D03*
X517989Y1300108D03*
X514989D03*
X509382Y1347521D03*
X511149Y1349468D03*
X506609Y1342755D03*
X502609Y1342017D03*
X510819Y1344245D03*
X509347Y1341787D03*
X502609Y1345073D03*
X505055Y1387601D03*
Y1382301D03*
X505018Y1385027D03*
X502418D03*
X505055Y1396001D03*
Y1398601D03*
Y1390201D03*
X508881Y1404880D03*
X506181D03*
X505059Y1393027D03*
X502459D03*
X503559Y1405025D03*
X508775Y1409889D03*
X508828Y1407385D03*
X508802Y1412420D03*
X506075Y1409889D03*
X506128Y1407385D03*
X503572Y1407539D03*
Y1415039D03*
Y1412539D03*
X506102Y1412420D03*
X503572Y1410039D03*
X509246Y1420002D03*
X508001Y1438669D03*
X507942Y1441312D03*
X507964Y1448979D03*
Y1445979D03*
X512895Y1737108D03*
X518606Y23797D03*
X529720Y30792D03*
X525000Y42257D03*
X524988Y49194D03*
X532075Y69508D03*
Y57894D03*
X524988Y69508D03*
X533915Y59822D03*
X527520Y69633D03*
X528590Y72922D03*
X529239Y99997D03*
Y92911D03*
X528400Y104225D03*
X518450Y101602D03*
X527310Y98147D03*
Y94747D03*
X528400Y114275D03*
X527823Y131802D03*
X527160Y129243D03*
X527823Y149802D03*
X527278Y164726D03*
X529507Y202448D03*
X522337Y202404D03*
X532533Y299500D03*
X529533D03*
X523682Y307541D03*
Y304541D03*
X523660Y323222D03*
X527720Y360862D03*
X523670Y368892D03*
X529720Y390362D03*
X521720Y398362D03*
X532650Y446396D03*
X518735Y452442D03*
X521885D03*
X533410Y475932D03*
X525820Y473662D03*
X524425Y489112D03*
Y495112D03*
X519520Y484027D03*
X522805Y482155D03*
X531258Y505473D03*
X526852Y511331D03*
X527042Y505830D03*
X521561Y505969D03*
Y500469D03*
Y511469D03*
X524220Y505862D03*
Y500362D03*
Y511362D03*
X526853Y516817D03*
X521561Y516969D03*
Y522469D03*
X524220Y516862D03*
X524720Y525293D03*
Y519743D03*
X521561Y527969D03*
Y539819D03*
X524920D03*
X521561Y550819D03*
X523699Y571545D03*
X526280Y569122D03*
X528500Y566722D03*
X523890Y592387D03*
X520710Y592552D03*
X531472Y579750D03*
X521118Y1273097D03*
X518488Y1271477D03*
X521058Y1275667D03*
X518490Y1274144D03*
X521058Y1278277D03*
X521020Y1280974D03*
X518500Y1280054D03*
X518490Y1277024D03*
X530398Y1288557D03*
X530548Y1283377D03*
X530428Y1285947D03*
X530410Y1291254D03*
X532558Y1289967D03*
X532618Y1287367D03*
X532678Y1284797D03*
X530450Y1297014D03*
Y1294134D03*
X532570Y1295554D03*
Y1298434D03*
Y1292674D03*
X523033Y1319406D03*
X527645Y1326076D03*
X528579Y1329143D03*
X528377Y1335982D03*
X525008Y1336287D03*
X520643Y1338247D03*
X522809Y1339517D03*
X522783Y1334882D03*
X520643Y1341147D03*
X528579Y1342143D03*
Y1344743D03*
X528447Y1353316D03*
Y1355816D03*
X524892Y1341462D03*
X522818Y1342930D03*
X528929Y1364212D03*
X531563Y1361597D03*
X532895Y1737108D03*
X548609Y32500D03*
X539720Y30792D03*
X534720D03*
X546248Y69508D03*
X539161D03*
Y57894D03*
X537315Y59822D03*
X541002Y71436D03*
X544402D03*
X546234Y77443D03*
X548070Y79372D03*
X542620Y103352D03*
X542460Y99172D03*
X549610Y120682D03*
X537360Y120522D03*
X539475Y118772D03*
X550545Y147302D03*
X547395D03*
X540460Y200392D03*
X542798Y202646D03*
X544390Y236512D03*
X550390Y231742D03*
X542050Y231722D03*
X539639Y271972D03*
X537720Y278212D03*
X535630Y306602D03*
X547420Y306862D03*
X544920D03*
X535720Y360862D03*
X547810Y414472D03*
X549670Y419892D03*
X543035Y441005D03*
X542870Y438320D03*
X548464Y456534D03*
X548780Y475932D03*
X538120Y463137D03*
X548550Y480382D03*
X546210Y519642D03*
X535290Y572932D03*
X541820Y575130D03*
X541722Y568054D03*
X543450Y590262D03*
X537730Y577440D03*
X547020Y590332D03*
X550320Y583362D03*
X536626Y590500D03*
X537560Y598102D03*
X537648Y1290037D03*
X535058Y1290007D03*
X535148Y1287397D03*
X543660Y1302934D03*
X541100D03*
X538560D03*
X535110Y1292704D03*
Y1295584D03*
Y1298464D03*
X537650Y1292704D03*
X540210D03*
X537650Y1298464D03*
Y1295584D03*
X540210Y1298464D03*
Y1295584D03*
X536020Y1302904D03*
X544813Y1322668D03*
X542213D03*
X538293D03*
X535693D03*
X542256Y1369935D03*
X538737Y1365553D03*
X534737Y1364815D03*
X542947Y1367043D03*
X541475Y1364585D03*
X534737Y1367871D03*
X562780Y32842D03*
X554720Y32862D03*
X564430Y45132D03*
X554983Y45312D03*
X560421Y69508D03*
X553335D03*
X553320Y77443D03*
X551470Y79372D03*
X559000Y102862D03*
X561000Y98862D03*
X564988Y118670D03*
X555545Y134340D03*
X552395D03*
X566500Y125097D03*
X551231Y122671D03*
X565500Y145252D03*
X555220Y164787D03*
X555545Y156462D03*
X555195Y184862D03*
Y171862D03*
X553657Y193862D03*
X554872Y196635D03*
X559400Y201162D03*
X557248Y198909D03*
X564600Y202662D03*
X552489Y212022D03*
X553402Y231292D03*
X564944Y252173D03*
X552089Y253202D03*
Y257202D03*
X562461Y272161D03*
X553536Y307527D03*
X566730Y300992D03*
X563790Y331846D03*
X561290D03*
X558790D03*
X562200Y419412D03*
X559300Y414112D03*
X559730Y434772D03*
X557829Y454479D03*
X558220Y459362D03*
X563281Y543113D03*
X560640Y540613D03*
X566140Y554972D03*
Y551472D03*
X559927Y548457D03*
X556820Y570462D03*
X557430Y583572D03*
X558933Y1323658D03*
X563634Y1334315D03*
X561034D03*
X558933Y1326258D03*
X556563Y1337918D03*
X553963D03*
X558933Y1328938D03*
X556563Y1335318D03*
Y1332718D03*
X558933Y1331538D03*
X553963Y1335318D03*
Y1332718D03*
X555313Y1340418D03*
X555372Y1343037D03*
X561070Y1346174D03*
X554837Y1359315D03*
X557037Y1363715D03*
Y1357915D03*
Y1360815D03*
X554937Y1362315D03*
X552771Y1361045D03*
Y1363945D03*
X555057Y1449395D03*
X552895Y1737108D03*
X572500Y32862D03*
X568500D03*
X578620Y45112D03*
X581500Y41862D03*
X567507Y45869D03*
X577300Y66682D03*
X577880Y75442D03*
X579080Y119402D03*
X567673Y130542D03*
X573115Y161232D03*
X581120Y155062D03*
X568245Y167112D03*
X579481Y202378D03*
Y198378D03*
X579170Y190092D03*
X579481Y210378D03*
X568149Y217916D03*
X580712Y215877D03*
X579481Y206378D03*
X581645Y233362D03*
X569668Y229812D03*
X578711Y230109D03*
X579245Y221362D03*
X567730Y225362D03*
Y221362D03*
X581755Y236978D03*
X578509Y265132D03*
X575359D03*
X582510Y296657D03*
X569880Y300992D03*
X580400Y302402D03*
X577480Y303822D03*
X582510Y304052D03*
Y311571D03*
X567630Y331958D03*
X574800Y322462D03*
X582436Y361032D03*
X572360Y351962D03*
X575050Y383602D03*
X580370Y383670D03*
X569490Y437600D03*
X570760Y451710D03*
X567320Y454962D03*
Y459962D03*
Y457462D03*
X578920Y466462D03*
X583045Y488212D03*
X571990Y501046D03*
X568840D03*
X568520Y504162D03*
Y506662D03*
X578925Y516846D03*
X571700Y552200D03*
X571627Y548124D03*
X569050Y578292D03*
X572057Y577242D03*
X573849Y1346968D03*
X569849D03*
X571555Y1352487D03*
X570645Y1361358D03*
X576220Y1423862D03*
X571620Y1424492D03*
X572895Y1737108D03*
X584950Y54842D03*
X596840Y45152D03*
X593925Y49193D03*
X586600Y60602D03*
X592307Y94262D03*
X597287D03*
X594720Y97220D03*
X591395Y132142D03*
X588245D03*
X598410Y124102D03*
X598390Y126802D03*
X595220Y140922D03*
X588000D03*
X592710Y156342D03*
X593248Y159480D03*
X589690Y161732D03*
X596581Y184849D03*
X590337Y177604D03*
X592220Y173862D03*
X596795Y179287D03*
X590281Y180698D03*
X598760Y203712D03*
X593966Y229965D03*
X584795Y233362D03*
X591310Y219582D03*
X592220Y249362D03*
X592039Y252202D03*
X588577Y285862D03*
X590350Y294402D03*
X591727Y285862D03*
X586820Y314662D03*
X599620Y314762D03*
X595520Y314862D03*
X583820Y314662D03*
X597820Y317062D03*
X592920Y326362D03*
X590820Y330962D03*
X590720Y327862D03*
Y324582D03*
X590470Y319192D03*
X583685Y363271D03*
X586185D03*
X591839Y426112D03*
X591720Y433937D03*
X595520Y439762D03*
X599080Y448062D03*
X584100Y477952D03*
X592520Y467662D03*
X593545Y488212D03*
X599645Y479862D03*
X598661Y486922D03*
X587100Y493842D03*
X592400Y479162D03*
X591070Y504900D03*
X594090Y505107D03*
Y501957D03*
X587100Y496342D03*
X594240Y511953D03*
X591425Y522337D03*
X591500Y516862D03*
X593675Y534702D03*
X596880Y534812D03*
X589989Y745475D03*
X592340Y744624D03*
X598693Y742072D03*
X607890Y34389D03*
X615420Y42342D03*
X605060Y42402D03*
X615185Y49193D03*
X612822Y43232D03*
X615185Y69508D03*
X603374D03*
X615220Y76862D03*
X615170Y73812D03*
X601220Y73862D03*
Y76862D03*
X601050Y100008D03*
X617585Y97257D03*
X613020Y94162D03*
X603880Y93902D03*
X600220Y96862D03*
X610104Y119342D03*
X614384D03*
X602306Y143077D03*
X612670Y142872D03*
X606040Y153432D03*
X606190Y144002D03*
X602430Y153862D03*
X612520Y154812D03*
X615572Y173942D03*
X615573Y181984D03*
Y179484D03*
X615572Y176442D03*
X614531Y200378D03*
X611030Y188372D03*
X611381Y200378D03*
X603340Y208142D03*
X614531Y209878D03*
X609456Y204994D03*
X611381Y209878D03*
X606719Y254966D03*
X611310Y266272D03*
X614200Y265792D03*
X609844Y330407D03*
X609040Y317282D03*
X615635Y317637D03*
X608830Y374302D03*
X605830Y402782D03*
X605220Y416362D03*
X610720Y436362D03*
X600800Y430900D03*
X614220Y436362D03*
X610720Y442862D03*
X614220D03*
X600351Y461862D03*
X614220Y452862D03*
Y447862D03*
X602910Y461862D03*
X610720Y457862D03*
X614220D03*
X610720Y452862D03*
X614220Y467862D03*
Y472862D03*
Y477862D03*
X610820Y472862D03*
X605469Y467562D03*
X610720Y462862D03*
X614220D03*
X603779Y486922D03*
X601220D03*
X600645Y504362D03*
X606200Y510862D03*
Y514862D03*
X611870Y512560D03*
X606220Y517762D03*
X614086Y537624D03*
X607328Y537481D03*
X610797Y537528D03*
X614000Y550800D03*
X607720Y550862D03*
X610720D03*
X603317Y738415D03*
X614660Y739553D03*
X600460Y744912D03*
X613047Y741492D03*
X602027Y761445D03*
X612407Y769485D03*
X612895Y1737108D03*
X616675Y31777D03*
X624633Y49193D03*
X629820Y42562D03*
Y45062D03*
X619562Y49193D03*
X624140Y46672D03*
X622271Y44782D03*
X629000Y67362D03*
X628590Y58622D03*
X622271Y57952D03*
X631546Y85024D03*
X618460Y119342D03*
X626699Y119182D03*
X630951D03*
X624610Y142842D03*
X624520Y154622D03*
X631300Y167872D03*
X631290Y153702D03*
X615970Y161522D03*
X628195Y178414D03*
X628194Y170372D03*
X628195Y175914D03*
X628194Y172872D03*
X630818Y191248D03*
X625862D03*
X620030Y188782D03*
X628730Y216472D03*
X631730D03*
X628730Y220472D03*
Y224472D03*
X631730Y220472D03*
Y224472D03*
X630795Y236862D03*
X621740Y265952D03*
X618470Y265732D03*
X629564Y253127D03*
X623150Y273172D03*
X621060Y271066D03*
X625800Y311912D03*
X630220Y314362D03*
X628294Y317007D03*
X623365Y316742D03*
X631146Y317768D03*
X623580Y336429D03*
X619100Y374638D03*
X621720Y373362D03*
X628500Y402362D03*
X624220Y411362D03*
X629220D03*
X625500Y421362D03*
X629220D03*
Y426362D03*
X629248Y436972D03*
X628900Y431050D03*
X625900D03*
X629220Y442862D03*
X622220D03*
X617220Y436362D03*
X622220Y452862D03*
Y447862D03*
X629220Y457862D03*
X622220D03*
X629220Y452862D03*
Y447862D03*
X626390Y467882D03*
X626210Y478002D03*
X626310Y472902D03*
X629220Y472862D03*
Y477862D03*
Y467862D03*
Y462862D03*
X622220D03*
X622520Y467862D03*
X629220Y487310D03*
Y482862D03*
X626720Y482880D03*
X629480Y508862D03*
X629920Y516652D03*
X623000Y546900D03*
X629220Y643462D03*
X626720D03*
X617252Y739354D03*
X626207Y747585D03*
X623497Y748235D03*
X626017Y745083D03*
X620870Y762072D03*
X617940Y763552D03*
X630417Y757135D03*
X618114Y1258470D03*
X637220Y31462D03*
X646440Y43632D03*
X632463Y43302D03*
X645150Y69508D03*
X645350Y60612D03*
X638500Y57362D03*
X635000D03*
X645330Y72972D03*
X647220Y96929D03*
X632640Y107532D03*
X637500Y110362D03*
X640130Y166362D03*
X642480Y184862D03*
X643170Y171362D03*
X645109Y249202D03*
Y260202D03*
X645876Y296231D03*
X633138Y296766D03*
X643800Y294327D03*
Y298297D03*
X645528Y308623D03*
X645807Y304291D03*
X643800Y306547D03*
Y302247D03*
X645990Y314482D03*
X643800Y310962D03*
X633350Y314362D03*
X647200Y354300D03*
X647100Y357372D03*
X632620Y389862D03*
X645925Y389937D03*
X647700Y399162D03*
X643500Y400962D03*
X643940Y411482D03*
X644220Y426362D03*
X640720Y418862D03*
X644220Y421362D03*
X637195D03*
X647420Y434162D03*
X640720Y431362D03*
X644000Y438862D03*
X644220Y431362D03*
X638250Y439250D03*
X637220Y431362D03*
X643736Y457214D03*
X644220Y452862D03*
X640820Y457902D03*
X637220Y452862D03*
X640920Y447862D03*
X644220D03*
X637195Y457862D03*
X637220Y467862D03*
Y472862D03*
Y477862D03*
X644245Y472862D03*
X644220Y467862D03*
Y477862D03*
Y462862D03*
X640798Y472934D03*
X637220Y462862D03*
X640820Y467862D03*
X644245Y482862D03*
X645220Y504362D03*
X646815Y517974D03*
X637020Y522362D03*
X642630Y517870D03*
X640130D03*
X633147Y758595D03*
X641057Y1648659D03*
X647725Y1643719D03*
X645407Y1660425D03*
X636702Y1677610D03*
X641386Y1687283D03*
X639745Y1714362D03*
X646225Y1708169D03*
X648290Y1720052D03*
X639745Y1726362D03*
Y1722362D03*
Y1718362D03*
X632895Y1737108D03*
X651943Y33535D03*
X661534Y41748D03*
X661550Y45133D03*
X654464D03*
X661681Y49193D03*
X654595D03*
X663543Y43328D03*
X656950Y59012D03*
X657165Y79131D03*
X652153Y98105D03*
X652680Y89712D03*
X651579Y102703D03*
X659000Y89262D03*
X651980Y133822D03*
X662498Y124960D03*
X650790Y144982D03*
Y149871D03*
Y140699D03*
X662880Y149912D03*
Y146912D03*
X662560Y214152D03*
X662780Y210362D03*
Y205362D03*
Y207862D03*
X659880Y210762D03*
Y205762D03*
Y208262D03*
X650705Y270947D03*
X662891Y357442D03*
X662680Y354362D03*
X651520Y378662D03*
X660690Y408162D03*
X660720Y404362D03*
X658720Y399862D03*
X652195Y457862D03*
X655820Y467662D03*
X663000Y489500D03*
X663014Y493860D03*
X655220Y486862D03*
X653800Y498740D03*
X663720Y523806D03*
X661743Y521166D03*
X657734Y528255D03*
X652577Y1000775D03*
X662282Y1386432D03*
X653690Y1392362D03*
X653761Y1396300D03*
X663187Y1395170D03*
Y1397720D03*
X666303Y1403476D03*
X663687Y1407279D03*
X654540Y1427605D03*
Y1424205D03*
X661100Y1451012D03*
X662660Y1548120D03*
X663410Y1553982D03*
X664590Y1631620D03*
X663043Y1647557D03*
X655307Y1647436D03*
X663097Y1642667D03*
X663118Y1659557D03*
X663145Y1664862D03*
X656725Y1657619D03*
Y1660769D03*
X663118Y1655557D03*
X663043Y1651557D03*
X663145Y1676862D03*
Y1672862D03*
Y1668862D03*
X656973Y1698727D03*
X652712Y1686275D03*
X653420Y1698662D03*
X663645Y1722862D03*
X652895Y1737108D03*
X680200Y39062D03*
X675854Y49193D03*
X672005Y44119D03*
X669004Y41698D03*
X668800Y45262D03*
X668768Y49193D03*
X666943Y43328D03*
X670612Y47264D03*
X674012D03*
X666406Y69508D03*
X675225Y58108D03*
X678050Y58157D03*
X673750Y77692D03*
X673987Y87662D03*
X677790Y104880D03*
X674145Y113487D03*
X677978Y119668D03*
Y115668D03*
X675560Y117120D03*
X665650Y147692D03*
X673690Y200672D03*
X673300Y211332D03*
X667020Y225762D03*
X674731Y359924D03*
X680600Y364282D03*
Y375462D03*
X673220Y388362D03*
X677295Y404362D03*
X677195Y408262D03*
X675295Y399862D03*
X670720D03*
X668695Y408362D03*
Y404262D03*
X665870Y433942D03*
X680220Y495887D03*
X670220Y503837D03*
X675220D03*
X680220D03*
X675220Y521862D03*
Y516852D03*
X670720Y521862D03*
Y516862D03*
X680220Y530362D03*
X671607Y742835D03*
X673617Y744735D03*
X669700Y746626D03*
X677887Y742121D03*
X669778Y759929D03*
X670037Y1336396D03*
X664987D03*
X667487D03*
X664987Y1338896D03*
X667487D03*
X670037D03*
Y1333896D03*
X664987D03*
X667487D03*
X664987Y1348896D03*
X667487D03*
X664987Y1346396D03*
X667487D03*
X664987Y1343896D03*
Y1341396D03*
X667487D03*
Y1343896D03*
X670037Y1341396D03*
Y1343896D03*
Y1346396D03*
Y1348896D03*
X673517Y1360815D03*
X676017D03*
X668096Y1360822D03*
X678517Y1360815D03*
X664782Y1383832D03*
Y1381232D03*
Y1378632D03*
Y1386432D03*
X666425Y1414200D03*
X676312Y1411554D03*
X673477Y1409386D03*
X669477Y1406694D03*
X677619Y1408887D03*
X675876Y1406619D03*
X669477Y1409415D03*
X674149Y1434149D03*
X671149D03*
X668649D03*
X674149Y1426149D03*
Y1431149D03*
Y1428649D03*
X671149Y1426149D03*
X668649D03*
X671149Y1431149D03*
X668649Y1428649D03*
Y1431149D03*
X671149Y1428649D03*
X677319Y1428359D03*
Y1433359D03*
Y1430859D03*
X667926Y1547018D03*
X665410Y1548180D03*
X679192Y1564252D03*
X679207Y1560482D03*
X678877Y1566798D03*
X678610Y1582154D03*
X666560Y1581000D03*
X678515Y1573910D03*
X666600Y1584900D03*
X678900Y1595400D03*
X678771Y1585945D03*
X666700Y1595500D03*
X678900Y1589800D03*
X666700Y1591900D03*
X678900Y1592600D03*
X666700Y1588500D03*
X679640Y1617520D03*
Y1614000D03*
X679270Y1604040D03*
X675710Y1620320D03*
X671112Y1639962D03*
X671290Y1646320D03*
X676648Y1657380D03*
X668695Y1662235D03*
X671620Y1670862D03*
Y1668303D03*
X677940Y1670110D03*
X678490Y1695660D03*
X674195Y1708362D03*
Y1712362D03*
X669120Y1718862D03*
X674195Y1728362D03*
X672895Y1737108D03*
X674195Y1732362D03*
X689940Y38952D03*
X696838Y45112D03*
X686854Y43701D03*
X692380Y43532D03*
X694751Y70212D03*
X685780Y70022D03*
X682941Y69982D03*
X685968Y58157D03*
X694400D03*
X681980D03*
X690510Y59132D03*
X696700Y72462D03*
X692389Y72692D03*
X687664Y73202D03*
X687050Y79212D03*
X685230Y76952D03*
X683820Y79192D03*
X682890Y72642D03*
X696370Y78512D03*
X696727Y81552D03*
Y84052D03*
X681053Y104668D03*
X695720Y102162D03*
X694220Y104862D03*
X684953Y104968D03*
X687030Y113090D03*
X694390Y133682D03*
X684520Y152482D03*
X688520D03*
X692520D03*
X686760Y222912D03*
X685600Y364282D03*
X690600D03*
X695600D03*
X685600Y375462D03*
X690600D03*
X695600D03*
X683500Y381200D03*
X688220Y388362D03*
X685210Y388852D03*
X694920Y388797D03*
X687500Y399402D03*
X692330Y388751D03*
X692402Y391250D03*
X697220Y404362D03*
X697120Y408262D03*
X695220Y399862D03*
X685270Y408362D03*
Y404262D03*
X692400Y404682D03*
X694720Y491962D03*
X690720D03*
X683320Y490662D03*
X690580Y482992D03*
X694510Y482942D03*
X686120Y481862D03*
X685220Y508862D03*
X690220Y506362D03*
X685220Y503837D03*
X690220Y508882D03*
X695257Y503847D03*
X690220Y516852D03*
X685220D03*
X690220Y519662D03*
X695220D03*
X689720Y530862D03*
X695220Y530662D03*
X684357Y742345D03*
X683457Y745175D03*
X692784Y1298845D03*
X684555Y1338896D03*
X689605Y1336396D03*
Y1338896D03*
X687105Y1336396D03*
X684555D03*
X687105Y1338896D03*
X689605Y1333896D03*
X687105D03*
X684555D03*
X689605Y1348896D03*
X687105D03*
X689605Y1346396D03*
X687105D03*
X684555Y1341396D03*
Y1343896D03*
Y1346396D03*
Y1348896D03*
X689605Y1341396D03*
Y1343896D03*
X687105Y1341396D03*
Y1343896D03*
X686426Y1360822D03*
X695022Y1361990D03*
X696462Y1386122D03*
X691351Y1380922D03*
X688751D03*
X691240Y1383522D03*
X693851D03*
Y1378322D03*
Y1380922D03*
X691351Y1378322D03*
X688751D03*
X693851Y1386122D03*
X696462Y1378322D03*
Y1383522D03*
Y1380922D03*
X696272Y1404560D03*
X691777Y1405594D03*
Y1399794D03*
X689577Y1401194D03*
X687511Y1402924D03*
X691777Y1402694D03*
X689677Y1404194D03*
X687511Y1405824D03*
X694596Y1396198D03*
X694129Y1420283D03*
X696754Y1419809D03*
X691129Y1420283D03*
X685015Y1438475D03*
X696940Y1437955D03*
X681899Y1434049D03*
Y1426049D03*
Y1431049D03*
Y1428549D03*
X694129Y1423303D03*
X691129D03*
X696694Y1427949D03*
Y1425449D03*
Y1430449D03*
X696784Y1422614D03*
X683930Y1552562D03*
Y1555062D03*
Y1557562D03*
X689875Y1577913D03*
X692026Y1580490D03*
X697122Y1632667D03*
X683592Y1634844D03*
X697197Y1644667D03*
Y1640667D03*
X697122Y1636667D03*
X689200Y1648843D03*
X689128Y1652262D03*
X692595Y1670862D03*
X687045Y1673362D03*
X701838Y45112D03*
X706370Y46782D03*
X703900Y72112D03*
X701400D03*
X700610Y57782D03*
X713000Y69662D03*
X697720Y58162D03*
X710200Y69662D03*
X706867Y58197D03*
X703100Y58157D03*
X700741Y83050D03*
X712500Y79862D03*
X710486Y77695D03*
X700500Y74862D03*
X698710Y86035D03*
X705390Y85792D03*
X703000Y84862D03*
X712433Y103308D03*
X706720Y100462D03*
X699220Y102162D03*
X702720D03*
X701220Y104862D03*
X697720D03*
X712733Y117488D03*
Y114588D03*
X712290Y106722D03*
X706673Y122762D03*
X703520Y122540D03*
X704880Y133643D03*
X700600Y125309D03*
X705800Y167788D03*
X701926Y166535D03*
X705800Y171188D03*
X701926Y178346D03*
Y184252D03*
Y172441D03*
Y190157D03*
Y196063D03*
Y201968D03*
Y207874D03*
Y213779D03*
Y219685D03*
X700600Y364282D03*
X705600D03*
X710600D03*
X709000Y354000D03*
X700600Y375462D03*
X705600D03*
X709400Y378200D03*
X713220Y378362D03*
X707220Y399362D03*
X709160Y386730D03*
X707400Y396200D03*
X713220Y399862D03*
X705195Y408362D03*
Y404262D03*
X705780Y411022D03*
X712770Y406822D03*
X705720Y488862D03*
X703220Y490362D03*
X705720Y484862D03*
X711220Y503842D03*
X705220D03*
Y508862D03*
X711220Y508882D03*
X710720Y521362D03*
X705220D03*
Y516852D03*
X698600Y530700D03*
X710940Y591172D03*
X698602Y580536D03*
X705240Y594020D03*
X702740D03*
X712060Y638542D03*
X708680Y638812D03*
X708310Y646032D03*
X704320Y645262D03*
X701917Y742865D03*
X704000Y740862D03*
X700500Y745862D03*
X703545Y745907D03*
X703755Y1290545D03*
X711720Y1286162D03*
X707720Y1290162D03*
X705720Y1286662D03*
X708795Y1303701D03*
X704795Y1294559D03*
X707320Y1301162D03*
X708137Y1336396D03*
Y1338896D03*
X703087Y1336396D03*
X705587D03*
Y1338896D03*
X703087D03*
X708137Y1333896D03*
X705587D03*
X703087D03*
Y1346396D03*
X705587D03*
X703087Y1348896D03*
X705587D03*
X708137Y1341396D03*
Y1343896D03*
X705587Y1341396D03*
X703087D03*
Y1343896D03*
X705587D03*
X708137Y1348896D03*
Y1346396D03*
X698094Y1361947D03*
X706239Y1360822D03*
X712060Y1360815D03*
X699062Y1380922D03*
Y1383522D03*
Y1378322D03*
X701662Y1380922D03*
Y1383522D03*
Y1378322D03*
X699062Y1386122D03*
X701662D03*
X701330Y1395195D03*
Y1397695D03*
X704446Y1403476D03*
X699262Y1413970D03*
X704568Y1414119D03*
X701830Y1407326D03*
X711620Y1409386D03*
X707620Y1406694D03*
Y1409660D03*
X699754Y1419809D03*
X706680Y1437535D03*
X701730Y1437855D03*
X711440Y1436905D03*
X699694Y1427949D03*
Y1425449D03*
Y1430449D03*
X699784Y1422614D03*
X702112Y1583683D03*
Y1571683D03*
Y1575683D03*
Y1579683D03*
X714162Y1574333D03*
X713052Y1579683D03*
X704497Y1598927D03*
X702112Y1587683D03*
Y1591683D03*
X713102Y1601307D03*
X714380Y1589960D03*
X702112Y1595683D03*
X712512Y1596338D03*
X711350Y1590720D03*
X711780Y1614590D03*
X704370Y1604580D03*
X709111Y1618842D03*
X705516Y1620296D03*
X710540Y1636070D03*
X697595Y1658862D03*
X704433Y1657964D03*
X697595Y1662862D03*
X697770Y1680810D03*
X702462Y1673258D03*
X697730Y1677460D03*
X717313Y-27626D03*
X714015Y-27612D03*
X720308Y-26403D03*
X723041Y-19800D03*
Y-23200D03*
X725537Y-23978D03*
Y-19022D03*
Y-13978D03*
Y-9022D03*
X714015Y-21457D03*
X717313Y-21471D03*
Y-17597D03*
X717298Y-15082D03*
X714015Y-17583D03*
X714030Y-15068D03*
X714015Y-11428D03*
X717313Y-11442D03*
X717298Y-25111D03*
X714030Y-25097D03*
X720308Y-16374D03*
X717313Y-7568D03*
X717298Y-5053D03*
X714015Y-7554D03*
X714030Y-5039D03*
X720308Y-6345D03*
X722580Y49182D03*
X728980Y39872D03*
X717320Y44062D03*
X729293Y58062D03*
X724644Y58362D03*
X719949Y58862D03*
X715990Y69662D03*
X725740Y69580D03*
X721990Y69762D03*
X718900Y69662D03*
X727700Y60562D03*
X728591Y71960D03*
X722415Y77862D03*
X718425Y77882D03*
X728090Y75132D03*
X719100Y85262D03*
X728028Y101968D03*
X728023Y98058D03*
X727518Y90984D03*
X728028Y105468D03*
X715933Y117488D03*
Y114588D03*
X728733Y132088D03*
Y129288D03*
X720433Y135088D03*
X717433D03*
X728733Y126388D03*
X719933Y124488D03*
X723133D03*
X724133Y141288D03*
X715940Y157362D03*
X718213Y159241D03*
X720633Y160788D03*
X719194Y172909D03*
X714202D03*
X719194Y177865D03*
X714202D03*
X719194Y184909D03*
X714202D03*
X719194Y189865D03*
X714202D03*
X719194Y196409D03*
X714202D03*
X719194Y201365D03*
X714202D03*
X719194Y208243D03*
X714202D03*
X719194Y213199D03*
X714202D03*
X717020Y220862D03*
X719720Y220142D03*
X727720Y356362D03*
X724897Y353887D03*
X721989Y351234D03*
X715600Y375462D03*
X718220Y388362D03*
X718720Y381892D03*
X715220Y404362D03*
X715120Y408262D03*
X723195Y408362D03*
Y404262D03*
X725220Y399862D03*
X713820Y488762D03*
Y484662D03*
X729220Y503842D03*
X723220D03*
X717220D03*
X714000Y496132D03*
X723120Y525362D03*
X728220Y521362D03*
X717220D03*
X722720D03*
X717296Y525407D03*
X723220Y516852D03*
X729220D03*
X717220D03*
X729200Y588952D03*
X729328Y583076D03*
X729295Y586113D03*
X725207Y579371D03*
X722707D03*
X715860Y585540D03*
X714320Y597462D03*
X723450Y597072D03*
X715420Y639162D03*
X719190Y646642D03*
X717720Y643262D03*
X715220D03*
X723340Y642922D03*
X714087Y745865D03*
X720697Y765862D03*
X723460Y1245632D03*
X713836Y1283689D03*
X714720Y1286162D03*
X723054Y1333896D03*
X725604D03*
X728104D03*
X725604Y1338896D03*
X723054Y1336396D03*
X725604D03*
X728104Y1338896D03*
Y1336396D03*
X723054Y1338896D03*
X725604Y1346396D03*
X728104D03*
X725604Y1348896D03*
X728104D03*
X725604Y1343896D03*
Y1341396D03*
X728104Y1343896D03*
Y1341396D03*
X723054Y1348896D03*
Y1346396D03*
Y1343896D03*
Y1341396D03*
X724969Y1360822D03*
X714560Y1360815D03*
X717060D03*
X729443Y1361224D03*
X726694Y1381583D03*
Y1378983D03*
X728044Y1384083D03*
X729294Y1381583D03*
Y1378983D03*
X725654Y1405824D03*
Y1402924D03*
X727720Y1401194D03*
X727820Y1404194D03*
X714455Y1411554D03*
X715762Y1408887D03*
X714019Y1406619D03*
X717300Y1547370D03*
X715792Y1567461D03*
X720370Y1566910D03*
X723520Y1561604D03*
X724712Y1566820D03*
X716612Y1584635D03*
X717152Y1570093D03*
X724465Y1580092D03*
X722465Y1582092D03*
X726465D03*
X718230Y1600372D03*
X724465Y1590950D03*
X722465Y1588950D03*
X726465D03*
X725378Y1614503D03*
X719770Y1614590D03*
X715780D03*
X723542Y1612702D03*
X721488Y1610945D03*
X725910Y1611900D03*
X716688Y1610055D03*
X719168Y1612016D03*
X722040Y1623970D03*
X713791Y1629816D03*
X714203Y1639776D03*
X721345Y1647300D03*
X716140Y1649895D03*
X718195Y1647300D03*
X714203Y1642926D03*
X729150Y1641690D03*
X726810Y1652430D03*
X726830Y1655380D03*
X714071Y1663842D03*
X722630Y1655740D03*
X724500Y1676500D03*
Y1680400D03*
X744987Y49062D03*
X742840Y39832D03*
X736790D03*
X745130Y69508D03*
X738043D03*
X730957D03*
X731330Y60712D03*
X745474Y57932D03*
X733642Y58062D03*
X741377Y57932D03*
X737595D03*
X732793Y71436D03*
X736193D03*
X742620Y71762D03*
X735880Y60662D03*
X730820Y84062D03*
X740819Y82362D03*
X737623Y98858D03*
X734523Y98758D03*
X735733Y111988D03*
X738600Y136600D03*
X736060Y145532D03*
X745725Y167537D03*
X734220Y238362D03*
X745685Y265322D03*
X744247Y312598D03*
X742090Y356082D03*
X735600Y351400D03*
X736220Y380787D03*
X742720Y380262D03*
X738220Y388362D03*
X742160Y396452D03*
X738220Y383862D03*
X743720Y404362D03*
X743820Y408262D03*
X745720Y399862D03*
X735220Y410842D03*
X735745Y408362D03*
Y404262D03*
X733720Y399862D03*
X740740Y473822D03*
X745220Y503842D03*
X730070Y506212D03*
X744630Y506529D03*
X735220Y503842D03*
X735430Y516862D03*
X745220Y516852D03*
X730220Y523362D03*
X740840Y521982D03*
X745220Y530362D03*
X736480Y531722D03*
X738980D03*
X733922Y531712D03*
X733117Y580071D03*
Y582571D03*
X733134Y585672D03*
X736710Y603842D03*
Y607242D03*
X739206Y608020D03*
Y603064D03*
X735620Y613862D03*
X730690Y655532D03*
X744538Y746524D03*
X737609Y744282D03*
X730889Y746834D03*
X740820Y741762D03*
X737299Y766887D03*
X737784Y1360017D03*
X730752Y1384080D03*
X731794Y1381583D03*
Y1378983D03*
X732238Y1388343D03*
X738810Y1396665D03*
X741540Y1396585D03*
X739170Y1405655D03*
X741670Y1405675D03*
X729920Y1405594D03*
X732226Y1396212D03*
X729920Y1399794D03*
Y1402694D03*
X738170Y1414185D03*
X740760Y1414165D03*
X733336Y1568341D03*
Y1565341D03*
Y1559341D03*
Y1562341D03*
X730336Y1559341D03*
Y1562341D03*
X745336D03*
Y1559341D03*
Y1565341D03*
Y1568341D03*
X742336Y1562341D03*
Y1559341D03*
Y1565341D03*
Y1568341D03*
X739336Y1562341D03*
Y1559341D03*
Y1565341D03*
Y1568341D03*
X736336D03*
Y1565341D03*
Y1559341D03*
Y1562341D03*
X733336Y1574341D03*
Y1571341D03*
X745336Y1574341D03*
Y1571341D03*
X742336Y1574341D03*
Y1571341D03*
X739336Y1574341D03*
Y1571341D03*
X736336D03*
Y1574341D03*
X730282Y1580391D03*
X741382Y1585251D03*
Y1580121D03*
X735882Y1580391D03*
X730282Y1590651D03*
Y1585521D03*
X735882Y1590651D03*
X741382Y1590691D03*
X732504Y1600321D03*
Y1597321D03*
X744504D03*
Y1600321D03*
X741504Y1597321D03*
Y1600321D03*
X735504Y1597321D03*
Y1600321D03*
X738504Y1597321D03*
Y1600321D03*
X744504Y1609521D03*
Y1612521D03*
X741504Y1609521D03*
X738504D03*
X735504D03*
X741504Y1612521D03*
X738504D03*
X735504D03*
X732504Y1603321D03*
Y1606321D03*
X744504Y1603321D03*
Y1606321D03*
X741504Y1603321D03*
Y1606321D03*
X738504Y1603321D03*
X735504D03*
X738504Y1606321D03*
X735504D03*
X735300Y1648760D03*
X744800Y1664840D03*
X737080Y1655820D03*
X735080Y1662980D03*
X742655Y1682362D03*
Y1678362D03*
X732705Y1669450D03*
X732895Y1737108D03*
X758606Y23797D03*
X747487Y49062D03*
X754620Y51602D03*
X758620D03*
X752720Y59002D03*
X749477Y57932D03*
X755700Y59942D03*
Y62442D03*
X758200Y59942D03*
Y62442D03*
X760700Y59942D03*
Y62442D03*
X747487Y71429D03*
X754219Y75707D03*
X757693Y100653D03*
Y96423D03*
X750033Y92888D03*
Y89988D03*
X754633Y108288D03*
Y105288D03*
X748033Y116288D03*
X747230Y108572D03*
X760390Y111810D03*
X762198Y129684D03*
Y126684D03*
X762172Y123898D03*
X751220Y137864D03*
X758110Y172636D03*
X747200Y251500D03*
X761720Y283262D03*
X748085Y278942D03*
X758360Y276122D03*
X757150Y280592D03*
X758720Y283262D03*
X759920Y280562D03*
X754290Y286632D03*
X755200Y296062D03*
X755305Y298847D03*
X748820Y284562D03*
X758390Y295450D03*
X748498Y309640D03*
X759637Y311585D03*
X757936Y303908D03*
X760670Y317432D03*
X747554Y384962D03*
X757430Y408212D03*
X760469Y442647D03*
X759940Y438232D03*
X750290Y462162D03*
X758420Y447662D03*
X756642Y496522D03*
Y501744D03*
X751220Y516852D03*
X759790Y525522D03*
X751220Y530362D03*
X757020Y530462D03*
X759820D03*
X754220D03*
X753137Y766625D03*
X762345Y1284542D03*
Y1287542D03*
Y1290542D03*
X762205Y1293272D03*
X757779Y1390645D03*
X757542Y1420684D03*
X755420Y1426262D03*
Y1422862D03*
X748336Y1562341D03*
Y1559341D03*
Y1565341D03*
Y1568341D03*
X751336D03*
Y1565341D03*
Y1559341D03*
Y1562341D03*
X748336Y1574341D03*
Y1571341D03*
X760112Y1579183D03*
X760152Y1583183D03*
X749612Y1583023D03*
X760112Y1592183D03*
Y1587183D03*
X747504Y1600321D03*
X749662Y1590733D03*
X747504Y1609521D03*
Y1612521D03*
X750504Y1609521D03*
X747504Y1603321D03*
Y1606321D03*
X761716Y1661194D03*
X761770Y1695347D03*
X755859Y1686090D03*
X759859D03*
X755183Y1709850D03*
X759359Y1729520D03*
X752875Y1726670D03*
X752895Y1737108D03*
X765606Y44894D03*
X769474Y75360D03*
X765858Y87340D03*
X762368Y84088D03*
X769284Y103895D03*
X767061Y99959D03*
X767045Y95960D03*
X767028Y91490D03*
X776730Y117479D03*
X773943Y114633D03*
X771131Y111788D03*
X769775Y107977D03*
X766769Y140138D03*
X773420Y143462D03*
X771774Y167518D03*
X772328Y153728D03*
X771426Y158026D03*
X763320Y264892D03*
X771630Y258102D03*
X762420Y280562D03*
X777420Y277962D03*
X773220Y296262D03*
X769789Y296231D03*
X777467Y296315D03*
X769860Y302462D03*
X772866Y311558D03*
X771377Y314139D03*
X777283Y320892D03*
X771490Y354942D03*
X777420Y354962D03*
X765000Y354862D03*
X771960Y375162D03*
X767960Y369662D03*
X776100Y375100D03*
X776000Y369662D03*
X764000D03*
X766195Y393212D03*
Y403212D03*
Y413212D03*
X768910Y403260D03*
X766195Y418212D03*
Y423212D03*
X768701Y418662D03*
X774982Y446908D03*
X768720Y459862D03*
X765315Y454862D03*
Y459862D03*
X765360Y475412D03*
X765315Y464862D03*
X765335Y469552D03*
X772364Y475062D03*
X772365Y469862D03*
X765315Y479862D03*
Y488862D03*
X772365D03*
X776170Y493422D03*
X766510Y493452D03*
X765386Y483572D03*
X773530Y507062D03*
X765521Y525364D03*
X769220Y530362D03*
X765720D03*
X772220D03*
X777020D03*
X772020Y746562D03*
X774384Y744088D03*
X762562Y746444D03*
X769921Y742095D03*
X767421D03*
X764921D03*
X775317Y764025D03*
X763747Y764335D03*
X769337Y760775D03*
X762617Y758885D03*
X765345Y1284542D03*
X768335Y1284612D03*
X765345Y1287542D03*
Y1290542D03*
X768335Y1287612D03*
Y1290612D03*
X765205Y1293272D03*
X768195Y1293342D03*
X778005Y1294092D03*
X768520Y1379962D03*
Y1384062D03*
Y1375462D03*
X768620Y1392762D03*
Y1397262D03*
X775375Y1403561D03*
X767820Y1410262D03*
Y1414762D03*
X763152Y1581893D03*
Y1577893D03*
Y1573793D03*
X773952Y1580493D03*
X768714Y1571203D03*
X769452Y1584393D03*
X770252Y1587268D03*
X763152Y1590893D03*
Y1594893D03*
X774052Y1590293D03*
X776052Y1611893D03*
X764920Y1695347D03*
X766880Y1689020D03*
X763359Y1729520D03*
X772208Y1731911D03*
X785095Y49388D03*
X785180Y120947D03*
X792680D03*
X790180D03*
X787680D03*
X783940Y118637D03*
X786440D03*
X788940D03*
X781440D03*
X782553Y150031D03*
Y152531D03*
X779893Y147521D03*
Y150021D03*
X785135Y281822D03*
Y267822D03*
X780820Y278262D03*
X785135Y274822D03*
X785200Y271400D03*
X780617Y296345D03*
X794057Y301569D03*
X794220Y296062D03*
X785220Y284762D03*
X792943Y312642D03*
X784415Y313734D03*
X779120Y306162D03*
X793896Y309026D03*
X793820Y304962D03*
X779120Y303410D03*
Y308755D03*
X794600Y360600D03*
X785000Y355000D03*
X779920Y354962D03*
X782420D03*
X790120Y354862D03*
X792620D03*
X787600Y354900D03*
X787925Y387900D03*
X791075Y388000D03*
X781195Y393212D03*
X787720Y408362D03*
X781195Y413212D03*
Y423212D03*
X785560Y417902D03*
X781195Y418212D03*
X791590Y417050D03*
X788120Y422942D03*
X791040Y422892D03*
X793660Y422842D03*
X785720Y427862D03*
X789230Y414942D03*
X780020Y438287D03*
X781410Y431822D03*
X780020Y441437D03*
Y445287D03*
X784730Y432682D03*
X791582Y435352D03*
X781205Y454402D03*
X780315Y459862D03*
X780340Y468982D03*
Y474862D03*
X786220Y464862D03*
X780315D03*
X793220Y493362D03*
X781170Y493422D03*
X793875Y483262D03*
X778670Y493422D03*
X793673Y512862D03*
X783400Y511902D03*
X789720Y589862D03*
X785220Y581362D03*
X789720Y587362D03*
X792720Y589862D03*
X789720Y581862D03*
X791720Y593862D03*
X793720Y595862D03*
X783100Y593582D03*
X794720Y617862D03*
X783507Y761875D03*
X794157Y761295D03*
X782515Y766702D03*
X791140Y761693D03*
X792045Y1284542D03*
Y1290542D03*
Y1287542D03*
X791905Y1293272D03*
X788225Y1388683D03*
X791260Y1388662D03*
X790380Y1432132D03*
X784352Y1568293D03*
Y1565293D03*
Y1559293D03*
Y1562293D03*
X781352Y1568293D03*
Y1565293D03*
Y1559293D03*
Y1562293D03*
X793352D03*
Y1559293D03*
Y1565293D03*
Y1568293D03*
X790352Y1562293D03*
Y1559293D03*
Y1565293D03*
Y1568293D03*
X787352D03*
Y1565293D03*
Y1559293D03*
Y1562293D03*
X784352Y1574293D03*
Y1571293D03*
X781352Y1574293D03*
Y1571293D03*
X793352Y1574293D03*
Y1571293D03*
X790352Y1574293D03*
Y1571293D03*
X787352D03*
Y1574293D03*
X788079Y1580393D03*
X782479D03*
X793579D03*
X788079Y1590653D03*
X782479D03*
Y1585523D03*
X793579Y1590653D03*
Y1585523D03*
X785052Y1600693D03*
Y1597693D03*
X782052D03*
Y1600693D03*
X794052D03*
X788052D03*
X791052D03*
X794052Y1597693D03*
X788052D03*
X791052D03*
X785052Y1607793D03*
X782052D03*
X779052D03*
X785052Y1611893D03*
X782052D03*
X779052D03*
X794052Y1607793D03*
X791052D03*
X788052D03*
X794052Y1611893D03*
X788052D03*
X791052D03*
X785052Y1603693D03*
X782052D03*
X794052D03*
X788052D03*
X791052D03*
X792208Y1731911D03*
X805095Y49388D03*
X797443Y271469D03*
X806300Y279662D03*
X809700Y273562D03*
X808800Y267900D03*
X810920Y280062D03*
X798204Y279146D03*
X795190Y298572D03*
X797924Y298358D03*
X798620Y312773D03*
X806450Y310362D03*
X803620Y302962D03*
X805870Y304812D03*
X799720Y300462D03*
X795920Y312662D03*
X803280Y354982D03*
X800646Y354921D03*
X809800Y360600D03*
X802200D03*
X806588Y351097D03*
X795220Y354862D03*
X806000Y360600D03*
X798400D03*
X805910Y355012D03*
X797900Y354800D03*
X799800Y368700D03*
X810781Y372615D03*
X803150Y408512D03*
X795600Y402500D03*
X795520Y398212D03*
X799458Y431217D03*
X802010Y439940D03*
X795320Y439862D03*
X805720Y432902D03*
X795320Y444862D03*
X810860Y454862D03*
X795320D03*
Y449862D03*
X810860Y459862D03*
X795320D03*
X810860Y449862D03*
X795370Y474862D03*
X798990D03*
X795320Y464862D03*
X810860D03*
X810815Y469862D03*
X807220Y493362D03*
X801940Y485932D03*
X804510Y486122D03*
X809510D03*
X799230Y485922D03*
X802790Y495652D03*
X805470Y510522D03*
X807640Y506672D03*
X808100Y509900D03*
X797420Y512503D03*
X805445Y587582D03*
X798720Y585362D03*
X810720Y586862D03*
X811143Y605265D03*
X798220Y597362D03*
X808860Y603802D03*
X807945Y594362D03*
X803220D03*
X797200Y599883D03*
X797720Y617862D03*
X795720Y614862D03*
X796702Y761195D03*
X799637Y763625D03*
X799577Y760985D03*
X807000Y757562D03*
X798035Y1284612D03*
X795045Y1284542D03*
X798035Y1290612D03*
Y1287612D03*
X795045Y1290542D03*
Y1287542D03*
X797895Y1293342D03*
X794905Y1293272D03*
X809210Y1343062D03*
X804100Y1435010D03*
X800000Y1431100D03*
X799352Y1562293D03*
Y1559293D03*
Y1565293D03*
Y1568293D03*
X796352Y1562293D03*
Y1559293D03*
Y1565293D03*
Y1568293D03*
X799352Y1574293D03*
Y1571293D03*
X796352Y1574293D03*
Y1571293D03*
X804652Y1581793D03*
Y1573793D03*
X812698Y1587047D03*
X804652Y1597793D03*
Y1585993D03*
X799152Y1586507D03*
X804652Y1589793D03*
X797052Y1607793D03*
X804652Y1609793D03*
X825095Y49388D03*
X819114Y115223D03*
X827114D03*
X823114D03*
X821118Y134632D03*
X825698Y139062D03*
X824498Y145198D03*
X813900Y269698D03*
X815060Y280072D03*
X813490Y273862D03*
X816220Y277162D03*
X827403Y286625D03*
X816420Y287062D03*
X813293D03*
X826300Y311962D03*
X823800D03*
X813855Y354008D03*
X820936Y356956D03*
X821164Y372312D03*
X818000Y378800D03*
X813210Y374292D03*
X815710D03*
X825003Y397276D03*
X819220Y397664D03*
X824980Y405260D03*
Y409260D03*
Y413260D03*
X823600Y421194D03*
X815310Y440100D03*
X818500Y451700D03*
X816500Y476800D03*
X825100Y468900D03*
X824860Y464862D03*
X820720Y493862D03*
X822415Y479600D03*
X814305Y499503D03*
X819320Y502347D03*
X821720Y519082D03*
Y515082D03*
Y523082D03*
X815040Y590772D03*
X820220Y586862D03*
X814220Y582530D03*
X823720Y594862D03*
X820470Y595112D03*
X815120Y593582D03*
X820613Y744641D03*
X823589Y746924D03*
X814800Y760922D03*
X822442Y762369D03*
X822374Y757039D03*
X814770Y763874D03*
X815789Y1008845D03*
X814234Y1340465D03*
X826090Y1334362D03*
Y1339362D03*
Y1329362D03*
Y1344362D03*
X820920Y1344342D03*
X818420D03*
X823352Y1565293D03*
Y1562293D03*
Y1559293D03*
Y1568293D03*
X826352Y1565293D03*
Y1562293D03*
Y1559293D03*
Y1568293D03*
X823352Y1571293D03*
Y1574293D03*
X826352Y1571293D03*
Y1574293D03*
X824479Y1580393D03*
X815652Y1582570D03*
Y1573793D03*
X813352Y1590893D03*
X812652Y1593793D03*
X824479Y1590653D03*
Y1585523D03*
X824052Y1597693D03*
Y1600693D03*
X827052D03*
Y1597693D03*
X815551Y1593793D03*
X818652Y1590444D03*
X812652Y1605793D03*
X824052Y1611893D03*
Y1607793D03*
Y1603693D03*
X827052Y1611893D03*
Y1607793D03*
Y1603693D03*
X821052Y1611893D03*
Y1607793D03*
X818052Y1611893D03*
X812652Y1601793D03*
X812208Y1731911D03*
X840001Y6800D03*
X842497Y6022D03*
X834273Y2374D03*
X834258Y4889D03*
X830975Y2388D03*
X830990Y4903D03*
X837268Y3597D03*
X840001Y10200D03*
X842497Y16022D03*
Y20978D03*
Y10978D03*
X834273Y22432D03*
X830975Y22446D03*
Y8543D03*
X834273Y8529D03*
Y12403D03*
X834258Y14918D03*
X830975Y12417D03*
X830990Y14932D03*
X830975Y18572D03*
X834273Y18558D03*
X837268Y13626D03*
X834258Y24947D03*
X830990Y24961D03*
X837268Y23655D03*
X836126Y62681D03*
X828600Y61752D03*
X837791Y85186D03*
X837250Y93221D03*
X831297Y104206D03*
X842864Y110296D03*
X831114Y115223D03*
X839360Y114862D03*
X835114Y115223D03*
X829114Y150273D03*
Y147123D03*
X836502Y161553D03*
X828145Y160362D03*
X838220Y163862D03*
X835220D03*
X837320Y175112D03*
X842720Y181360D03*
X837975Y210064D03*
X830339Y228143D03*
X837500Y229642D03*
X829680Y264580D03*
X836210Y272452D03*
X829720Y277562D03*
X829800Y271562D03*
X840063Y285022D03*
X839450Y272662D03*
X835400Y268800D03*
X829620Y280345D03*
X829820Y275045D03*
X840850Y278948D03*
X829320Y296762D03*
X834400Y283862D03*
X834900Y293462D03*
X829720Y292762D03*
X839860Y294702D03*
X827620Y302962D03*
X830417Y311865D03*
X828222Y359960D03*
X835471Y363003D03*
X843133Y366158D03*
X833300Y386500D03*
X836300Y418800D03*
X832400Y427100D03*
X840400Y418900D03*
X839200Y434300D03*
X841300Y446800D03*
X831720Y457700D03*
X839640Y449612D03*
X832700Y446800D03*
X830600Y449200D03*
X841200Y456500D03*
X842600Y477200D03*
X842341Y474241D03*
X832720Y494862D03*
X829720D03*
X841795Y492862D03*
X830870Y480010D03*
X829745Y502082D03*
X832370Y525849D03*
X843287Y527817D03*
X834635Y515447D03*
X830480Y527817D03*
X841461Y525849D03*
X840990Y529786D03*
X828009Y587913D03*
X829230Y582772D03*
X831700Y596962D03*
X831530Y651932D03*
X830587Y741205D03*
X833120Y743392D03*
X838587Y766825D03*
X836847Y762495D03*
X841827Y766795D03*
X837127Y758976D03*
X829420Y758422D03*
X841997Y773085D03*
X838020Y1232432D03*
X828799Y1336870D03*
X828910Y1331756D03*
X832090Y1331862D03*
Y1336862D03*
X828910Y1341725D03*
X832090Y1341862D03*
X829352Y1565293D03*
Y1562293D03*
Y1559293D03*
Y1568293D03*
X832352D03*
Y1565293D03*
Y1559293D03*
Y1562293D03*
X835352Y1568293D03*
Y1565293D03*
Y1559293D03*
Y1562293D03*
X838352Y1568293D03*
Y1565293D03*
Y1559293D03*
Y1562293D03*
X841352Y1568293D03*
Y1565293D03*
Y1559293D03*
Y1562293D03*
X829352Y1574293D03*
Y1571293D03*
X832352D03*
Y1574293D03*
X835352Y1571293D03*
Y1574293D03*
X838352Y1571293D03*
Y1574293D03*
X841352Y1571293D03*
Y1574293D03*
X830079Y1580393D03*
X835579D03*
X843652Y1584539D03*
X833052Y1597693D03*
X836052D03*
X830079Y1590653D03*
X835579D03*
X833052Y1600693D03*
X836052D03*
X835579Y1585523D03*
X830052Y1600693D03*
Y1597693D03*
X841152Y1586507D03*
X833052Y1603693D03*
X836052D03*
X833052Y1607793D03*
Y1611893D03*
X836052Y1607793D03*
Y1611893D03*
X830052D03*
Y1607793D03*
Y1603693D03*
X839052Y1607793D03*
X832208Y1731911D03*
X845095Y49388D03*
X858629Y60293D03*
X843855Y87711D03*
X854577Y99651D03*
X854107Y91232D03*
X850280Y113852D03*
X847660Y113962D03*
X853100Y113762D03*
X856776Y129268D03*
X846846Y127064D03*
X854100Y132972D03*
X854220Y135862D03*
Y129362D03*
X854200Y138562D03*
X851895Y160262D03*
X848745Y160187D03*
X848709Y156752D03*
X848360Y182872D03*
X845720Y181362D03*
X849710Y212062D03*
X845220Y216532D03*
X855858Y212425D03*
X855933Y215375D03*
X854706Y229878D03*
X852206D03*
X853828Y265057D03*
X854333Y276117D03*
X854338Y280027D03*
Y283527D03*
X853828Y269043D03*
X850133Y271049D03*
X852800Y288562D03*
X853200Y297462D03*
X850093Y286625D03*
X855480Y299692D03*
X856700Y304862D03*
X848000Y374622D03*
X851396Y369614D03*
X859734Y373032D03*
X846040Y399210D03*
X844200Y418800D03*
X847830Y443892D03*
X843810Y453322D03*
X851606Y447927D03*
X844210Y455902D03*
X846700Y473000D03*
Y476900D03*
X855200D03*
X848710Y505641D03*
X858600Y511130D03*
X857195Y522162D03*
X859054Y583752D03*
X845523Y582126D03*
X856698Y594011D03*
X856520Y751262D03*
X853200Y751062D03*
X859450Y750462D03*
X854687Y761685D03*
X844957Y763065D03*
X854620Y1242125D03*
X854237Y1250358D03*
X846652Y1581793D03*
Y1573793D03*
X854652Y1577793D03*
X857652Y1582570D03*
Y1573793D03*
X854777Y1586968D03*
X846652Y1597793D03*
X855352Y1590893D03*
X854652Y1593793D03*
X846652Y1585993D03*
X857551Y1593793D03*
X846652Y1589793D03*
X854652Y1605793D03*
Y1601793D03*
X846652Y1609793D03*
X852208Y1731911D03*
X865095Y49388D03*
X862930Y70072D03*
X866330D03*
X876124Y66072D03*
X868187Y72006D03*
X860937Y71877D03*
X861350Y61672D03*
X876124Y86072D03*
Y106072D03*
Y126072D03*
X862452Y151590D03*
X874295Y163862D03*
X867620Y154362D03*
X871145Y163862D03*
X863488Y176332D03*
X871580Y183370D03*
X871980Y199500D03*
X864859Y187110D03*
X871890Y196740D03*
X875543Y266447D03*
X860833Y276817D03*
X863933Y276917D03*
X875543Y269347D03*
X862043Y290047D03*
X874243Y287047D03*
X877322Y296051D03*
X872320Y304936D03*
X869820D03*
X867320D03*
X864820D03*
X867922Y376450D03*
X875922Y379793D03*
X860531Y375826D03*
X870700Y382415D03*
Y390620D03*
Y394620D03*
Y386476D03*
Y398620D03*
Y402581D03*
X871320Y416752D03*
X870513Y414276D03*
X860574Y445404D03*
X861080Y459742D03*
X870360Y493042D03*
X862620Y503162D03*
Y499062D03*
Y507162D03*
X865290Y499032D03*
X865810Y521862D03*
X860345Y513062D03*
X863925Y737697D03*
X864680Y751582D03*
X874155Y756993D03*
X864700Y778300D03*
X868352Y1568293D03*
Y1565293D03*
Y1559293D03*
Y1562293D03*
X865352Y1568293D03*
Y1565293D03*
Y1559293D03*
Y1562293D03*
X874352D03*
Y1559293D03*
Y1565293D03*
Y1568293D03*
X871352D03*
Y1565293D03*
Y1559293D03*
Y1562293D03*
X868352Y1574293D03*
Y1571293D03*
X865352Y1574293D03*
Y1571293D03*
X874352Y1574293D03*
Y1571293D03*
X871352D03*
Y1574293D03*
X866479Y1580393D03*
X872079D03*
X866052Y1597693D03*
X869052D03*
X866479Y1590653D03*
X869052Y1600693D03*
X866052D03*
X872052Y1597693D03*
X872079Y1590653D03*
X872052Y1600693D03*
X866479Y1585523D03*
X875052Y1597693D03*
Y1600693D03*
X860652Y1590444D03*
X869052Y1603693D03*
X866052D03*
X872052D03*
X869052Y1607793D03*
Y1611893D03*
X866052Y1607793D03*
X863052Y1611893D03*
X866052D03*
X872052Y1607793D03*
Y1611893D03*
X875052Y1603693D03*
Y1607793D03*
Y1611893D03*
X863052Y1607793D03*
X860052Y1611893D03*
X872208Y1731911D03*
X892214Y141891D03*
X886280Y174085D03*
X878327Y183169D03*
X876695Y171362D03*
Y176862D03*
X887520Y171362D03*
Y176862D03*
X878220Y192055D03*
X877724Y200837D03*
X878220Y187449D03*
X888929Y209223D03*
X891620Y209662D03*
X888929Y206723D03*
X891620Y207162D03*
X880943Y283347D03*
X884003Y278712D03*
X883870Y275802D03*
X880943Y286347D03*
X880473Y329370D03*
X882520Y327562D03*
X885020D03*
X887520D03*
X890422Y333879D03*
X887869Y386618D03*
X883472Y382910D03*
X890920Y386352D03*
X889453Y458926D03*
X887590Y471552D03*
X889439Y489599D03*
Y492999D03*
X887671Y487831D03*
Y494767D03*
X878931Y509051D03*
X878941Y503813D03*
X881680Y504742D03*
Y508142D03*
X884512Y523800D03*
X882410Y526132D03*
X888130Y532612D03*
X891530D03*
X886362Y534380D03*
X886500Y739162D03*
X889000Y737562D03*
X886720Y741902D03*
X878152Y876760D03*
X878192Y879910D03*
X884747Y871745D03*
X879100Y912608D03*
X881372Y920655D03*
X880102Y923235D03*
X889439Y1437938D03*
X891560Y1435510D03*
X883352Y1562293D03*
Y1559293D03*
Y1565293D03*
Y1568293D03*
X880352Y1562293D03*
Y1559293D03*
Y1565293D03*
Y1568293D03*
X877352Y1562293D03*
Y1559293D03*
Y1565293D03*
Y1568293D03*
X883352Y1574293D03*
Y1571293D03*
X880352Y1574293D03*
Y1571293D03*
X877352Y1574293D03*
Y1571293D03*
X888652Y1581793D03*
Y1573793D03*
X877579Y1580393D03*
X885652Y1584539D03*
X888652Y1585993D03*
X877579Y1585523D03*
X878052Y1597693D03*
Y1600693D03*
X877579Y1590653D03*
X883152Y1586507D03*
X888652Y1589793D03*
X878052Y1603693D03*
Y1607793D03*
X881052Y1611893D03*
X878052D03*
X881052Y1607793D03*
X892208Y1731911D03*
X908620Y188899D03*
X903930Y202885D03*
X903980Y210355D03*
X903930Y217059D03*
X896620Y209662D03*
X894120D03*
Y207162D03*
X896620D03*
X903980Y224529D03*
X906120Y261252D03*
X894770Y283062D03*
X893500Y339062D03*
X908675Y455386D03*
X899625Y473856D03*
X902260Y473153D03*
Y475653D03*
X903124Y470797D03*
X900020Y470672D03*
X896060Y481222D03*
Y484622D03*
X893321Y480293D03*
X893311Y485531D03*
X907678Y488177D03*
X895340Y497882D03*
Y501282D03*
X893572Y503050D03*
Y496114D03*
X900061Y510962D03*
X906127Y496343D03*
X901829Y512730D03*
Y516130D03*
X900061Y517898D03*
X893450Y516862D03*
X901230Y531612D03*
X904630D03*
X893298Y534380D03*
X899462Y533380D03*
X906398D03*
X894897Y871745D03*
X897000Y891895D03*
X894375Y913692D03*
X894965Y917422D03*
X898062Y976652D03*
Y969716D03*
X899830Y971484D03*
Y974884D03*
X907770Y1045242D03*
X894830Y1435970D03*
X907352Y1568293D03*
Y1565293D03*
Y1559293D03*
Y1562293D03*
Y1574293D03*
Y1571293D03*
X908479Y1580393D03*
X896652Y1577793D03*
X899652Y1582570D03*
Y1573793D03*
X896672Y1587073D03*
X897352Y1590893D03*
X896652Y1593793D03*
X908479Y1590653D03*
Y1585523D03*
X908052Y1600693D03*
Y1597693D03*
X899551Y1593793D03*
X902652Y1590444D03*
X908052Y1611893D03*
X905052D03*
X902052D03*
X908052Y1607793D03*
X905052D03*
X908052Y1603693D03*
X896652Y1601793D03*
X912214Y141891D03*
X917680Y174999D03*
Y177999D03*
Y171999D03*
X920246Y184138D03*
X909386Y195925D03*
X924920Y196199D03*
X909386Y203011D03*
Y210098D03*
Y217185D03*
Y224271D03*
Y231358D03*
X914550Y239924D03*
X923897Y445545D03*
X912984Y458135D03*
X909584D03*
X913913Y455396D03*
X919279Y461244D03*
X924447Y463012D03*
X921047D03*
X909190Y473392D03*
X912288Y472430D03*
X920682Y494586D03*
X920980Y503393D03*
X913394Y521662D03*
X916794D03*
X909600Y521162D03*
X911720Y511662D03*
X911626Y523430D03*
X918562D03*
X924647Y526808D03*
X922879Y531976D03*
Y528576D03*
X924647Y533744D03*
X918420Y804062D03*
X909720Y798861D03*
Y794862D03*
X913720Y799362D03*
X914152Y803294D03*
X924600Y824262D03*
X921757Y962082D03*
X916974Y962108D03*
X923403Y983327D03*
X923930Y976652D03*
X923322Y990227D03*
X924440Y996852D03*
X918720Y1009937D03*
X921880Y1525110D03*
X924380D03*
X921880Y1527610D03*
X924380D03*
X910352Y1568293D03*
Y1565293D03*
Y1559293D03*
Y1562293D03*
X922352D03*
Y1559293D03*
Y1565293D03*
Y1568293D03*
X919352Y1562293D03*
Y1559293D03*
Y1565293D03*
Y1568293D03*
X916352Y1562293D03*
Y1559293D03*
Y1565293D03*
Y1568293D03*
X913352D03*
Y1565293D03*
Y1559293D03*
Y1562293D03*
X910352Y1574293D03*
Y1571293D03*
X922352Y1574293D03*
Y1571293D03*
X919352Y1574293D03*
Y1571293D03*
X916352Y1574293D03*
Y1571293D03*
X913352D03*
Y1574293D03*
X919579Y1580393D03*
X914079D03*
X919579Y1590653D03*
X914079D03*
X919579Y1585523D03*
X917052Y1600693D03*
Y1597693D03*
X914052Y1600693D03*
Y1597693D03*
X911052Y1600693D03*
Y1597693D03*
X920052Y1600693D03*
Y1597693D03*
X917052Y1611893D03*
X914052D03*
X911052D03*
X917052Y1607793D03*
X914052D03*
X911052D03*
X920052Y1611893D03*
X923052D03*
Y1607793D03*
X920052D03*
X917052Y1603693D03*
X914052D03*
X911052D03*
X920052D03*
X922320Y1660953D03*
X919488Y1660733D03*
X918020Y1672860D03*
X912208Y1731911D03*
X932214Y141891D03*
X938160Y173389D03*
X935550Y173329D03*
X940720Y173389D03*
X938160Y176389D03*
X935550Y176329D03*
X940720Y176389D03*
X927133Y189386D03*
X935496Y195925D03*
X935770Y191419D03*
X939270D03*
X935496Y203012D03*
X925320Y203399D03*
X935496Y210098D03*
Y217185D03*
Y224272D03*
Y231358D03*
X930472Y246093D03*
X938603Y240063D03*
X933122Y246115D03*
X933686Y242922D03*
X935454Y241154D03*
X933217Y380693D03*
Y384693D03*
X941059Y427911D03*
Y424511D03*
X940709Y460438D03*
X938437Y455454D03*
X932724Y455538D03*
X926215Y461244D03*
X937447Y457862D03*
X934047D03*
X928394Y472201D03*
Y474701D03*
X929234Y494915D03*
X938588Y485197D03*
X929698Y503595D03*
X940596Y498648D03*
X939872Y495813D03*
X931720Y524862D03*
X939097Y527257D03*
X940550Y517400D03*
X940140Y514925D03*
X933773Y530479D03*
X930731D03*
X941050Y532252D03*
Y528852D03*
X928231Y530479D03*
X936273Y530478D03*
X939282Y534020D03*
X938742Y803831D03*
X931573Y816109D03*
X927470Y815112D03*
X927200Y811462D03*
X934260Y808312D03*
X938371Y809311D03*
X930786Y811785D03*
X925220Y817862D03*
X928237Y824844D03*
X926469Y826612D03*
X931496Y962082D03*
X926823D03*
X940170Y962842D03*
X930233Y983298D03*
X930274Y990237D03*
X936998Y985750D03*
X932310Y996812D03*
X929221Y1014664D03*
X927220Y1012362D03*
X931220D03*
X939380Y1525110D03*
X926880D03*
X929380D03*
X931880D03*
X934380D03*
X936880D03*
X926880Y1527610D03*
X929380D03*
X931880D03*
X934380D03*
X936880D03*
X939380D03*
X925352Y1562293D03*
Y1559293D03*
Y1565293D03*
Y1568293D03*
Y1574293D03*
Y1571293D03*
X938652Y1581393D03*
X928152Y1584539D03*
X938652Y1593393D03*
Y1585393D03*
X925152Y1586507D03*
X938652Y1589393D03*
X927122Y1661380D03*
X938220Y1661062D03*
X933979Y1661327D03*
X929979Y1661352D03*
X942100Y1671100D03*
X932208Y1731911D03*
X952214Y141891D03*
X957420Y153699D03*
X945720Y173389D03*
X943220D03*
X945720Y176389D03*
X943220D03*
X948400Y176499D03*
X949120Y184912D03*
X949710Y198289D03*
X941634Y199051D03*
Y193451D03*
X944250Y194489D03*
Y197889D03*
X957020Y193299D03*
X949550Y192819D03*
X951354Y209437D03*
Y203837D03*
X944880Y210959D03*
Y216559D03*
Y230697D03*
Y225097D03*
X954874Y232071D03*
X954904Y225741D03*
X953046Y390103D03*
X951181Y391916D03*
X956487Y394831D03*
X942646Y400793D03*
X942827Y422743D03*
Y429679D03*
X944032Y437631D03*
Y434231D03*
X945800Y432463D03*
Y439399D03*
X946492Y460410D03*
X945447Y463012D03*
X942047D03*
X946727Y507952D03*
Y504552D03*
X954420Y511252D03*
Y500552D03*
Y497152D03*
X956188Y495384D03*
Y502320D03*
X948495Y502784D03*
X948693Y509497D03*
X956188Y509484D03*
X954420Y514652D03*
X954390Y527596D03*
X956188Y516420D03*
X947190Y527330D03*
X945524Y515483D03*
X944261Y517871D03*
X941740Y512922D03*
X942610Y515350D03*
X952622Y529364D03*
X955123Y533642D03*
X948415Y534313D03*
X956518Y531567D03*
X953594Y787477D03*
X956700Y786862D03*
X954447Y791735D03*
X951043Y796140D03*
X950190Y791382D03*
X944272Y803410D03*
X943366Y798707D03*
X946786Y795287D03*
X947921Y799761D03*
X941400Y810062D03*
X944170Y962842D03*
X946865Y974077D03*
X953235Y972642D03*
X946938Y991162D03*
X943720Y985772D03*
X951560Y997422D03*
X956980Y1536260D03*
X953980D03*
X950980D03*
X947980D03*
X944980D03*
Y1551260D03*
X947980D03*
X950980D03*
X953980D03*
X956980D03*
X944980Y1548260D03*
X947980D03*
X950980D03*
X953980D03*
X956980D03*
X944980Y1545260D03*
X947980D03*
X950980D03*
X953980D03*
X956980D03*
X944980Y1542260D03*
X947980D03*
X950980D03*
X953980D03*
X956980D03*
Y1539260D03*
X953980D03*
X950980D03*
X947980D03*
X944980D03*
Y1554260D03*
X947980D03*
X950980D03*
X953980D03*
X956980D03*
X956022Y1620730D03*
X953022D03*
Y1632730D03*
X956022D03*
Y1629730D03*
X953022D03*
X956022Y1626730D03*
X953022D03*
Y1623730D03*
X956022D03*
X946100Y1661100D03*
X956800Y1663725D03*
X956600Y1666875D03*
X952208Y1731911D03*
X972214Y141891D03*
X960420Y153699D03*
X962604Y165313D03*
X962458Y162398D03*
X965150Y193412D03*
X966720Y198099D03*
X970720D03*
X961120Y193299D03*
X963520Y214699D03*
X960703Y212668D03*
X971471Y242358D03*
X968384Y242051D03*
X965884D03*
X960020Y264862D03*
X963020D03*
X967239Y320073D03*
X963300Y347962D03*
X965792Y350959D03*
X962623Y350642D03*
X965420Y365719D03*
X970730Y377872D03*
X963856Y394202D03*
X960059Y387004D03*
X972986Y393171D03*
X972220Y386251D03*
Y390239D03*
X963856Y398302D03*
X965890Y405967D03*
X970054Y478773D03*
X961320Y476242D03*
X970054Y485709D03*
X968286Y483941D03*
Y480541D03*
X966720Y511362D03*
X960620Y509462D03*
X972379Y509303D03*
X964347Y509462D03*
X970788Y501230D03*
X964347Y501262D03*
X957790Y527596D03*
X963930Y533362D03*
X967330D03*
X959558Y529364D03*
X962162Y535130D03*
X969098D03*
X959351Y533566D03*
X958755Y657078D03*
X960920Y644762D03*
Y649762D03*
Y654762D03*
X963720Y647262D03*
Y657262D03*
Y652262D03*
X963520Y665062D03*
X958866Y662378D03*
X960820Y665062D03*
X960920Y659762D03*
X963720Y662262D03*
X959100Y789862D03*
X963610Y981292D03*
X959535Y990477D03*
X963780Y997496D03*
X967750Y1376460D03*
X969000Y1536262D03*
X971700D03*
X969000Y1548262D03*
X971700D03*
X969000Y1545262D03*
X971700D03*
X969000Y1551262D03*
X971700D03*
Y1542262D03*
X969000D03*
X971700Y1539262D03*
X969000D03*
Y1554262D03*
X971700D03*
X965622Y1579240D03*
Y1576240D03*
Y1573240D03*
X966852Y1585920D03*
X969852D03*
X960852D03*
X963852D03*
X957852D03*
X965086Y1603984D03*
X962022Y1620730D03*
X959022D03*
Y1632730D03*
X962022D03*
Y1629730D03*
X959022D03*
X962022Y1626730D03*
X959022D03*
Y1623730D03*
X962022D03*
X968022Y1620730D03*
X965022D03*
X971022D03*
X965022Y1632730D03*
X968022Y1629730D03*
X965022D03*
X968022Y1626730D03*
X965022D03*
Y1623730D03*
X968022D03*
X971022Y1626730D03*
Y1623730D03*
Y1629730D03*
Y1632730D03*
X968022D03*
X972208Y1731911D03*
X989910Y-27961D03*
X989925Y-25446D03*
X986642Y-27947D03*
X986627Y-25432D03*
X983632Y-26655D03*
X980899Y-19800D03*
Y-23200D03*
X978403Y-9022D03*
Y-13978D03*
Y-19022D03*
Y-23978D03*
X986627Y-21558D03*
X989925Y-21572D03*
X983632Y-16626D03*
X989910Y-17932D03*
X989925Y-15417D03*
X986642Y-17918D03*
X986627Y-15403D03*
Y-11529D03*
X989925Y-11543D03*
X980899Y6800D03*
X978403Y6022D03*
X989910Y-7903D03*
X989925Y-5388D03*
X986642Y-7889D03*
X986627Y-5374D03*
X983632Y-6597D03*
X986627Y4655D03*
X986642Y2140D03*
X989925Y4641D03*
X989910Y2126D03*
X983632Y3432D03*
X980899Y10200D03*
X978403Y10978D03*
Y20978D03*
Y16022D03*
X986627Y14684D03*
X989925Y14670D03*
X986642Y12169D03*
X989910Y12155D03*
X989925Y8515D03*
X986627Y8529D03*
X983632Y13461D03*
X986642Y22698D03*
X989910Y22684D03*
X986627Y19058D03*
X989925Y19044D03*
X986627Y25213D03*
X989895Y25199D03*
X983632Y23990D03*
X975688Y152950D03*
Y149950D03*
X975690Y157220D03*
X983811Y156694D03*
X988835Y185443D03*
X981445Y181058D03*
X985431D03*
X987320Y194599D03*
Y198099D03*
Y201599D03*
X977220Y201399D03*
X986020Y191099D03*
X981795Y216623D03*
X978012Y276436D03*
X975512Y282096D03*
X978012D03*
X975512Y279266D03*
X978012D03*
X981470Y268532D03*
X979940Y292262D03*
Y289762D03*
X975512Y294996D03*
X978012D03*
X979940Y284762D03*
Y287262D03*
X988818Y346372D03*
X985016Y344659D03*
X974791Y339990D03*
X986182Y361062D03*
X991934Y368443D03*
X989500Y376362D03*
X979380Y373082D03*
X988908Y373392D03*
X980916Y384286D03*
X986955Y391939D03*
X979559Y399362D03*
X983970Y392562D03*
X988159Y409068D03*
X983760Y424292D03*
X980092Y421289D03*
X984254Y418379D03*
X987440Y431193D03*
X985672Y432961D03*
X986400Y503200D03*
X983720Y512362D03*
X976283Y534226D03*
X986273Y532996D03*
X980535Y532643D03*
X986418Y530019D03*
X975900Y1265062D03*
X987920Y1290662D03*
X985320Y1288762D03*
X979373Y1342724D03*
X974700Y1536262D03*
X980400D03*
X977700D03*
X974700Y1548262D03*
Y1545262D03*
Y1551262D03*
X980400Y1548262D03*
X977700D03*
X980400Y1545262D03*
X977700D03*
X980400Y1551262D03*
X977700D03*
Y1542262D03*
X980400D03*
X974700D03*
X977700Y1539262D03*
X980400D03*
X974700D03*
Y1554262D03*
X980400D03*
X977700D03*
X989270Y1554364D03*
X988988Y1579240D03*
Y1573240D03*
Y1576240D03*
X987662Y1620870D03*
Y1629870D03*
Y1626870D03*
Y1623870D03*
Y1632870D03*
X995000Y150883D03*
X1001500D03*
X1002735Y153943D03*
X999735D03*
X1006220Y160799D03*
X1002720D03*
X999915Y180548D03*
X996415D03*
X992505Y180553D03*
X993205Y174053D03*
X993305Y170953D03*
X999220Y185299D03*
X1002720D03*
X1006220D03*
X990220Y195699D03*
Y199199D03*
X990495Y212923D03*
X990195Y216823D03*
X990220Y202699D03*
X1001195Y219898D03*
X1005120Y230399D03*
X1002500Y266862D03*
X998500Y269862D03*
X1002500D03*
X1001065Y304622D03*
Y307122D03*
Y309622D03*
X1006232Y343983D03*
X1001440Y359702D03*
X994553Y365711D03*
X994689Y379348D03*
X997598Y382952D03*
X997612Y391804D03*
X1006221Y382945D03*
X997900Y400720D03*
X994322Y404090D03*
X997394Y415578D03*
X991770Y418835D03*
X993387Y429827D03*
X993012Y421570D03*
X990840Y431193D03*
X992608Y432961D03*
X1003220Y512862D03*
X999720D03*
X991097Y529902D03*
X991237Y533043D03*
X1002640Y594692D03*
X1005960Y594682D03*
X1005373Y748826D03*
X995120Y773122D03*
X994942Y777055D03*
X996675Y1286985D03*
X996320Y1280683D03*
Y1284062D03*
X997920Y1278762D03*
X994574Y1297318D03*
X995066Y1536262D03*
X992466D03*
X1001066D03*
X1003766D03*
X998066D03*
X995066Y1551262D03*
X992466D03*
X995066Y1545262D03*
X992466D03*
X995066Y1548262D03*
X992466D03*
X1001066Y1551262D03*
X1003766D03*
X1001066Y1545262D03*
X1003766D03*
X1001066Y1548262D03*
X1003766D03*
X998066Y1551262D03*
Y1545262D03*
Y1548262D03*
Y1542262D03*
X1003766D03*
X1001066D03*
X992466D03*
X995066D03*
X998066Y1539262D03*
X1003766D03*
X1001066D03*
X992466D03*
X995066D03*
Y1554262D03*
X992466D03*
X1001066D03*
X1003766D03*
X998066D03*
X1002782Y1585920D03*
X999782D03*
X996782D03*
X990782D03*
X993782D03*
X996698Y1604000D03*
X990662Y1620870D03*
X993662D03*
X996662D03*
X999662D03*
X1002662D03*
Y1626870D03*
Y1623870D03*
X996662Y1629870D03*
X999662Y1626870D03*
X996662D03*
Y1623870D03*
X999662D03*
X996662Y1632870D03*
X993662Y1629870D03*
X990662D03*
X993662Y1626870D03*
X990662D03*
Y1623870D03*
X993662D03*
X990662Y1632870D03*
X993662D03*
X1001810Y1662700D03*
Y1665200D03*
X992208Y1731911D03*
X1021908Y60392D03*
Y120392D03*
X1012214Y141826D03*
X1015300Y148736D03*
X1012187Y148749D03*
X1008129Y150948D03*
X1009720Y160799D03*
X1013220D03*
X1012791Y157596D03*
X1006435Y172843D03*
X1012000Y185299D03*
X1014900D03*
X1017800D03*
X1017200Y175699D03*
X1014300D03*
X1019900Y175799D03*
X1009895Y192359D03*
X1008067Y194356D03*
X1020645Y190499D03*
X1019935Y206463D03*
Y203333D03*
X1019802Y214099D03*
X1011720Y229699D03*
X1019355Y222423D03*
X1019530Y226423D03*
X1007820Y229999D03*
X1018000Y263862D03*
X1022000Y264362D03*
X1014500Y263862D03*
X1010500D03*
X1018000Y266862D03*
X1022002Y267342D03*
X1010500Y266862D03*
X1006500D03*
X1014500Y269862D03*
X1018000D03*
X1022002Y270142D03*
X1006500Y269862D03*
X1010500D03*
X1010828Y304822D03*
Y307322D03*
Y309822D03*
X1021419Y305704D03*
X1020720Y310937D03*
X1013500Y344900D03*
X1021695Y364518D03*
X1006710Y372931D03*
X1015096Y373758D03*
X1017163Y367963D03*
X1015638Y382968D03*
X1015637Y391334D03*
X1006589Y392017D03*
X1006750Y401010D03*
X1015657Y401013D03*
X1015420Y410862D03*
X1021259Y420548D03*
X1007249Y422682D03*
X1011611Y430038D03*
X1017511D03*
X1009009Y419948D03*
X1021239Y416974D03*
X1016261Y432888D03*
X1012861D03*
X1008720Y498362D03*
X1019145Y503823D03*
X1018092Y520212D03*
X1011720Y589362D03*
X1018720Y592362D03*
X1016220Y590862D03*
X1021720Y601862D03*
X1011160Y594682D03*
X1010630Y748741D03*
X1007873Y748826D03*
X1007600Y1298250D03*
X1007610Y1295040D03*
X1021612Y1536262D03*
X1016012D03*
X1018612D03*
Y1551262D03*
X1016012D03*
X1018612Y1545262D03*
X1016012D03*
X1018612Y1548262D03*
X1016012D03*
X1021612Y1551262D03*
Y1545262D03*
Y1548262D03*
X1018612Y1542262D03*
X1016012D03*
X1021612D03*
Y1539262D03*
X1016012D03*
X1018612D03*
Y1554262D03*
X1016012D03*
X1021612D03*
X1012636Y1554364D03*
X1012354Y1579240D03*
Y1573240D03*
Y1576240D03*
X1021942Y1586090D03*
X1019252Y1620870D03*
X1022252D03*
Y1623870D03*
Y1626870D03*
X1019252Y1623870D03*
Y1626870D03*
X1019910Y1662700D03*
Y1665200D03*
X1012208Y1731911D03*
X1032433Y-29811D03*
Y-33211D03*
X1034929Y-33989D03*
Y-29033D03*
X1026705Y-27695D03*
X1023407Y-27681D03*
X1029700Y-26472D03*
X1026705Y-38224D03*
X1023437Y-38210D03*
X1026690Y-35709D03*
X1023422Y-35695D03*
X1026705Y-32069D03*
X1023407Y-32055D03*
X1029700Y-37001D03*
X1032433Y-13211D03*
Y-9811D03*
X1034929Y-13989D03*
Y-9033D03*
Y-23989D03*
Y-19033D03*
X1026705Y-17666D03*
X1026690Y-15151D03*
X1023407Y-17652D03*
X1023422Y-15137D03*
X1026705Y-11511D03*
X1023407Y-11497D03*
X1029700Y-16443D03*
X1026690Y-25180D03*
X1023422Y-25166D03*
X1023407Y-21526D03*
X1026705Y-21540D03*
X1034929Y-3989D03*
Y967D03*
X1029700Y3615D03*
X1023422Y4921D03*
X1023407Y2406D03*
X1026690Y4907D03*
X1026705Y2392D03*
X1023422Y-5108D03*
X1023407Y-7623D03*
X1026690Y-5122D03*
X1026705Y-7637D03*
Y-1482D03*
X1023407Y-1468D03*
X1029700Y-6414D03*
X1023407Y22464D03*
X1026705Y22450D03*
Y18576D03*
X1023407Y18590D03*
X1026705Y8547D03*
X1023407Y8561D03*
X1023422Y14950D03*
X1023407Y12435D03*
X1026690Y14936D03*
X1026705Y12421D03*
X1029700Y13644D03*
Y23673D03*
X1023422Y24979D03*
X1026690Y24965D03*
X1038609Y49388D03*
X1027520Y122732D03*
X1037650Y128842D03*
X1026620Y125662D03*
X1034229Y128953D03*
X1032894Y155185D03*
X1022800Y175799D03*
X1023220Y187574D03*
X1025000Y264362D03*
X1031502Y267342D03*
X1028202D03*
X1025102D03*
X1031702Y264130D03*
X1033133Y272564D03*
X1031502Y270142D03*
X1029833Y272564D03*
X1026733D03*
X1023633D03*
X1028202Y270142D03*
X1025102D03*
X1036915Y290969D03*
X1032317Y291284D03*
X1036278Y303993D03*
X1033285Y353627D03*
X1029395Y375844D03*
X1031950Y383771D03*
Y387171D03*
X1029094Y383070D03*
Y387872D03*
X1026820Y394362D03*
X1033860Y400802D03*
X1038320Y407062D03*
Y404462D03*
X1026548Y400571D03*
X1035920Y428962D03*
Y420062D03*
Y417462D03*
X1027190Y510672D03*
X1026370Y503562D03*
X1029220Y520032D03*
X1038220Y589862D03*
X1030980Y598722D03*
X1023740Y596152D03*
X1036480Y596272D03*
X1024154Y601152D03*
X1026654Y596152D03*
X1035760Y592952D03*
X1033260Y601272D03*
X1038260D03*
X1033817Y735612D03*
X1036954Y734669D03*
X1030660Y735082D03*
X1027212Y1536262D03*
X1024612D03*
Y1551262D03*
X1027212D03*
X1024612Y1545262D03*
X1027212D03*
X1024612Y1548262D03*
X1027212D03*
X1024612Y1542262D03*
X1027212D03*
Y1539262D03*
X1024612D03*
Y1554262D03*
X1027212D03*
X1036002Y1554364D03*
X1035720Y1579240D03*
Y1573240D03*
Y1576240D03*
X1030942Y1586090D03*
X1033942D03*
X1024942D03*
X1027942D03*
X1028298Y1604000D03*
X1025252Y1620870D03*
X1034252Y1623870D03*
Y1626870D03*
X1031252Y1623870D03*
Y1626870D03*
X1025252Y1623870D03*
X1028252D03*
Y1626870D03*
X1025252D03*
X1031252Y1620870D03*
X1034252D03*
X1028252D03*
X1023580Y1662700D03*
Y1665200D03*
X1027370Y1662700D03*
Y1665200D03*
X1032208Y1731911D03*
X1040970Y128332D03*
X1053028Y246518D03*
X1053428Y261118D03*
X1040924Y286073D03*
X1043629Y375078D03*
Y372578D03*
X1054820Y370162D03*
X1044120Y366362D03*
X1049100Y390162D03*
X1040120Y393962D03*
X1042720D03*
X1046156Y442699D03*
X1041420Y443962D03*
X1043920D03*
X1050470Y447062D03*
X1041444Y506504D03*
X1053690Y520760D03*
X1043720Y589362D03*
X1045720Y591672D03*
X1050200Y598062D03*
X1050390Y604172D03*
X1043260Y601272D03*
X1048260D03*
X1053200Y612162D03*
X1053745Y742341D03*
X1053354Y1286714D03*
Y1291714D03*
X1039510Y1296655D03*
X1049510D03*
X1044510D03*
X1039510Y1293155D03*
X1049510D03*
X1044510D03*
X1053354Y1296714D03*
X1041798Y1536262D03*
X1047798D03*
X1050498D03*
X1044798D03*
X1039298D03*
X1041798Y1551262D03*
X1039298D03*
X1041798Y1545262D03*
X1039298D03*
X1041798Y1548262D03*
X1039298D03*
X1047798Y1551262D03*
X1050498D03*
X1047798Y1545262D03*
X1050498D03*
X1047798Y1548262D03*
X1050498D03*
X1044798Y1551262D03*
Y1545262D03*
Y1548262D03*
X1039298Y1542262D03*
X1044798D03*
X1050498D03*
X1047798D03*
X1041798D03*
X1044798Y1539262D03*
X1050498D03*
X1047798D03*
X1039298D03*
X1041798D03*
Y1554262D03*
X1039298D03*
X1047798D03*
X1050498D03*
X1044798D03*
X1053612Y1586010D03*
X1050721Y1633043D03*
X1053721D03*
Y1624043D03*
Y1627043D03*
Y1630043D03*
X1050721Y1624043D03*
Y1627043D03*
Y1630043D03*
X1053721Y1621043D03*
X1050721D03*
X1044850Y1665050D03*
Y1662550D03*
X1052208Y1731911D03*
X1058609Y49388D03*
X1067220Y145362D03*
X1066820Y151632D03*
X1067220Y142862D03*
Y148362D03*
X1058028Y246518D03*
X1055528D03*
X1068093Y265503D03*
X1058428Y261118D03*
X1055928D03*
X1067618Y273800D03*
X1070718Y273700D03*
X1067718Y288500D03*
X1070618D03*
X1067718Y285600D03*
X1070618D03*
X1059943Y435314D03*
X1056190Y520760D03*
X1061470Y585862D03*
X1056280Y601232D03*
X1056220Y605052D03*
X1055205Y744853D03*
X1063354Y1286714D03*
X1058354D03*
X1063354Y1291714D03*
X1058354D03*
X1063354Y1296714D03*
X1058290Y1296302D03*
X1071179Y1294669D03*
X1066462Y1520088D03*
X1065164Y1536262D03*
X1062464D03*
X1071164D03*
X1068164D03*
X1065164Y1551262D03*
X1062464D03*
X1065164Y1545262D03*
X1062464D03*
X1065164Y1548262D03*
X1062464D03*
X1071164Y1551262D03*
Y1545262D03*
Y1548262D03*
X1068164Y1551262D03*
Y1545262D03*
Y1548262D03*
Y1542262D03*
X1071164D03*
X1062464D03*
X1065164D03*
X1068164Y1539262D03*
X1071164D03*
X1062464D03*
X1065164D03*
Y1554262D03*
X1062464D03*
X1071164D03*
X1068164D03*
X1059368Y1554364D03*
X1059086Y1573240D03*
Y1576240D03*
X1062612Y1586010D03*
X1065612D03*
X1056612D03*
X1059612D03*
X1059898Y1604000D03*
X1065721Y1633043D03*
X1068721D03*
Y1624043D03*
Y1627043D03*
Y1630043D03*
X1065721Y1624043D03*
Y1627043D03*
Y1630043D03*
X1062721Y1633043D03*
Y1624043D03*
Y1627043D03*
Y1630043D03*
X1056721Y1633043D03*
X1059721D03*
X1056721Y1624043D03*
X1059721D03*
Y1627043D03*
X1056721D03*
X1059721Y1630043D03*
X1056721D03*
X1068721Y1621043D03*
X1065721D03*
X1062721D03*
X1059721D03*
X1056721D03*
X1078609Y49388D03*
X1075100Y55682D03*
X1071920Y53862D03*
X1084146Y67102D03*
X1079114Y75775D03*
X1080168Y90721D03*
X1078270Y93462D03*
X1081282Y180937D03*
X1086756Y187540D03*
X1077973Y246362D03*
X1083973D03*
X1080973D03*
X1077883Y260842D03*
X1076823Y265438D03*
X1083823D03*
X1083883Y260842D03*
X1080883D03*
X1080323Y265438D03*
X1082853Y269492D03*
X1079853D03*
X1075400Y273762D03*
X1078400D03*
X1081400D03*
X1084400D03*
X1087400D03*
X1076018Y289400D03*
X1079018D03*
X1082018D03*
X1085018D03*
X1084130Y298342D03*
X1086630D03*
X1076353Y363966D03*
X1078853D03*
X1077270Y369061D03*
Y379251D03*
X1087330Y369061D03*
Y374131D03*
Y379251D03*
X1075462Y386723D03*
X1078151Y413911D03*
X1078120Y411262D03*
X1084245Y435437D03*
X1078545Y435637D03*
X1081045D03*
X1087280Y435437D03*
X1073724Y476867D03*
X1081906Y472577D03*
X1079320Y473892D03*
X1076820D03*
X1073589Y506461D03*
X1082220Y522362D03*
X1085720Y522422D03*
X1073250Y582332D03*
X1084637Y744635D03*
X1083714Y1285144D03*
Y1288144D03*
Y1291144D03*
X1077634Y1294869D03*
X1074387Y1294652D03*
X1073864Y1536262D03*
X1085830D03*
X1073864Y1551262D03*
Y1545262D03*
Y1548262D03*
X1085830Y1551262D03*
Y1545262D03*
Y1548262D03*
Y1542262D03*
X1073864D03*
X1085830Y1539262D03*
X1073864D03*
Y1554262D03*
X1085830D03*
X1082734Y1554364D03*
X1084000Y1647110D03*
X1072208Y1731911D03*
X1098609Y49388D03*
X1097794Y67881D03*
X1094644Y67992D03*
X1102561Y78461D03*
X1102480Y133722D03*
X1090279Y126524D03*
X1099030Y245140D03*
X1088018Y289400D03*
X1089130Y298342D03*
X1091630D03*
X1094130D03*
X1089660Y408560D03*
X1095820Y420762D03*
X1090245Y435437D03*
X1096477Y744385D03*
X1093497Y744655D03*
X1089714Y1285144D03*
X1088530Y1536262D03*
X1091530D03*
X1088530Y1551262D03*
Y1545262D03*
Y1548262D03*
X1094530Y1551262D03*
X1097230D03*
X1094530Y1545262D03*
X1097230D03*
X1094530Y1548262D03*
X1097230D03*
X1091530Y1551262D03*
Y1545262D03*
Y1548262D03*
Y1542262D03*
X1097230D03*
X1094530D03*
X1088530D03*
X1091530Y1539262D03*
X1094530D03*
X1088530D03*
Y1554262D03*
X1094530D03*
X1097230D03*
X1091530D03*
X1092302Y1585650D03*
X1089302D03*
X1098302D03*
X1095302D03*
X1095436Y1603944D03*
X1099901Y1633203D03*
Y1624203D03*
Y1627203D03*
Y1630203D03*
Y1621203D03*
X1093901Y1633203D03*
X1096901D03*
Y1624203D03*
Y1627203D03*
Y1630203D03*
X1093901Y1624203D03*
Y1627203D03*
Y1630203D03*
X1090901Y1633203D03*
X1087901D03*
X1090901Y1624203D03*
X1087901D03*
Y1627203D03*
X1090901D03*
X1087901Y1630203D03*
X1090901D03*
X1096901Y1621203D03*
X1093901D03*
X1087901D03*
X1090901D03*
X1095900Y1646935D03*
X1095649Y1638875D03*
X1099457D03*
X1088790Y1641830D03*
X1102930Y1668690D03*
X1094225Y1671710D03*
X1091880Y1673720D03*
X1092072Y1734244D03*
X1118609Y49388D03*
X1110977Y55505D03*
X1110754Y60028D03*
X1113594Y69862D03*
X1109020Y80592D03*
X1118309Y111687D03*
X1115860Y113883D03*
X1109088Y234668D03*
X1111918Y237718D03*
Y240718D03*
X1109088Y237668D03*
Y240668D03*
X1117820Y456132D03*
X1113207Y744455D03*
X1118110Y1398010D03*
X1115853Y1426342D03*
Y1435532D03*
X1117574Y1448604D03*
X1114400Y1518237D03*
X1109118Y1526046D03*
X1113725Y1530935D03*
X1117407Y1628495D03*
X1113990Y1631370D03*
X1113325Y1627975D03*
X1106480Y1641275D03*
X1113110Y1666460D03*
X1104457Y1675490D03*
X1108320Y1680200D03*
X1116338Y1711380D03*
X1112130Y1711600D03*
X1112252Y1706170D03*
X1112200Y1709000D03*
X1113055Y1718338D03*
X1110663Y1719189D03*
X1119200Y1730300D03*
Y1727200D03*
X1114300Y1722700D03*
X1119300Y1724100D03*
X1111866Y1737108D03*
X1132856Y52926D03*
X1129948Y66786D03*
X1122278Y107549D03*
X1120420Y109829D03*
X1124858Y197309D03*
X1133041Y194137D03*
X1120544Y312200D03*
X1129995Y301637D03*
X1122059Y305673D03*
X1124985Y302578D03*
X1127402Y456174D03*
X1136051Y503324D03*
X1133720Y642862D03*
X1129420Y644062D03*
X1122980Y741312D03*
X1127972Y747250D03*
X1135750Y1255672D03*
X1127179Y1372700D03*
X1124679D03*
Y1370200D03*
X1127179D03*
X1129729Y1372700D03*
Y1370200D03*
Y1375200D03*
X1127179D03*
X1124679D03*
X1129729Y1377700D03*
Y1380200D03*
Y1385200D03*
Y1382700D03*
X1127179D03*
X1124679D03*
X1127179Y1380200D03*
Y1377700D03*
X1124679D03*
Y1380200D03*
Y1385200D03*
X1127179D03*
X1127788Y1397126D03*
X1135709Y1397119D03*
X1133209D03*
X1123674Y1414936D03*
X1121174D03*
X1123674Y1417536D03*
Y1420136D03*
X1121174Y1417536D03*
Y1420136D03*
X1123674Y1422736D03*
X1121174D03*
X1122879Y1431474D03*
Y1434024D03*
X1125995Y1439780D03*
X1136004Y1447858D03*
X1126117Y1450504D03*
X1123379Y1443583D03*
X1133169Y1445690D03*
X1129169Y1442998D03*
X1135568Y1442923D03*
X1129169Y1445719D03*
X1130841Y1462953D03*
X1128341Y1465453D03*
Y1462953D03*
X1130841Y1465453D03*
X1133841Y1462953D03*
Y1465453D03*
X1128341Y1468453D03*
X1130841D03*
X1133841D03*
X1128341Y1460453D03*
X1130841D03*
X1133841D03*
Y1471453D03*
X1130841D03*
X1128341D03*
X1127008Y1524203D03*
X1135748Y1524187D03*
X1127008Y1550285D03*
X1133780Y1550301D03*
X1132142Y1555301D03*
X1132187Y1582738D03*
X1135187D03*
X1132187Y1590738D03*
X1135187D03*
X1120472Y1615010D03*
X1124862D03*
X1131632Y1625969D03*
X1131866Y1737108D03*
X1138609Y49388D03*
X1145603Y73679D03*
X1140242Y101135D03*
X1152720Y180862D03*
X1150914Y197407D03*
X1148795Y213731D03*
X1141957Y227277D03*
X1144457D03*
X1139457D03*
X1148354Y222677D03*
X1146670Y230110D03*
X1142302Y366532D03*
X1137315Y379592D03*
X1148220Y501362D03*
X1138551Y503324D03*
X1144720Y501362D03*
Y498662D03*
X1142967Y592097D03*
X1138500Y586362D03*
X1142127Y586452D03*
X1140697Y608762D03*
X1150140Y610362D03*
X1142790Y611122D03*
X1150272Y638346D03*
X1142674Y1287608D03*
X1144247Y1372700D03*
Y1370200D03*
X1146797Y1372700D03*
X1149297D03*
X1146797Y1370200D03*
X1149297D03*
X1144247Y1375200D03*
X1146797D03*
X1149297D03*
X1144247Y1377700D03*
Y1380200D03*
Y1385200D03*
Y1382700D03*
X1146797D03*
X1149297D03*
X1146797Y1380200D03*
Y1377700D03*
X1149297Y1380200D03*
Y1377700D03*
Y1385200D03*
X1146797D03*
X1146118Y1397126D03*
X1138209Y1397119D03*
X1150843Y1415126D03*
X1148243D03*
X1150843Y1417726D03*
X1148243D03*
X1150732Y1420326D03*
X1149469Y1437098D03*
X1151669Y1435698D03*
Y1438598D03*
X1137311Y1445191D03*
X1147203Y1441968D03*
X1149569Y1440098D03*
X1151669Y1441498D03*
X1147203Y1439068D03*
X1141591Y1462853D03*
Y1465353D03*
Y1468353D03*
Y1471353D03*
Y1460353D03*
X1150821Y1459607D03*
Y1456587D03*
X1145108Y1476732D03*
X1138430Y1524150D03*
X1151497Y1524187D03*
X1149528Y1550301D03*
X1145410Y1540640D03*
X1143060Y1538380D03*
X1141654Y1550301D03*
X1137717Y1558020D03*
X1141690Y1552920D03*
X1152187Y1574738D03*
X1142187D03*
X1145187D03*
X1142187Y1582738D03*
X1145187D03*
X1152187D03*
X1141525Y1597630D03*
X1152187Y1590738D03*
X1142187D03*
X1145187D03*
X1150380Y1602590D03*
X1146960Y1618960D03*
X1152257Y1628910D03*
X1158609Y49388D03*
X1155703Y73679D03*
X1160720Y180862D03*
X1165440Y176450D03*
X1168710Y176590D03*
X1165000Y190962D03*
X1162500D03*
X1164300Y197262D03*
X1163732Y204887D03*
X1160732D03*
X1160630Y213870D03*
X1158172Y230157D03*
X1159460Y366025D03*
X1156790Y363231D03*
X1161690Y374110D03*
X1164320Y451062D03*
X1156100Y456342D03*
X1167190Y526922D03*
X1153467Y586462D03*
X1158300Y585862D03*
X1170740Y602132D03*
X1153490Y610322D03*
X1159912Y638216D03*
X1166722Y636206D03*
X1158762Y642266D03*
X1168402Y642136D03*
X1155962Y746193D03*
X1156609Y1286685D03*
X1165279Y1372700D03*
X1162779D03*
X1167829D03*
X1162779Y1370200D03*
X1165279D03*
X1167829D03*
X1162779Y1375200D03*
X1165279D03*
X1167829D03*
Y1377700D03*
Y1380200D03*
Y1385200D03*
Y1382700D03*
X1165279D03*
X1162779D03*
X1165279Y1380200D03*
X1162779D03*
Y1377700D03*
X1165279D03*
X1162779Y1385200D03*
X1165279D03*
X1165931Y1397126D03*
X1154714Y1398295D03*
X1157786Y1398252D03*
X1153913Y1420606D03*
Y1415406D03*
Y1418006D03*
X1159124D03*
Y1420606D03*
Y1415406D03*
X1161724D03*
Y1420606D03*
Y1418006D03*
X1156524Y1415406D03*
Y1420606D03*
Y1418006D03*
X1153913Y1423206D03*
X1159124D03*
X1161724D03*
X1156524D03*
X1161022Y1431499D03*
Y1433999D03*
X1164138Y1439780D03*
X1154288Y1432502D03*
X1155964Y1440864D03*
X1164260Y1450423D03*
X1158954Y1450274D03*
X1161522Y1443630D03*
X1167312Y1442998D03*
Y1445964D03*
X1159386Y1464253D03*
Y1466753D03*
X1156386Y1464253D03*
Y1466753D03*
X1159386Y1469253D03*
X1156386D03*
X1153821Y1459607D03*
Y1456587D03*
X1159386Y1461753D03*
X1159476Y1458918D03*
X1156386Y1461753D03*
X1156476Y1458918D03*
X1159446Y1456113D03*
X1156446D03*
X1167245Y1524187D03*
X1159371D03*
X1165276Y1550301D03*
X1157402D03*
X1161595Y1574738D03*
X1164595D03*
X1155187D03*
X1161595Y1582738D03*
X1164595D03*
X1155187D03*
X1163079Y1601479D03*
X1161595Y1590738D03*
X1164595D03*
X1155187D03*
X1168192Y1604130D03*
X1152950Y1616470D03*
X1165950Y1617729D03*
X1152930Y1633880D03*
X1158030Y1619250D03*
X1163970Y1620600D03*
X1159930Y1645632D03*
X1164830Y1654632D03*
X1159930D03*
X1161076Y1680624D03*
X1157700Y1681100D03*
X1174120Y57111D03*
X1175926Y69151D03*
X1180676Y106858D03*
X1170595Y170056D03*
X1181476Y172247D03*
X1184510Y188962D03*
X1173065Y194174D03*
X1173100Y186962D03*
X1172925Y202174D03*
X1181369Y199234D03*
X1183460Y205342D03*
X1172865Y210174D03*
X1172835Y218174D03*
X1181500Y211962D03*
Y218462D03*
Y215962D03*
X1180398Y289814D03*
X1171540Y310902D03*
X1181450Y306052D03*
X1169690Y526922D03*
X1172720Y527862D03*
X1172310Y584562D03*
X1181300Y584762D03*
X1174980Y585632D03*
X1174880Y592652D03*
X1170337Y607327D03*
X1173990Y602192D03*
X1177570Y602052D03*
X1175217Y595762D03*
X1176362Y636076D03*
X1180262Y642216D03*
X1183230Y739102D03*
X1173020Y745972D03*
X1175573Y1286765D03*
X1172573D03*
X1182747Y1372700D03*
X1185297D03*
X1182747Y1370200D03*
X1185297D03*
X1182747Y1375200D03*
X1185297D03*
X1182747Y1380200D03*
Y1377700D03*
Y1385200D03*
Y1382700D03*
X1185297D03*
Y1377700D03*
Y1380200D03*
Y1385200D03*
X1184661Y1397126D03*
X1171752Y1397119D03*
X1176752D03*
X1174252D03*
X1174147Y1447858D03*
X1171342Y1445650D03*
X1175454Y1445191D03*
X1173711Y1442923D03*
X1179922Y1524203D03*
X1171182Y1524187D03*
X1179922Y1550285D03*
X1184330Y1573260D03*
X1184290Y1570080D03*
X1171595Y1574738D03*
X1174595D03*
X1171595Y1582738D03*
X1174595D03*
X1183410Y1594450D03*
X1183440Y1591640D03*
X1171595Y1590738D03*
X1174595D03*
X1178140Y1601100D03*
X1183320Y1597080D03*
X1184501Y1606521D03*
X1169968Y1602370D03*
X1174550Y1615630D03*
X1178250Y1609100D03*
X1184200Y1602700D03*
X1185030Y1633010D03*
X1182470Y1618914D03*
X1172530Y1623020D03*
X1176900Y1627510D03*
X1181930Y1645632D03*
X1170930D03*
X1181930Y1654632D03*
X1175830D03*
X1170930D03*
X1183076Y1680624D03*
X1172076D03*
X1198609Y49388D03*
X1194478Y56986D03*
X1188720Y56755D03*
X1191700Y56822D03*
X1197520Y56962D03*
X1201158Y57130D03*
X1189393Y60183D03*
X1185500Y101400D03*
X1190700Y99000D03*
X1188700Y100700D03*
X1185400Y104000D03*
X1197627Y132859D03*
X1185420Y153762D03*
X1200720Y184862D03*
X1196100Y188962D03*
X1193500D03*
X1188300Y189062D03*
X1200720Y187862D03*
X1200963Y212648D03*
X1192600Y217662D03*
X1193000Y204486D03*
X1195500D03*
X1195100Y217662D03*
X1200830Y206002D03*
X1186340Y204492D03*
X1187300Y217862D03*
X1188500Y205772D03*
X1188600Y225962D03*
X1187013Y238972D03*
X1194840Y236592D03*
X1199720Y252362D03*
X1196720D03*
X1188810Y296088D03*
X1186280Y298972D03*
X1199027Y588714D03*
X1193198Y586172D03*
X1195698D03*
X1198198D03*
X1200698D03*
X1189902Y642086D03*
X1185687Y744475D03*
X1187797Y1372700D03*
Y1370200D03*
Y1375200D03*
Y1382700D03*
Y1377700D03*
Y1380200D03*
Y1385200D03*
X1189135Y1397529D03*
X1187736Y1420387D03*
X1188986Y1415287D03*
Y1417887D03*
X1186386Y1415287D03*
Y1417887D03*
X1191486Y1415287D03*
Y1417887D03*
X1190444Y1420384D03*
X1194750Y1424672D03*
X1191930Y1424647D03*
X1187412Y1437498D03*
X1189612Y1436098D03*
X1191918Y1432516D03*
X1185346Y1442128D03*
X1187512Y1440498D03*
X1189612Y1441898D03*
X1185346Y1439228D03*
X1189612Y1438998D03*
X1187720Y1517688D03*
X1198546Y1520188D03*
X1187830Y1526688D03*
X1198436Y1529362D03*
X1187720Y1531862D03*
X1198497Y1539667D03*
X1187720Y1548772D03*
X1198436Y1546492D03*
Y1556192D03*
X1197181Y1563587D03*
X1187720Y1558682D03*
X1194510Y1563076D03*
X1187600Y1622064D03*
X1199400Y1627800D03*
X1192500Y1645942D03*
X1186000Y1640000D03*
X1197400Y1654942D03*
X1192500D03*
X1186830Y1654632D03*
X1201110Y1681767D03*
X1193646Y1680934D03*
X1201106Y1677873D03*
X1192340Y1691422D03*
Y1700422D03*
X1197240D03*
X1193174Y1726414D03*
X1191866Y1737108D03*
X1213026Y56742D03*
X1216176D03*
X1201800Y94600D03*
X1202860Y120392D03*
X1206093Y120362D03*
X1204800Y108900D03*
X1206900Y115900D03*
X1215800Y111300D03*
X1201700Y110000D03*
X1202920Y117162D03*
X1210910Y129502D03*
X1206434Y129492D03*
X1214573Y148909D03*
X1206664Y158952D03*
X1214091Y164962D03*
X1214593Y168962D03*
X1214534Y157462D03*
X1203858Y185451D03*
X1214693Y174962D03*
X1214134Y180972D03*
X1213720Y200309D03*
X1204420Y195362D03*
X1213720Y189362D03*
X1204220D03*
X1203200Y202514D03*
X1210084Y224362D03*
X1217720Y249862D03*
X1207220Y243998D03*
X1208365Y271151D03*
X1204475Y350684D03*
X1207100Y600882D03*
X1204880Y754032D03*
X1211277Y744265D03*
X1206757Y744455D03*
X1210288Y754081D03*
X1202300Y753962D03*
X1207607Y754095D03*
X1202600Y759662D03*
X1215896Y756942D03*
X1206432Y758995D03*
X1202307Y757082D03*
X1210830Y1676500D03*
X1213910Y1691732D03*
X1203110Y1691467D03*
X1207180Y1685680D03*
X1208010Y1700467D03*
X1213910Y1700732D03*
X1203110Y1700467D03*
X1203939Y1726459D03*
X1214834Y1726724D03*
X1211866Y1737108D03*
X1218609Y49388D03*
X1228420Y58862D03*
X1230250Y89450D03*
X1228425Y91500D03*
X1222100Y91600D03*
X1225700Y108962D03*
X1228704Y112122D03*
X1232182Y110659D03*
X1224614Y116962D03*
X1219534Y116492D03*
X1223100Y127300D03*
X1226400Y125200D03*
X1226093Y134262D03*
X1223100Y130700D03*
X1226093Y152792D03*
X1234093Y144962D03*
X1226093Y140962D03*
X1222593D03*
X1222920Y144909D03*
Y148909D03*
X1222593Y168962D03*
X1222890Y157002D03*
X1226093Y156962D03*
X1222594Y154242D03*
X1226093Y168162D03*
X1225874Y163462D03*
X1222720Y163362D03*
X1226093Y177962D03*
X1222724Y176102D03*
X1226093Y172962D03*
X1223134Y190802D03*
X1228520Y202162D03*
X1229720Y197302D03*
X1226093Y193462D03*
X1233282Y201875D03*
X1223720Y217862D03*
Y205862D03*
X1223180Y210552D03*
X1231720Y217862D03*
Y209862D03*
X1232000Y244332D03*
X1219220Y243862D03*
Y247148D03*
X1227500Y380400D03*
X1221220Y380362D03*
X1232720Y377862D03*
X1223650Y520672D03*
X1230650D03*
X1227150D03*
X1219060Y757272D03*
X1223327Y757615D03*
X1228320Y758598D03*
X1218810Y1700732D03*
X1231866Y1737108D03*
X1238609Y49388D03*
X1236620Y58862D03*
X1239907Y95008D03*
X1241010Y110782D03*
X1243808Y116832D03*
X1250010Y117121D03*
X1241035Y114399D03*
X1247333Y121999D03*
X1234746Y136040D03*
X1240728Y136198D03*
X1240904Y151592D03*
X1238604Y150062D03*
X1242520Y165362D03*
X1244120Y167462D03*
X1239874Y182322D03*
X1236410Y201462D03*
X1236220Y189362D03*
X1236593Y197462D03*
X1236584Y205762D03*
X1236593Y209562D03*
X1236584Y217462D03*
X1236520Y213462D03*
X1245486Y203000D03*
X1245593Y211762D03*
X1236620Y221562D03*
X1245614Y227462D03*
X1245574Y234042D03*
X1244720Y230362D03*
X1245514Y224302D03*
X1245593Y219662D03*
X1239045Y224062D03*
X1245593Y241462D03*
X1246878Y248615D03*
X1240500Y248332D03*
X1246444Y256098D03*
X1236720Y257362D03*
X1243589Y379595D03*
X1236720Y377862D03*
X1234720Y380362D03*
X1248150Y520672D03*
X1244650D03*
X1241150D03*
X1237650D03*
X1234150D03*
X1242260Y757602D03*
X1258609Y49388D03*
X1261227Y52061D03*
X1258727D03*
X1263454Y83060D03*
X1266464Y83090D03*
X1264098Y88787D03*
X1262320Y96012D03*
X1262800Y101100D03*
X1264620Y92724D03*
X1258539Y100900D03*
X1252520Y92022D03*
X1258539Y109263D03*
X1260641Y114399D03*
X1252961Y111903D03*
X1264220Y110462D03*
X1250424Y108943D03*
X1257581Y114579D03*
X1266093Y129962D03*
X1256093Y143462D03*
X1264663Y158946D03*
X1254994Y157382D03*
X1264685Y175506D03*
X1253624Y201362D03*
X1264874Y217462D03*
X1256504D03*
X1255613Y209568D03*
X1265207Y208442D03*
X1256070Y229512D03*
X1264584Y226592D03*
X1256593Y221462D03*
Y233972D03*
Y225972D03*
X1256494Y243177D03*
X1256574Y238662D03*
X1266518Y237042D03*
X1256584Y248002D03*
X1256454Y252122D03*
X1264854Y253996D03*
Y256496D03*
X1258883Y280558D03*
X1255150Y306211D03*
X1260220Y477362D03*
X1251650Y520672D03*
X1255150D03*
X1256787Y749605D03*
X1258667Y751405D03*
X1255520Y747362D03*
X1263486Y739949D03*
X1253586Y1334649D03*
X1257672Y1351008D03*
X1251866Y1737108D03*
X1276820Y58142D03*
X1282360Y58132D03*
X1279580D03*
X1278300Y81232D03*
X1279390Y87697D03*
X1270329Y101011D03*
X1266722Y101005D03*
X1278456Y96187D03*
X1279415Y90847D03*
X1281704Y95402D03*
X1279485Y105752D03*
X1282824Y108872D03*
X1278993Y193262D03*
X1273093Y200038D03*
X1275493Y193962D03*
X1267289Y192167D03*
X1269904Y192692D03*
X1267773Y208373D03*
X1275727Y209597D03*
X1267618Y225382D03*
X1267593Y229462D03*
X1282176Y221436D03*
X1278320Y239292D03*
X1282293Y248962D03*
X1279493Y248662D03*
X1282645Y255671D03*
Y252271D03*
X1280223Y256841D03*
X1279841Y253052D03*
X1277771Y255173D03*
X1273754Y256504D03*
X1275557Y269477D03*
Y272436D03*
X1282653Y269446D03*
X1278557Y272436D03*
Y269477D03*
X1272557Y272436D03*
X1271150Y305792D03*
X1269220Y477362D03*
X1274420Y463362D03*
X1275576Y730879D03*
X1266727Y752955D03*
X1279788Y1304042D03*
X1280135Y1340002D03*
Y1337402D03*
X1272707Y1334865D03*
X1280135Y1345202D03*
Y1342602D03*
X1279812Y1353552D03*
X1279334Y1356089D03*
X1280312Y1365689D03*
X1275856Y1358098D03*
X1271990Y1358079D03*
X1276891Y1362891D03*
X1282928Y1361833D03*
X1269012Y1368293D03*
X1271866Y1737108D03*
X1290291Y-29811D03*
Y-33211D03*
X1287795Y-29033D03*
Y-33989D03*
X1296019Y-35472D03*
Y-31598D03*
X1293024Y-36695D03*
X1296034Y-37987D03*
Y-27958D03*
X1296019Y-25443D03*
X1293024Y-26666D03*
X1290291Y-13211D03*
Y-9811D03*
X1287795Y-9033D03*
Y-13989D03*
Y-19033D03*
Y-23989D03*
X1296019Y-21569D03*
X1293024Y-16637D03*
X1296034Y-17929D03*
X1296019Y-15414D03*
Y-11540D03*
X1287795Y967D03*
Y-3989D03*
X1296034Y-7900D03*
X1296019Y-5385D03*
X1293024Y-6608D03*
X1296019Y4644D03*
X1296034Y2129D03*
X1296019Y-1511D03*
X1293024Y3421D03*
X1296019Y14673D03*
X1296034Y12158D03*
X1296019Y8518D03*
X1293024Y13450D03*
X1296034Y22687D03*
X1296019Y19047D03*
Y25202D03*
X1293024Y23979D03*
X1291280Y58262D03*
X1293860Y58312D03*
X1285201Y58121D03*
X1293430Y84072D03*
X1289210Y81232D03*
X1294354Y103166D03*
Y105912D03*
X1291704Y109427D03*
X1295053Y140181D03*
X1292293Y143162D03*
X1283425Y179272D03*
X1287943Y233748D03*
X1284437Y230280D03*
X1293893Y237962D03*
X1286611Y260908D03*
X1291071Y275543D03*
Y278543D03*
X1290005Y293768D03*
X1295278Y297056D03*
X1290322D03*
X1290005Y290268D03*
X1294500Y299692D03*
X1291100D03*
X1295887Y315571D03*
X1291500Y312862D03*
Y315362D03*
X1291420Y320662D03*
Y318162D03*
X1296630Y463462D03*
X1284220Y463362D03*
X1289936Y732539D03*
X1294937Y746965D03*
X1290520Y746562D03*
X1292904Y782048D03*
X1292572Y785575D03*
X1292614Y789910D03*
X1296719Y1290197D03*
X1299169Y1295467D03*
Y1297967D03*
X1296569D03*
Y1295467D03*
Y1292967D03*
X1299169D03*
X1296581Y1300474D03*
X1299181D03*
X1296576Y1303298D03*
X1299176D03*
X1295150Y1323217D03*
X1298150D03*
X1291010Y1323307D03*
X1288010D03*
X1283280Y1372301D03*
X1293887Y1370043D03*
X1294477Y1372651D03*
X1290102Y1365789D03*
X1286102Y1365051D03*
X1294312Y1367279D03*
X1292840Y1364821D03*
X1286102Y1368107D03*
X1291866Y1737108D03*
X1299317Y-35486D03*
Y-31612D03*
X1299302Y-38001D03*
Y-27972D03*
X1299317Y-25457D03*
Y-21583D03*
X1299302Y-17943D03*
X1299317Y-15428D03*
Y-11554D03*
X1299302Y-7914D03*
X1299317Y-5399D03*
Y4630D03*
X1299302Y2115D03*
X1299317Y-1525D03*
Y14659D03*
X1299302Y12144D03*
X1299317Y8504D03*
X1299302Y22673D03*
X1299317Y19033D03*
X1299287Y25188D03*
X1311960Y49672D03*
X1301820Y58672D03*
X1314741Y68652D03*
X1311424D03*
X1308174D03*
X1311960Y58152D03*
X1310857Y78542D03*
X1307120Y78562D03*
X1310906Y97807D03*
X1300454Y95302D03*
X1314059Y93877D03*
X1307244Y118452D03*
X1306836Y108242D03*
X1302060Y113852D03*
X1302964Y124633D03*
X1300990Y121812D03*
X1315156Y130656D03*
X1314920Y135361D03*
X1301993Y140462D03*
X1313117Y250605D03*
X1314685Y248651D03*
X1313950Y261612D03*
X1307431Y256099D03*
X1309283Y254162D03*
X1311275Y252297D03*
X1305552Y257974D03*
X1308736Y284948D03*
X1312136D03*
X1308790Y290172D03*
X1302450Y290072D03*
X1307798Y287561D03*
X1313246Y287631D03*
X1307042Y292636D03*
X1303642D03*
X1307442Y306998D03*
X1304042D03*
X1308220Y304262D03*
X1303120Y304162D03*
X1307677Y322996D03*
X1311077D03*
X1314450Y319841D03*
X1312845Y324764D03*
X1305909D03*
X1308600Y653500D03*
X1311420Y738262D03*
X1315020Y739862D03*
X1307469Y787772D03*
X1303017Y785837D03*
X1301034Y784165D03*
X1304260Y788265D03*
X1309930Y789852D03*
X1306701Y794779D03*
X1309210Y792802D03*
X1315169Y1274887D03*
X1315289Y1269717D03*
X1315229Y1272287D03*
X1304149Y1291317D03*
X1301889Y1284987D03*
X1301829Y1290167D03*
X1301859Y1287587D03*
X1304299Y1280967D03*
X1304269Y1283567D03*
X1304239Y1286147D03*
X1304209Y1288747D03*
X1315176Y1280218D03*
X1315181Y1277594D03*
X1299319Y1290197D03*
X1299349Y1287617D03*
X1301686Y1303268D03*
X1304196Y1299248D03*
X1304189Y1293917D03*
X1304201Y1296624D03*
X1301679Y1292937D03*
Y1295437D03*
Y1297937D03*
X1301691Y1300444D03*
X1307656Y1337104D03*
X1305056D03*
X1307656Y1326704D03*
X1305056D03*
X1307656Y1334504D03*
Y1329304D03*
Y1331904D03*
X1305056Y1334504D03*
Y1329304D03*
Y1331904D03*
Y1339704D03*
X1311820Y1330518D03*
Y1333018D03*
X1314936Y1338799D03*
X1312488Y1348353D03*
X1315058Y1349488D03*
X1312650Y1342572D03*
X1308616Y1363345D03*
Y1360445D03*
X1306082Y1359315D03*
X1306182Y1362315D03*
X1304016Y1363945D03*
Y1361045D03*
X1308616Y1357945D03*
X1311866Y1737108D03*
X1318609Y49388D03*
X1316459Y58697D03*
X1330102Y59025D03*
X1321279Y58767D03*
X1317831Y68652D03*
X1316478Y92970D03*
X1329891Y99455D03*
X1329646Y104954D03*
X1330273Y128373D03*
X1326493Y249562D03*
X1317893Y257462D03*
X1328393Y264262D03*
X1325414Y293556D03*
X1328814D03*
X1319903Y299176D03*
X1323303D03*
X1319125Y296540D03*
X1324081D03*
X1324636Y290920D03*
X1329592D03*
X1319618Y318073D03*
X1325080Y323902D03*
X1316218Y318073D03*
X1328480Y323902D03*
X1330248Y325670D03*
X1323312D03*
X1321386Y319841D03*
X1329977Y334384D03*
X1330101Y540049D03*
X1327601D03*
X1328530Y747702D03*
X1325210Y744322D03*
X1331519Y1262027D03*
X1331459Y1264597D03*
X1331399Y1267197D03*
X1317889Y1267147D03*
X1320399Y1267117D03*
X1317883Y1269978D03*
X1317895Y1272485D03*
X1320393Y1269948D03*
X1320405Y1272455D03*
X1331177Y1269933D03*
Y1272433D03*
X1317895Y1274985D03*
X1320405Y1274955D03*
X1331177Y1274933D03*
X1331166Y1280248D03*
X1317746D03*
X1320256Y1280218D03*
X1317895Y1277485D03*
X1320405Y1277455D03*
X1331189Y1277440D03*
X1324945Y1346877D03*
X1327196Y1349068D03*
X1322110Y1342755D03*
X1318110Y1342017D03*
X1326320Y1344245D03*
X1324848Y1341787D03*
X1318110Y1345073D03*
X1331288Y1372440D03*
X1327491Y1372358D03*
X1324491Y1372658D03*
X1327491Y1375858D03*
X1331288Y1375940D03*
X1324491Y1375858D03*
X1327491Y1381478D03*
Y1378478D03*
X1331288Y1378560D03*
X1324491Y1381478D03*
Y1378478D03*
X1331304Y1401986D03*
Y1404986D03*
X1327926D03*
X1322228Y1419890D03*
X1322186Y1411326D03*
Y1414326D03*
Y1417326D03*
X1322270Y1422454D03*
X1325084Y1420066D03*
X1325042Y1408502D03*
Y1411502D03*
Y1417502D03*
Y1414502D03*
X1331344Y1414456D03*
X1330804Y1411536D03*
Y1408536D03*
X1331386Y1420020D03*
X1328008D03*
X1331344Y1417456D03*
X1327966Y1408456D03*
Y1411456D03*
Y1417456D03*
Y1414456D03*
X1331428Y1422584D03*
X1328050D03*
X1322312Y1425018D03*
X1325126Y1422630D03*
X1325168Y1425194D03*
X1328092Y1425148D03*
X1331470D03*
X1341752Y-29811D03*
Y-33211D03*
X1344248Y-33989D03*
Y-29033D03*
X1332726Y-27681D03*
X1336024Y-27695D03*
X1339019Y-26472D03*
X1332726Y-32055D03*
X1336024Y-32069D03*
X1332741Y-35695D03*
X1336009Y-35709D03*
X1332756Y-38210D03*
X1336024Y-38224D03*
X1339019Y-37001D03*
X1341752Y-9811D03*
Y-13211D03*
X1344248Y-13989D03*
Y-9033D03*
Y-23989D03*
Y-19033D03*
X1332726Y-11497D03*
X1336024Y-11511D03*
X1339019Y-16443D03*
X1332741Y-15137D03*
X1332726Y-17652D03*
X1336009Y-15151D03*
X1336024Y-17666D03*
Y-21540D03*
X1332726Y-21526D03*
X1332741Y-25166D03*
X1336009Y-25180D03*
X1344248Y-3989D03*
Y967D03*
X1336024Y2392D03*
X1336009Y4907D03*
X1332726Y2406D03*
X1332741Y4921D03*
X1339019Y3615D03*
X1332726Y-1468D03*
X1336024Y-1482D03*
X1339019Y-6414D03*
X1336024Y-7637D03*
X1336009Y-5122D03*
X1332726Y-7623D03*
X1332741Y-5108D03*
X1332726Y18590D03*
X1336024Y18576D03*
Y22450D03*
X1332726Y22464D03*
X1339019Y13644D03*
X1336024Y12421D03*
X1336009Y14936D03*
X1332726Y12435D03*
X1332741Y14950D03*
X1332726Y8561D03*
X1336024Y8547D03*
X1336009Y24965D03*
X1332741Y24979D03*
X1339019Y23673D03*
X1338609Y49388D03*
X1333190Y58825D03*
X1346720Y82912D03*
X1345583Y91307D03*
X1336549Y105970D03*
X1339280Y126175D03*
X1344631Y127244D03*
X1332497Y133931D03*
X1343362Y283155D03*
X1336761Y293404D03*
X1340161D03*
X1335947Y290755D03*
X1340903D03*
X1335145Y332616D03*
X1341431Y322693D03*
X1331745Y332616D03*
X1338031Y322693D03*
X1345424Y328981D03*
X1343656Y330749D03*
X1343199Y324461D03*
X1336263D03*
X1336913Y334384D03*
X1344720Y423162D03*
X1337220D03*
X1342220D03*
X1339720D03*
X1333143Y540049D03*
X1340420Y538422D03*
Y541822D03*
X1338652Y536654D03*
Y543590D03*
X1335643Y540048D03*
X1336187Y755635D03*
X1347419Y1259257D03*
X1347379Y1256687D03*
X1336269Y1274957D03*
X1333969Y1264567D03*
X1334029Y1261997D03*
X1333909Y1267167D03*
X1336339Y1269777D03*
X1336279Y1272347D03*
X1347359Y1261857D03*
X1347371Y1264564D03*
X1336519Y1264627D03*
X1336579Y1262057D03*
X1347366Y1267188D03*
X1336459Y1267227D03*
X1333687Y1269903D03*
Y1272403D03*
Y1274903D03*
X1333676Y1280218D03*
X1336261Y1277654D03*
X1333699Y1277410D03*
X1339784Y1306506D03*
X1337184D03*
X1344080Y1305919D03*
X1337663Y1301001D03*
X1343968Y1300579D03*
X1340663Y1301001D03*
X1344080Y1308519D03*
X1337184Y1309106D03*
X1339784D03*
X1338534Y1319406D03*
X1339784Y1316906D03*
Y1314306D03*
Y1311706D03*
X1337184Y1314306D03*
Y1316906D03*
Y1311706D03*
X1343948Y1317092D03*
Y1319592D03*
X1347015Y1335876D03*
X1343631Y1332568D03*
X1344532Y1328161D03*
X1347397Y1325320D03*
X1336144Y1341147D03*
X1338288Y1339653D03*
X1340488Y1340853D03*
X1336144Y1338247D03*
X1340214Y1334853D03*
X1340410Y1338017D03*
X1338288Y1336553D03*
X1334288Y1372440D03*
X1340288D03*
X1346193Y1372523D03*
X1343193D03*
X1337288Y1372440D03*
Y1375940D03*
X1334288D03*
X1343193Y1376023D03*
X1346193D03*
X1340288Y1375940D03*
X1346304Y1401986D03*
X1343304D03*
X1340304D03*
X1337304D03*
X1334304D03*
Y1404986D03*
X1346304D03*
X1343304D03*
X1340304D03*
X1337304D03*
X1337344Y1414456D03*
X1346344D03*
X1343344D03*
X1340344D03*
X1346534Y1411496D03*
Y1408496D03*
X1334344Y1414456D03*
X1346344Y1417456D03*
X1340344D03*
X1337344D03*
X1334386Y1420020D03*
X1334344Y1417456D03*
X1346386Y1420020D03*
X1343386D03*
X1340386D03*
X1337386D03*
X1343344Y1417456D03*
X1337428Y1422584D03*
X1340428D03*
X1343428D03*
X1334428D03*
X1337328Y1425164D03*
X1340328D03*
X1343328D03*
X1346178Y1425254D03*
X1346278Y1422674D03*
X1334470Y1425148D03*
X1331866Y1737108D03*
X1348610Y84712D03*
X1349480Y77072D03*
X1350550Y101632D03*
X1349570Y104147D03*
X1356223Y131569D03*
X1353394Y131812D03*
X1348620Y136162D03*
X1349220Y140362D03*
X1363846Y279848D03*
X1349362Y283155D03*
X1353902Y287540D03*
X1359902D03*
X1348824Y328981D03*
X1358371Y332275D03*
X1361771D03*
X1350592Y330749D03*
X1355200Y337843D03*
X1351800D03*
X1356968Y339611D03*
X1350032D03*
X1363539Y334043D03*
X1356603D03*
X1356047Y680000D03*
X1358907Y681262D03*
X1352474Y1256866D03*
X1349964Y1256896D03*
X1352486Y1259373D03*
X1349976Y1259403D03*
X1363258Y1256851D03*
Y1259351D03*
X1349876Y1267158D03*
X1352426Y1267218D03*
X1363266Y1267188D03*
X1349976Y1261903D03*
X1352486Y1261873D03*
Y1264373D03*
X1349976Y1264403D03*
X1363258Y1261851D03*
X1363270Y1264358D03*
X1353982Y1287048D03*
X1362382D03*
X1359382D03*
X1350982D03*
X1356983Y1334095D03*
X1359516Y1334058D03*
X1354238Y1329329D03*
X1350238Y1328591D03*
X1358448Y1330819D03*
X1356976Y1328361D03*
X1350238Y1331647D03*
X1352666Y1378560D03*
X1349666D03*
X1352666Y1381560D03*
X1349666D03*
X1352666Y1375940D03*
X1349666D03*
X1355357Y1396020D03*
X1352126Y1401986D03*
X1349426D03*
X1352126Y1404986D03*
X1349426D03*
X1349508Y1420020D03*
X1352166Y1420456D03*
Y1414456D03*
Y1411456D03*
Y1408456D03*
Y1417456D03*
X1349466Y1411456D03*
Y1408456D03*
Y1417456D03*
Y1414456D03*
X1349278Y1422674D03*
X1362410Y1445272D03*
X1351866Y1737108D03*
X1378839Y87626D03*
X1366124Y101529D03*
X1366369Y92450D03*
X1378550Y110692D03*
X1366714Y109506D03*
X1376991Y176430D03*
X1373591D03*
X1375300Y208422D03*
X1375257Y229756D03*
X1373493Y227762D03*
X1378452Y236055D03*
X1377742Y244372D03*
Y250372D03*
X1377626Y258914D03*
Y264914D03*
X1369846Y279848D03*
X1372381Y661428D03*
X1371931Y672978D03*
Y685278D03*
X1372243Y697108D03*
Y709108D03*
Y721108D03*
X1374938Y1161569D03*
Y1170069D03*
X1379579Y1259317D03*
X1368379Y1259287D03*
X1379639Y1256747D03*
X1368439Y1256717D03*
X1365768Y1256821D03*
Y1259321D03*
X1365776Y1267158D03*
X1368326Y1267218D03*
X1379519Y1261917D03*
X1379531Y1264624D03*
X1379526Y1267248D03*
X1368361Y1264594D03*
X1368369Y1261897D03*
X1365768Y1261821D03*
X1365780Y1264328D03*
X1375463Y1287048D03*
X1372463D03*
X1370662Y1305980D03*
X1371912Y1303480D03*
X1376208Y1305919D03*
Y1303319D03*
X1371912Y1300880D03*
X1376208Y1300719D03*
Y1295586D03*
X1371912Y1295747D03*
Y1298280D03*
X1376208Y1298119D03*
X1369312Y1303480D03*
Y1300880D03*
Y1295747D03*
Y1298280D03*
X1376208Y1308519D03*
X1376076Y1317092D03*
Y1319592D03*
X1379192Y1325373D03*
X1368272Y1324821D03*
X1372538Y1324591D03*
X1370338Y1323091D03*
X1372538Y1321691D03*
X1379271Y1335963D03*
X1375814Y1332653D03*
X1377214Y1327653D03*
X1368272Y1327721D03*
X1370438Y1326091D03*
X1372538Y1327491D03*
X1377054Y1394028D03*
X1376666Y1402778D03*
X1376686Y1399758D03*
X1367316Y1399053D03*
Y1403458D03*
X1377060Y1411231D03*
X1367436Y1414778D03*
X1370891Y1410306D03*
X1378417Y1415292D03*
X1367316Y1407458D03*
X1367889Y1419235D03*
X1371960Y1436172D03*
X1365040Y1431142D03*
X1365235Y1428637D03*
X1370250Y1433715D03*
X1367620Y1431472D03*
X1367170Y1453142D03*
X1368842Y1449261D03*
X1364800Y1449231D03*
X1368980Y1457122D03*
X1370041Y1460374D03*
X1371866Y1737108D03*
X1393250Y93802D03*
X1383480Y88932D03*
X1389609Y145291D03*
X1389443Y147859D03*
X1395960Y226422D03*
X1393460D03*
X1386868Y222937D03*
X1384017Y223697D03*
X1386138Y225411D03*
X1384895Y221346D03*
X1381951Y221420D03*
X1381235Y236020D03*
X1383734Y243329D03*
Y237329D03*
X1388778Y250661D03*
X1390600Y248262D03*
X1388908Y260301D03*
X1386237Y265620D03*
Y275200D03*
X1385190Y501242D03*
X1390220Y497742D03*
X1392685Y498992D03*
X1387550Y502922D03*
X1387600Y499182D03*
X1391260Y507082D03*
X1381131Y656378D03*
Y668378D03*
X1395831Y666278D03*
X1386931Y660978D03*
X1381131Y680278D03*
X1396031Y680678D03*
X1386931Y675478D03*
X1387143Y690208D03*
X1380731Y692208D03*
X1395631Y695108D03*
X1380731Y704208D03*
X1387143Y704708D03*
X1380731Y716208D03*
X1395631Y709608D03*
X1387143Y719235D03*
X1395631Y724135D03*
X1382920Y733725D03*
X1391408Y738625D03*
X1384173Y1161549D03*
X1384089Y1153369D03*
X1386673Y1161520D03*
Y1153340D03*
X1396081Y1161569D03*
Y1153369D03*
X1384173Y1169599D03*
X1386673Y1169570D03*
X1396081Y1170069D03*
X1384652Y1256866D03*
X1382142Y1256896D03*
X1384664Y1259373D03*
X1382154Y1259403D03*
X1395436Y1256851D03*
Y1259351D03*
X1384586Y1267278D03*
X1395426Y1267188D03*
X1382036Y1267218D03*
X1382154Y1261903D03*
X1384664Y1261873D03*
Y1264373D03*
X1382154Y1264403D03*
X1395436Y1261851D03*
X1395448Y1264358D03*
X1390758Y1333473D03*
X1392076Y1335658D03*
X1386366Y1329329D03*
X1382366Y1328591D03*
X1390576Y1330819D03*
X1389104Y1328361D03*
X1382366Y1331647D03*
X1390474Y1385142D03*
X1388813Y1393160D03*
X1396115Y1405289D03*
Y1412789D03*
X1396615Y1420289D03*
X1387470Y1418302D03*
X1385109Y1410427D03*
X1387068Y1413991D03*
X1384695Y1425047D03*
X1381066Y1425008D03*
X1393630Y1426562D03*
X1395907Y1430227D03*
X1398569Y1437860D03*
X1392620Y1446708D03*
X1382600Y1563480D03*
X1384840Y1565640D03*
X1386790Y1563610D03*
X1392475Y1576097D03*
X1396600Y1582500D03*
Y1594000D03*
Y1590200D03*
Y1586400D03*
X1395325Y1606862D03*
X1386200Y1645700D03*
X1386600Y1641400D03*
X1391866Y1737108D03*
X1412954Y138742D03*
X1409558Y151948D03*
X1404402Y138742D03*
X1407029Y152732D03*
X1410370Y138742D03*
X1406970D03*
X1409558Y156904D03*
X1407029Y156132D03*
X1407613Y177159D03*
X1398770D03*
X1402258Y184263D03*
X1411101D03*
X1409716Y171696D03*
X1401240Y171672D03*
X1407178Y171684D03*
X1403778D03*
X1404630Y220018D03*
X1412270Y230952D03*
X1396900Y228932D03*
X1405436Y238378D03*
X1400207Y238257D03*
X1407913Y1161569D03*
X1410413Y1153369D03*
X1407913D03*
X1410613Y1161569D03*
X1398831D03*
Y1153369D03*
X1407913Y1170069D03*
X1410613D03*
X1398831D03*
X1411909Y1259257D03*
X1400599Y1256717D03*
X1411969Y1256687D03*
X1397946Y1256821D03*
Y1259321D03*
X1400539Y1259287D03*
X1400521Y1264594D03*
X1400529Y1261897D03*
X1397936Y1267158D03*
X1400486Y1267218D03*
X1411849Y1261857D03*
X1411861Y1264564D03*
X1411856Y1267188D03*
X1397946Y1261821D03*
X1397958Y1264328D03*
X1410819Y1287198D03*
X1407819D03*
X1399419D03*
X1402419D03*
X1404040Y1303480D03*
X1408336Y1305919D03*
Y1303319D03*
X1404040Y1300880D03*
X1408336Y1300719D03*
Y1295586D03*
X1404040Y1295747D03*
Y1298280D03*
X1408336Y1298119D03*
X1401440Y1303480D03*
X1402790Y1305980D03*
X1401440Y1300880D03*
Y1295747D03*
Y1298280D03*
X1408336Y1308519D03*
X1408204Y1317092D03*
Y1319592D03*
X1411320Y1325373D03*
X1400400Y1324821D03*
X1404666Y1324591D03*
X1402466Y1323091D03*
X1404666Y1321691D03*
X1411124Y1335924D03*
X1407719Y1332560D03*
X1408969Y1327645D03*
X1402566Y1326091D03*
X1400400Y1327721D03*
X1404666Y1327491D03*
X1406461Y1383862D03*
X1412961Y1387387D03*
X1403615Y1405289D03*
X1411115D03*
Y1412789D03*
X1403615Y1420289D03*
X1411115D03*
X1410477Y1440117D03*
X1410038Y1434670D03*
X1405876Y1453298D03*
X1403687Y1444711D03*
X1400287D03*
X1400220Y1518862D03*
X1403590Y1532255D03*
X1403350Y1521335D03*
X1409248Y1528862D03*
X1403740Y1548375D03*
X1403590Y1537155D03*
X1403740Y1543475D03*
X1400160Y1543342D03*
X1404433Y1565037D03*
X1407440Y1557552D03*
X1404433Y1570037D03*
X1402536Y1576097D03*
X1398700Y1597800D03*
X1407200Y1591400D03*
X1402680Y1597700D03*
X1411070Y1603282D03*
X1400000Y1630362D03*
X1410900Y1624800D03*
X1400000Y1642362D03*
Y1634362D03*
Y1638362D03*
X1396900Y1642100D03*
X1411866Y1737108D03*
X1420222Y184263D03*
X1418268Y171696D03*
X1413350Y220018D03*
X1416020D03*
X1424690D03*
X1424520Y225002D03*
X1416810Y225422D03*
X1428640Y230022D03*
X1428336Y232762D03*
X1418630Y220018D03*
X1422030D03*
X1413847Y239528D03*
X1426020Y261501D03*
X1428940Y269292D03*
X1426647Y329050D03*
X1417022Y621419D03*
X1424119Y1161520D03*
X1426619D03*
X1424119Y1153369D03*
X1426619D03*
Y1169570D03*
X1424119D03*
X1416999Y1256866D03*
X1414489Y1256896D03*
X1417011Y1259373D03*
X1414501Y1259403D03*
X1427783Y1256851D03*
Y1259351D03*
X1414366Y1267158D03*
X1416916Y1267218D03*
X1427786Y1267158D03*
X1414501Y1261903D03*
X1417011Y1261873D03*
Y1264373D03*
X1414501Y1264403D03*
X1427783Y1261851D03*
X1427795Y1264358D03*
X1421294Y1334095D03*
X1423656Y1335468D03*
X1418494Y1329329D03*
X1414494Y1328591D03*
X1422704Y1330819D03*
X1421232Y1328361D03*
X1414494Y1331647D03*
X1422594Y1383301D03*
X1419995Y1397492D03*
X1426872Y1405811D03*
X1421480Y1415731D03*
X1422371Y1407722D03*
X1419991Y1423404D03*
X1429345Y1433695D03*
X1424930Y1433850D03*
X1416272Y1433949D03*
X1421435Y1430415D03*
X1419746Y1435932D03*
X1427349Y1442776D03*
X1414264Y1439494D03*
X1419256Y1440258D03*
X1423829Y1442776D03*
X1414350Y1516435D03*
X1414590Y1532255D03*
X1414350Y1521335D03*
X1414590Y1537155D03*
X1414740Y1543475D03*
Y1548375D03*
X1418241Y1583441D03*
X1422145Y1575362D03*
X1422680Y1582100D03*
X1419450Y1596150D03*
X1423700Y1600400D03*
X1426680Y1603262D03*
X1425770Y1633772D03*
X1429250Y1623391D03*
X1419270Y1631000D03*
X1413230Y1641042D03*
X1438609Y49388D03*
X1434600Y59262D03*
X1441125Y57362D03*
X1438680Y64412D03*
X1444275Y57262D03*
X1432220Y61862D03*
X1440800Y66862D03*
X1447340Y157402D03*
X1429382Y184263D03*
X1442434Y210757D03*
X1441490Y224062D03*
X1438720Y220018D03*
X1430000D03*
X1430120Y225182D03*
X1431636Y230448D03*
X1444570Y238372D03*
X1431933Y238125D03*
X1430130Y259342D03*
X1431431Y267378D03*
X1436436Y300319D03*
X1436120Y315772D03*
X1436270Y312592D03*
X1436320Y305862D03*
Y303362D03*
X1436120Y318272D03*
X1436232Y344176D03*
X1437177Y720965D03*
X1433418Y729104D03*
X1435387Y1161569D03*
X1435837Y1153369D03*
X1432887Y1161569D03*
X1433337Y1153369D03*
X1435387Y1170069D03*
X1432887D03*
X1444099Y1259397D03*
X1432899Y1259257D03*
X1444159Y1256827D03*
X1432959Y1256687D03*
X1430293Y1256821D03*
Y1259321D03*
X1444051Y1264704D03*
X1444039Y1261997D03*
X1444046Y1267328D03*
X1432889Y1261867D03*
X1432881Y1264564D03*
X1432846Y1267188D03*
X1430296Y1267128D03*
X1430293Y1261821D03*
X1430305Y1264328D03*
X1437258Y1287198D03*
X1445106Y1287158D03*
X1440258Y1287198D03*
X1437182Y1298991D03*
X1434582Y1304191D03*
Y1306791D03*
Y1301591D03*
Y1296458D03*
Y1298991D03*
X1440507Y1305430D03*
Y1302830D03*
Y1300230D03*
X1440536Y1296455D03*
X1440464Y1308519D03*
X1437182Y1304191D03*
Y1306791D03*
Y1301591D03*
Y1296458D03*
X1440332Y1317092D03*
Y1319592D03*
X1443448Y1325373D03*
X1432528Y1324821D03*
X1436794Y1324591D03*
X1434594Y1323091D03*
X1436794Y1321691D03*
X1443785Y1335981D03*
X1440879Y1333085D03*
X1441332Y1327793D03*
X1434694Y1326091D03*
X1432528Y1327721D03*
X1436794Y1327491D03*
X1439155Y1399064D03*
X1437443Y1406289D03*
X1435462Y1393009D03*
X1431717Y1420625D03*
Y1417125D03*
Y1409125D03*
X1431829Y1412370D03*
X1443325Y1410068D03*
X1434312Y1415197D03*
X1431717Y1427632D03*
Y1424125D03*
X1433750Y1429208D03*
X1430204Y1452014D03*
X1444468Y1570610D03*
X1433720Y1569762D03*
X1438300Y1598400D03*
X1440105Y1593352D03*
X1430250Y1608442D03*
X1438300Y1611000D03*
Y1606800D03*
Y1602600D03*
X1430250Y1612812D03*
X1441800Y1620300D03*
Y1632900D03*
Y1628700D03*
Y1624500D03*
X1438547Y1638212D03*
X1443617D03*
X1431575Y1634842D03*
X1442573Y1649862D03*
X1442587Y1659242D03*
X1438273Y1671103D03*
X1431866Y1737108D03*
X1458609Y49388D03*
X1446000Y67802D03*
X1458720Y153362D03*
Y149362D03*
Y145362D03*
X1450270Y143022D03*
X1450720Y153362D03*
X1448820Y148092D03*
X1458720Y169862D03*
Y165862D03*
Y161862D03*
Y157862D03*
X1450720Y169862D03*
Y161862D03*
X1449740Y166912D03*
X1458720Y181862D03*
Y177862D03*
Y173862D03*
X1450720Y181862D03*
Y177862D03*
Y173862D03*
X1456423Y209362D03*
X1453823Y205982D03*
X1449110Y233742D03*
X1446830Y236232D03*
X1453670Y278170D03*
X1455600Y297200D03*
X1459312Y341130D03*
X1460849Y343327D03*
X1445777Y362021D03*
X1460600Y352742D03*
X1449777Y362021D03*
X1456700Y369642D03*
X1449296Y410497D03*
Y407347D03*
X1449600Y402322D03*
X1454889Y658712D03*
X1454439Y670262D03*
Y682562D03*
X1454751Y694392D03*
Y706392D03*
X1454439Y718362D03*
X1459057Y733545D03*
X1457597Y739035D03*
X1456237Y726945D03*
X1457620Y736195D03*
X1460187Y729805D03*
X1455692Y731401D03*
X1457714Y741622D03*
X1458911Y1161569D03*
X1447149D03*
X1449649D03*
X1447299Y1153369D03*
X1449799D03*
X1458911Y1170069D03*
X1447149D03*
X1449649D03*
X1449176Y1256866D03*
X1446666Y1256896D03*
X1449188Y1259373D03*
X1446678Y1259403D03*
X1459960Y1259351D03*
Y1256851D03*
X1449106Y1267358D03*
X1459886Y1267218D03*
X1446556Y1267298D03*
X1446678Y1261903D03*
X1449188Y1261873D03*
Y1264373D03*
X1446678Y1264403D03*
X1459960Y1261851D03*
X1459972Y1264358D03*
X1453366Y1287198D03*
X1458766D03*
X1461766D03*
X1450366D03*
X1453303Y1334095D03*
X1455436Y1335598D03*
X1450622Y1329329D03*
X1446622Y1328591D03*
X1454832Y1330819D03*
X1453360Y1328361D03*
X1446622Y1331647D03*
X1459968Y1402765D03*
X1451176Y1399026D03*
X1451198Y1403047D03*
X1461377Y1417844D03*
X1460224Y1407545D03*
X1458138Y1409955D03*
X1454829Y1439732D03*
X1459135Y1439627D03*
X1459136Y1442241D03*
X1455006Y1447938D03*
X1459111Y1445669D03*
Y1448669D03*
X1457577Y1526689D03*
X1457817Y1542509D03*
X1457967Y1553729D03*
X1458200Y1565037D03*
Y1560037D03*
X1446600Y1595400D03*
X1456030Y1590302D03*
X1456120Y1586262D03*
X1453600Y1595662D03*
X1460441Y1602441D03*
X1446786Y1610639D03*
X1451500Y1612800D03*
X1451580Y1627990D03*
X1454167Y1638302D03*
X1459127D03*
X1448507Y1638212D03*
X1452757Y1671399D03*
X1446380Y1676291D03*
X1474142Y61767D03*
X1470220Y145362D03*
X1462000Y153362D03*
X1470220Y169862D03*
X1465179Y213102D03*
X1470101Y207751D03*
X1472335Y209362D03*
X1466940Y230272D03*
X1463833Y230448D03*
X1477700Y236522D03*
X1463808Y244948D03*
X1463833Y235566D03*
X1468620Y258857D03*
X1467230Y252472D03*
X1471510Y252878D03*
X1463950Y258172D03*
X1463330Y264060D03*
X1463510Y273878D03*
X1475452Y289708D03*
X1475352Y306308D03*
X1476826Y312177D03*
X1462777Y362021D03*
X1470877Y374496D03*
X1463277Y406446D03*
X1470954D03*
X1475790Y404842D03*
X1473310Y418502D03*
X1469777Y418396D03*
X1469951Y429251D03*
X1469720Y434542D03*
X1469760Y452622D03*
X1471460Y633402D03*
X1468060D03*
X1466292Y631634D03*
X1473228D03*
X1463639Y653662D03*
X1469651Y655992D03*
X1462010Y645842D03*
X1465171Y647132D03*
X1469020Y647102D03*
X1463639Y665662D03*
X1478139Y660892D03*
X1469439Y670262D03*
X1463639Y677562D03*
X1463239Y689492D03*
X1478139Y689892D03*
X1469651Y684992D03*
X1463239Y701492D03*
X1478139Y704392D03*
X1469477Y699475D03*
X1463239Y713492D03*
X1478139Y718892D03*
X1469651Y713992D03*
X1474100Y735662D03*
X1466451Y726992D03*
X1474939Y731892D03*
X1464999Y1259317D03*
X1476369Y1259237D03*
X1465059Y1256747D03*
X1462470Y1259321D03*
Y1256821D03*
X1476291Y1275224D03*
X1464946Y1267248D03*
X1464989Y1261927D03*
X1464981Y1264624D03*
X1476339Y1264467D03*
Y1267037D03*
X1476309Y1261807D03*
X1476279Y1269637D03*
X1476291Y1272344D03*
X1462396Y1267188D03*
X1462470Y1261821D03*
X1462482Y1264328D03*
X1476291Y1278104D03*
X1472592Y1306345D03*
X1474180Y1300407D03*
X1471180D03*
X1465696Y1303480D03*
X1467046Y1305980D03*
X1468296Y1303480D03*
X1465696Y1300880D03*
X1468296D03*
X1472361Y1322440D03*
X1472592Y1308945D03*
Y1316745D03*
Y1314145D03*
Y1311545D03*
X1466819Y1324018D03*
X1469019Y1322618D03*
X1473956Y1341068D03*
X1472460Y1330493D03*
Y1333043D03*
X1475576Y1338799D03*
X1469019Y1325518D03*
X1464680Y1325772D03*
X1469019Y1328418D03*
X1466919Y1327018D03*
X1464680Y1328672D03*
X1475599Y1349468D03*
X1475959Y1385027D03*
X1476000Y1393027D03*
X1465747Y1401405D03*
X1475935Y1439627D03*
X1475936Y1442241D03*
X1467550Y1439642D03*
X1467536Y1442241D03*
X1467567Y1445669D03*
Y1448669D03*
X1475967Y1445669D03*
Y1448669D03*
X1472565Y1623635D03*
X1463767Y1638302D03*
X1476570Y1657974D03*
Y1661124D03*
X1482650Y-29811D03*
Y-33211D03*
X1480154Y-29033D03*
Y-33989D03*
X1491661Y-27972D03*
X1491676Y-25457D03*
X1488393Y-27958D03*
X1488378Y-25443D03*
X1485383Y-26666D03*
X1491661Y-38001D03*
X1491676Y-35486D03*
X1488393Y-37987D03*
X1488378Y-35472D03*
Y-31598D03*
X1491676Y-31612D03*
X1485383Y-36695D03*
X1482650Y-9811D03*
Y-13211D03*
X1480154Y-9033D03*
Y-13989D03*
Y-19033D03*
Y-23989D03*
X1491661Y-17943D03*
X1491676Y-15428D03*
X1488393Y-17929D03*
X1488378Y-15414D03*
Y-11540D03*
X1491676Y-11554D03*
X1485383Y-16637D03*
X1488378Y-21569D03*
X1491676Y-21583D03*
X1480154Y967D03*
Y-3989D03*
X1485383Y3421D03*
X1491661Y2115D03*
X1491676Y4630D03*
X1488393Y2129D03*
X1488378Y4644D03*
X1491661Y-7914D03*
X1491676Y-5399D03*
X1488393Y-7900D03*
X1488378Y-5385D03*
Y-1511D03*
X1491676Y-1525D03*
X1485383Y-6608D03*
X1488378Y14673D03*
X1488393Y12158D03*
Y22687D03*
X1491661Y22673D03*
X1491676Y14659D03*
X1491661Y12144D03*
X1485383Y13450D03*
X1488378Y8518D03*
X1491676Y8504D03*
X1488378Y19047D03*
X1491676Y19033D03*
X1485383Y23979D03*
X1488378Y25202D03*
X1491646Y25188D03*
X1478609Y49388D03*
X1487958Y236062D03*
X1490060Y255378D03*
X1485320Y260362D03*
X1487058Y281456D03*
X1478745Y281508D03*
X1493289Y280027D03*
X1484958Y289656D03*
X1487658D03*
X1478526Y289677D03*
X1481445Y289708D03*
X1484758Y312356D03*
X1487458D03*
X1484858Y305956D03*
X1487558D03*
X1479745Y312208D03*
X1478426Y306277D03*
X1481345Y306308D03*
X1481360Y358792D03*
X1481484Y361688D03*
X1486884Y374338D03*
X1479207D03*
X1478203Y406207D03*
X1488500Y410152D03*
X1493384Y419263D03*
X1481384Y419392D03*
X1484805Y427577D03*
X1478539Y675462D03*
X1481539Y1259377D03*
X1478999Y1259257D03*
X1481479Y1261947D03*
X1481419Y1264547D03*
X1481431Y1267254D03*
X1478939Y1261827D03*
X1478879Y1264427D03*
X1478891Y1267134D03*
X1481359Y1271447D03*
X1492039D03*
X1481359Y1274144D03*
X1492091D03*
X1478859Y1271417D03*
Y1274114D03*
X1481361Y1280054D03*
X1492101D03*
X1478821D03*
X1481359Y1277024D03*
X1492091D03*
X1478859Y1276994D03*
X1491840Y1300447D03*
X1485523Y1347521D03*
X1487386Y1349258D03*
X1482750Y1342755D03*
X1478750Y1342017D03*
X1486960Y1344245D03*
X1485488Y1341787D03*
X1478750Y1345073D03*
X1481155Y1387742D03*
X1481255Y1382042D03*
X1478559Y1385027D03*
X1481159Y1384727D03*
X1481155Y1396342D03*
Y1398942D03*
Y1390342D03*
X1478600Y1393027D03*
X1481107Y1393095D03*
X1479658Y1405397D03*
X1485301Y1409442D03*
X1485274Y1406911D03*
X1485380Y1412202D03*
X1479671Y1410411D03*
Y1412911D03*
Y1407911D03*
X1482201Y1409442D03*
X1482174Y1406911D03*
X1482280Y1412202D03*
X1485387Y1420002D03*
X1484395Y1439598D03*
X1484336Y1442241D03*
X1484442Y1445557D03*
Y1448557D03*
X1478724Y1637189D03*
X1480800Y1663600D03*
X1491866Y1737108D03*
X1498609Y49388D03*
X1510500Y125992D03*
X1505821Y215802D03*
X1503020D03*
X1505378Y225502D03*
X1496720Y225292D03*
X1509571Y239053D03*
X1507860Y249792D03*
X1504650Y254392D03*
X1508049Y280056D03*
X1508558Y291175D03*
X1512244Y311522D03*
X1504602Y312867D03*
X1509539Y308467D03*
X1496200Y359522D03*
X1497880Y373062D03*
X1495150Y369842D03*
X1503450Y382693D03*
Y385843D03*
X1497770Y732502D03*
X1509638Y738627D03*
X1509350Y741315D03*
X1504747Y747293D03*
X1503514Y801361D03*
Y797961D03*
X1497199Y1275667D03*
X1497259Y1273097D03*
X1494629Y1271477D03*
X1494631Y1274144D03*
X1506569Y1285947D03*
X1508819Y1284797D03*
X1506539Y1288557D03*
X1508759Y1287367D03*
X1508699Y1289967D03*
X1494641Y1280054D03*
X1494631Y1277024D03*
X1506551Y1291254D03*
X1497199Y1278277D03*
X1497161Y1280974D03*
X1506689Y1283377D03*
X1494840Y1300447D03*
X1506591Y1297014D03*
Y1294134D03*
X1508711Y1295554D03*
Y1298434D03*
Y1292674D03*
X1499048Y1319946D03*
X1504720Y1329143D03*
X1503786Y1326076D03*
X1504518Y1335982D03*
X1496784Y1341147D03*
X1498924Y1334882D03*
X1498950Y1339517D03*
X1501149Y1336287D03*
X1496784Y1338247D03*
X1504720Y1342143D03*
Y1344743D03*
X1504588Y1353316D03*
Y1355816D03*
X1501033Y1341462D03*
X1498959Y1342930D03*
X1505116Y1369724D03*
X1505570Y1364212D03*
X1507704Y1361597D03*
X1507617Y1424045D03*
X1518608Y49377D03*
X1522920Y116180D03*
X1513900Y117762D03*
X1524770Y195792D03*
X1521115Y193262D03*
X1521201Y215551D03*
X1513110Y247412D03*
X1514593Y249698D03*
Y235116D03*
X1513759Y263676D03*
X1519758Y265161D03*
X1522786Y262558D03*
X1522258Y265161D03*
X1516683Y278437D03*
X1519833Y277297D03*
X1511624Y291175D03*
X1522258Y288956D03*
X1522883Y305187D03*
X1519336Y303426D03*
X1520094Y306543D03*
X1514369Y308467D03*
X1526216Y306909D03*
X1524505Y748912D03*
X1515940Y795815D03*
Y799215D03*
X1513789Y1290037D03*
X1511289Y1287397D03*
X1511199Y1290007D03*
X1513791Y1292704D03*
X1516351D03*
X1513791Y1298464D03*
Y1295584D03*
X1516351D03*
Y1298464D03*
X1511251Y1292704D03*
Y1298464D03*
Y1295584D03*
X1522066Y1312808D03*
X1526066D03*
X1518066D03*
X1515066D03*
X1511066D03*
X1518451Y1369919D03*
X1514878Y1365553D03*
X1510878Y1364815D03*
X1519088Y1367043D03*
X1517616Y1364585D03*
X1510878Y1367871D03*
X1512177Y1427795D03*
X1513657Y1429985D03*
X1511866Y1737108D03*
X1529002Y32290D03*
X1536310Y47492D03*
X1534818Y66801D03*
Y71793D03*
X1539774Y66801D03*
Y71793D03*
X1541774Y69297D03*
X1532818D03*
X1534774Y103093D03*
X1529818D03*
X1534060Y100162D03*
X1530660D03*
X1533520Y110662D03*
X1535575Y118862D03*
X1529500Y129602D03*
X1540090Y122782D03*
X1536925Y129937D03*
X1529500Y125862D03*
X1535520Y151562D03*
X1531750Y199762D03*
X1534720Y199803D03*
X1528720Y199862D03*
X1529610Y211614D03*
X1532590Y225432D03*
X1529670Y225522D03*
X1528716Y306909D03*
X1533716D03*
X1536216D03*
X1534899Y310447D03*
X1540958Y307756D03*
X1540937Y576522D03*
X1536527Y589012D03*
X1539720Y589862D03*
Y581862D03*
X1540377Y634165D03*
X1535052Y1325904D03*
X1532552Y1334504D03*
X1535052D03*
X1529952D03*
X1532552Y1339704D03*
X1529952D03*
X1537652Y1325904D03*
Y1334504D03*
X1532552Y1337104D03*
X1529952D03*
X1538510Y1346392D03*
X1531302Y1342204D03*
X1535892Y1346354D03*
Y1343754D03*
X1538757Y1356355D03*
Y1360855D03*
Y1365355D03*
X1533178Y1360815D03*
X1530978Y1359315D03*
X1528912Y1361045D03*
X1531078Y1362315D03*
X1533178Y1363715D03*
X1528912Y1363945D03*
X1533178Y1357915D03*
X1531866Y1737108D03*
X1547768Y3010D03*
X1555635Y16999D03*
Y21991D03*
X1553635Y19495D03*
X1553486Y23935D03*
X1548530D03*
X1546530Y25931D03*
X1555486D03*
X1547429Y28406D03*
Y37106D03*
X1554515Y28406D03*
Y37106D03*
Y40020D03*
Y48720D03*
X1547429Y40020D03*
Y48720D03*
X1554818Y69297D03*
X1556818Y66801D03*
Y71793D03*
X1543818Y75297D03*
X1552774D03*
X1550774Y77793D03*
Y72801D03*
X1545818Y77793D03*
Y72801D03*
X1553189Y127781D03*
X1556049Y147711D03*
X1545763Y159305D03*
X1554723Y200375D03*
X1557560Y196912D03*
X1557320Y203297D03*
X1554723Y224529D03*
Y248945D03*
X1545668Y305266D03*
X1545768Y302766D03*
X1543958Y307556D03*
X1546458Y307856D03*
X1543858Y310056D03*
X1547312Y579080D03*
X1543720Y581862D03*
X1548720D03*
X1552720Y589862D03*
Y581862D03*
X1554727Y631527D03*
X1554753Y628860D03*
X1553312Y636815D03*
X1559354Y655716D03*
Y659116D03*
X1550417Y677045D03*
X1550057Y693485D03*
X1548479Y706088D03*
X1551866Y1737108D03*
X1567768Y3010D03*
X1560591Y16999D03*
Y21991D03*
X1569808Y16999D03*
Y21991D03*
X1574764Y16999D03*
Y21991D03*
X1562591Y19495D03*
X1567808D03*
X1567659Y23935D03*
X1562703D03*
X1560703Y25931D03*
X1569659D03*
X1574876D03*
X1561602Y28406D03*
Y37106D03*
X1568688Y28406D03*
Y37106D03*
Y40020D03*
Y48720D03*
X1561602Y40020D03*
Y48720D03*
X1563774Y69297D03*
X1561774Y66801D03*
Y71793D03*
X1565818Y75297D03*
X1574774D03*
X1572774Y77793D03*
Y72801D03*
X1567818Y77793D03*
Y72801D03*
X1559860Y240002D03*
X1559722Y243110D03*
X1570675Y267857D03*
X1575169Y303929D03*
X1573246Y306650D03*
X1572396Y309450D03*
X1567114Y572792D03*
X1561494Y584292D03*
X1559557Y593290D03*
X1560717Y648522D03*
X1564768Y708159D03*
X1570720Y729362D03*
X1562871Y732316D03*
X1571577Y747145D03*
X1567547Y755485D03*
X1571920Y762662D03*
X1568490Y758162D03*
X1570374Y760093D03*
X1587768Y3010D03*
X1583981Y16999D03*
Y21991D03*
X1588937Y16999D03*
Y21991D03*
X1576764Y19495D03*
X1581981D03*
X1590937D03*
X1576876Y23935D03*
X1581832D03*
X1591050D03*
X1583832Y25931D03*
X1589050D03*
X1575775Y28406D03*
Y37106D03*
X1582862Y28406D03*
Y37106D03*
X1589948Y28406D03*
Y37106D03*
Y40020D03*
Y48720D03*
X1582862Y40020D03*
Y48720D03*
X1575775Y40020D03*
Y48720D03*
X1576818Y69297D03*
X1585774D03*
X1578818Y66801D03*
Y71793D03*
X1583774Y66801D03*
Y71793D03*
X1587818Y75297D03*
X1589818Y77793D03*
Y72801D03*
X1576589Y300927D03*
X1588314Y592553D03*
X1585714D03*
X1583114D03*
X1590914D03*
X1588254Y595103D03*
X1588284Y597613D03*
X1585654Y595103D03*
X1585684Y597613D03*
X1583084D03*
X1583054Y595103D03*
X1588284Y608655D03*
X1585684D03*
X1583084D03*
X1590854Y595103D03*
X1590884Y597613D03*
Y608655D03*
X1588254Y613715D03*
X1588224Y611205D03*
X1585654Y613715D03*
X1585624Y611205D03*
X1583024D03*
X1583054Y613715D03*
X1590854D03*
X1590824Y611205D03*
X1591368Y628727D03*
X1591428Y626177D03*
X1588928D03*
X1588868Y628727D03*
X1591398Y631237D03*
X1588898D03*
X1591368Y650877D03*
X1591338Y648367D03*
X1591398Y645817D03*
X1588868Y650877D03*
X1588838Y648367D03*
X1588898Y645817D03*
X1591368Y653377D03*
X1588868D03*
X1591448Y657677D03*
X1588948D03*
Y660177D03*
X1591448D03*
X1588968Y665237D03*
X1591468D03*
X1588938Y662727D03*
X1591438D03*
X1588938Y679807D03*
X1588878Y682357D03*
X1588908Y684867D03*
X1591438Y679807D03*
X1591378Y682357D03*
X1591408Y684867D03*
X1591328Y696727D03*
X1591388Y694177D03*
X1588888D03*
X1588828Y696727D03*
X1591358Y699277D03*
X1588858D03*
X1591358Y718837D03*
X1591328Y716327D03*
X1591388Y713777D03*
X1588858Y718837D03*
X1588828Y716327D03*
X1588888Y713777D03*
X1590915Y755793D03*
X1591866Y1737108D03*
X1607768Y3010D03*
X1598155Y16999D03*
Y21991D03*
X1603111Y16999D03*
Y21991D03*
X1596155Y19495D03*
X1605111D03*
X1596006Y23935D03*
X1598006Y25931D03*
X1597035Y28406D03*
Y37106D03*
X1604122Y28406D03*
Y37106D03*
Y40020D03*
Y48720D03*
X1597035Y40020D03*
Y48720D03*
X1598818Y69297D03*
X1607774D03*
X1600818Y66801D03*
Y71793D03*
X1605774Y66801D03*
Y71793D03*
X1596774Y75297D03*
X1594774Y77793D03*
Y72801D03*
X1603778Y189943D03*
X1603726Y198061D03*
X1603747Y192951D03*
X1596444Y215526D03*
X1603706Y211526D03*
X1603580Y206902D03*
X1604200Y234642D03*
X1603920Y222922D03*
X1604040Y219692D03*
X1604270Y231490D03*
X1598030Y251002D03*
X1604290Y242472D03*
X1602980Y560002D03*
X1593514Y592553D03*
X1601830Y590685D03*
X1604430D03*
X1607200Y583962D03*
X1593484Y597613D03*
X1593454Y595103D03*
X1593484Y608655D03*
X1593424Y611205D03*
X1593454Y613715D03*
X1601830Y615201D03*
X1604430D03*
X1598868Y628727D03*
X1598928Y626177D03*
X1593868Y628727D03*
X1593928Y626177D03*
X1596428D03*
X1596368Y628727D03*
X1598898Y631237D03*
X1593898D03*
X1596398D03*
X1598868Y650877D03*
X1598838Y648367D03*
X1596368Y650877D03*
X1593868D03*
X1596338Y648367D03*
X1593838D03*
X1598898Y645817D03*
X1596398D03*
X1593898D03*
X1598868Y653377D03*
X1596368D03*
X1593868D03*
X1598948Y657677D03*
X1593948D03*
X1596448D03*
Y660177D03*
X1593948D03*
X1598948D03*
X1596468Y665237D03*
X1593968D03*
X1598968D03*
X1596438Y662727D03*
X1593938D03*
X1598938D03*
X1593938Y679807D03*
X1596438D03*
X1593878Y682357D03*
X1596378D03*
X1593908Y684867D03*
X1596408D03*
X1598878Y682357D03*
X1598908Y684867D03*
X1598938Y679807D03*
X1596288Y688902D03*
X1598888D03*
X1598828Y696727D03*
X1593828D03*
X1593888Y694177D03*
X1596388D03*
X1596328Y696727D03*
X1593858Y699277D03*
X1596358D03*
X1598888Y694177D03*
X1596288Y691502D03*
X1598858Y699277D03*
X1598888Y691502D03*
X1598858Y718837D03*
X1598828Y716327D03*
X1596358Y718837D03*
X1593858D03*
X1596328Y716327D03*
X1593828D03*
X1596388Y713777D03*
X1593888D03*
X1598888D03*
X1596250Y721452D03*
X1598850D03*
X1599010Y724002D03*
X1598440Y736692D03*
X1592760Y736652D03*
X1595600D03*
X1606788Y756199D03*
X1602788D03*
X1606980Y1449922D03*
X1621920Y25962D03*
X1622220Y49862D03*
X1620818Y69297D03*
X1622818Y66801D03*
Y71793D03*
X1609818Y75297D03*
X1618774D03*
X1616774Y77793D03*
Y72801D03*
X1611818Y77793D03*
Y72801D03*
X1623881Y129627D03*
X1619980Y590685D03*
X1615800Y584062D03*
X1620170Y623762D03*
X1622770D03*
X1619980Y615201D03*
X1612980Y623762D03*
X1620170Y626362D03*
X1622770D03*
X1612980D03*
X1615580Y650092D03*
Y657762D03*
X1620170D03*
X1622770D03*
X1622109Y652469D03*
X1619509D03*
X1612980Y657762D03*
Y650092D03*
X1615580Y660362D03*
X1620170D03*
X1622770D03*
X1612980D03*
X1622109Y686469D03*
X1619509D03*
X1615580Y684092D03*
X1612980D03*
X1622770Y691762D03*
Y694362D03*
X1620170Y691762D03*
Y694362D03*
X1615580D03*
X1612980D03*
X1615580Y691762D03*
X1612980D03*
X1619509Y720469D03*
X1622109D03*
X1612980Y718092D03*
X1615580D03*
X1610100Y725152D03*
X1610788Y756199D03*
X1614788D03*
X1618788D03*
X1623448Y1420028D03*
Y1417428D03*
Y1414828D03*
Y1412228D03*
X1612630Y1418842D03*
X1615062Y1421241D03*
X1613047Y1415669D03*
X1615597Y1433669D03*
X1614927Y1426076D03*
Y1429896D03*
X1624353Y1428766D03*
Y1431316D03*
X1617215Y1440822D03*
X1611866Y1737108D03*
X1634021Y16999D03*
Y21991D03*
X1638977Y16999D03*
Y21991D03*
X1632021Y19495D03*
X1631872Y23935D03*
X1626916D03*
X1624916Y25931D03*
X1633872D03*
X1639089D03*
X1625814Y28406D03*
Y37106D03*
X1632901Y28406D03*
Y37106D03*
X1639988Y28406D03*
Y37106D03*
X1625814Y40020D03*
Y48720D03*
X1632901Y40020D03*
Y48720D03*
X1639988Y40020D03*
Y48720D03*
X1629774Y69297D03*
X1627774Y66801D03*
Y71793D03*
X1633022Y75297D03*
X1635022Y77793D03*
X1639978D03*
Y72801D03*
X1635022D03*
X1635032Y196188D03*
X1632899Y213012D03*
X1632342Y216015D03*
X1635835Y343002D03*
X1636800Y429982D03*
X1639800D03*
X1636800Y426982D03*
X1639800D03*
X1636800Y438982D03*
X1639800D03*
X1636800Y435982D03*
X1639800D03*
X1636800Y432982D03*
X1639800D03*
X1637667Y587844D03*
Y590444D03*
X1629867D03*
Y587844D03*
X1632467Y590444D03*
Y587844D03*
X1635067Y590444D03*
Y587844D03*
X1626606Y616576D03*
X1629206D03*
X1631806D03*
X1634406D03*
X1637006D03*
X1639606D03*
X1630570Y623762D03*
X1627970D03*
X1625370D03*
X1630570Y626362D03*
X1627970D03*
X1625370D03*
X1630570Y657762D03*
X1627970D03*
X1625370D03*
X1629909Y652469D03*
X1632509D03*
X1624709D03*
X1627309D03*
X1630570Y660362D03*
X1627970D03*
X1625370D03*
X1629909Y686469D03*
X1632509D03*
X1624709D03*
X1627309D03*
X1625370Y691762D03*
Y694362D03*
X1630570D03*
Y691762D03*
X1627970D03*
Y694362D03*
X1632509Y720469D03*
X1627309D03*
X1629909D03*
X1624709D03*
X1638928Y756199D03*
X1630928D03*
X1634928D03*
X1638277Y1269065D03*
X1640812Y1270020D03*
X1631203Y1367492D03*
X1628653D03*
X1626153D03*
X1628653Y1372492D03*
X1631203D03*
X1626153D03*
X1631203Y1369992D03*
X1628653D03*
X1626153D03*
X1628653Y1379992D03*
Y1382492D03*
Y1377492D03*
Y1374992D03*
X1631203Y1377492D03*
Y1374992D03*
Y1379992D03*
Y1382492D03*
X1626153Y1379992D03*
Y1382492D03*
Y1374992D03*
Y1377492D03*
X1637183Y1394411D03*
X1639683D03*
X1629262Y1394418D03*
X1634683Y1394411D03*
X1625948Y1417428D03*
Y1412228D03*
Y1414828D03*
Y1420028D03*
X1627469Y1437072D03*
X1627591Y1447796D03*
X1637478Y1445150D03*
X1624853Y1440875D03*
X1634643Y1442982D03*
X1638785Y1442483D03*
X1637042Y1440215D03*
X1630643Y1443090D03*
X1635315Y1465745D03*
Y1462745D03*
X1632315Y1468745D03*
X1629815D03*
X1632315Y1465745D03*
X1629815D03*
X1632315Y1462745D03*
X1629815D03*
X1635315Y1468745D03*
Y1460245D03*
X1629815D03*
X1632315D03*
X1629815Y1457745D03*
X1632315D03*
X1635315D03*
X1639645Y1473645D03*
X1631866Y1737108D03*
X1648194Y16999D03*
Y21991D03*
X1653150Y16999D03*
Y21991D03*
X1640977Y19495D03*
X1646194D03*
X1655150D03*
X1641089Y23935D03*
X1646045D03*
X1648045Y25931D03*
X1654161Y28406D03*
Y37106D03*
X1647074Y28406D03*
Y37106D03*
Y40020D03*
Y48720D03*
X1654161Y40020D03*
Y48720D03*
X1644022Y69297D03*
X1652978D03*
X1646022Y66801D03*
Y71793D03*
X1650978Y66801D03*
Y71793D03*
X1655022Y75297D03*
X1641978D03*
X1657022Y77793D03*
Y72801D03*
X1652610Y394727D03*
X1652810Y407402D03*
X1650020Y408952D03*
X1647310Y408922D03*
X1650020Y411452D03*
X1647310Y411422D03*
X1652113Y527325D03*
X1652138Y524071D03*
X1651890Y520540D03*
X1657755Y517910D03*
X1651931Y540071D03*
Y536071D03*
X1651851Y532057D03*
X1651112Y545572D03*
X1653230Y549322D03*
X1642720Y560862D03*
X1656238Y592113D03*
X1642873Y604206D03*
Y607206D03*
X1645625Y600495D03*
Y603295D03*
X1642873Y601206D03*
Y598206D03*
X1645625Y597795D03*
Y594995D03*
X1642873Y595006D03*
X1649833Y594946D03*
X1653794Y594956D03*
X1653774Y598576D03*
X1649844Y598555D03*
X1649220Y620662D03*
X1642340Y618546D03*
X1642873Y610206D03*
X1656955Y611090D03*
X1653220Y620662D03*
X1645681Y624011D03*
X1648581D03*
X1651481D03*
X1654809Y638101D03*
X1652351Y639573D03*
X1648811Y628277D03*
X1647081Y626211D03*
X1650081Y626111D03*
X1651711Y628277D03*
X1656550Y653086D03*
X1651635Y651836D03*
X1652581Y646311D03*
X1643582Y652601D03*
X1655637Y646311D03*
X1641082Y652601D03*
X1649363Y649485D03*
X1654809Y672101D03*
X1652351Y673573D03*
X1645681Y658011D03*
X1648581D03*
X1648811Y662277D03*
X1647081Y660211D03*
X1650081Y660111D03*
X1651481Y658011D03*
X1651711Y662277D03*
X1656550Y687086D03*
X1641082Y686601D03*
X1651635Y685836D03*
X1652581Y680311D03*
X1653319Y676311D03*
X1643582Y686601D03*
X1655113Y680835D03*
X1649363Y683485D03*
X1654809Y706101D03*
X1648811Y696277D03*
X1650081Y694111D03*
X1645681Y692011D03*
X1647081Y694211D03*
X1648581Y692011D03*
X1651711Y696277D03*
X1651481Y692011D03*
X1641082Y720601D03*
X1651635Y719836D03*
X1652581Y714311D03*
X1653319Y710311D03*
X1652351Y707573D03*
X1643582Y720601D03*
X1655637Y714311D03*
X1649363Y717485D03*
X1651509Y756492D03*
X1650771Y1367492D03*
X1648271D03*
X1645721D03*
X1648271Y1372492D03*
X1650771D03*
X1645721D03*
X1650771Y1369992D03*
X1648271D03*
X1645721D03*
X1648271Y1379992D03*
Y1382492D03*
X1650771Y1379992D03*
Y1382492D03*
X1648271Y1377492D03*
Y1374992D03*
X1650771Y1377492D03*
Y1374992D03*
X1645721Y1377492D03*
Y1374992D03*
Y1379992D03*
Y1382492D03*
X1656188Y1394736D03*
X1647592Y1394418D03*
X1655779Y1417618D03*
Y1412418D03*
Y1415018D03*
X1653279Y1412418D03*
X1650679D03*
X1653279Y1415018D03*
X1650679D03*
X1653168Y1417618D03*
X1650557D03*
X1655762Y1429794D03*
X1648677Y1436220D03*
X1653243Y1435690D03*
X1651043Y1434190D03*
X1653243Y1432790D03*
X1651143Y1437190D03*
X1653243Y1438590D03*
X1648677Y1439120D03*
X1655295Y1453879D03*
X1652295D03*
X1643065Y1462645D03*
Y1465645D03*
Y1468645D03*
Y1460145D03*
Y1457645D03*
X1655295Y1456899D03*
X1652295D03*
X1648947Y1476695D03*
X1642645Y1473645D03*
X1646958Y1501553D03*
X1651866Y1737108D03*
X1671050Y23935D03*
X1669050Y25931D03*
X1669948Y28406D03*
Y37106D03*
Y40020D03*
Y48720D03*
X1666022Y69297D03*
X1668022Y66801D03*
Y71793D03*
X1672978Y66801D03*
Y71793D03*
X1663978Y75297D03*
X1661978Y77793D03*
Y72801D03*
X1668030Y200580D03*
X1667739Y187187D03*
X1672596Y220541D03*
X1666074Y229710D03*
X1660176Y231100D03*
X1670400Y229462D03*
X1664866Y225162D03*
X1659610Y394727D03*
X1663610D03*
X1664970Y472112D03*
X1662447Y480619D03*
X1663376Y515531D03*
X1670004Y537065D03*
Y543065D03*
Y531065D03*
X1662262Y537334D03*
X1659740Y542222D03*
X1661872Y534703D03*
X1660243Y532071D03*
X1660866Y546749D03*
X1666902Y555115D03*
X1664040Y569642D03*
X1668040D03*
X1672040D03*
X1665700Y583462D03*
X1661510Y583442D03*
X1672770Y580512D03*
X1669770D03*
X1658738Y592113D03*
X1661238D03*
X1664997Y604762D03*
X1662120Y604782D03*
X1664197Y602191D03*
X1669222Y604490D03*
X1670700Y594562D03*
X1672500Y596462D03*
X1657220Y620662D03*
X1663720Y620434D03*
X1664410Y617953D03*
X1668920Y617637D03*
X1660754Y609837D03*
X1669397Y614064D03*
X1663471Y609837D03*
X1659458Y637149D03*
X1658085Y639511D03*
X1659914Y649681D03*
X1659458Y671149D03*
X1658085Y673511D03*
X1659914Y683681D03*
X1659458Y705149D03*
X1658085Y707511D03*
X1659914Y717681D03*
X1666686Y757162D03*
X1669303Y1372492D03*
X1664253D03*
X1666753D03*
X1669303Y1367492D03*
Y1369992D03*
X1666753Y1367492D03*
X1664253D03*
Y1369992D03*
X1666753D03*
X1669303Y1379992D03*
Y1382492D03*
Y1377492D03*
Y1374992D03*
X1666753Y1379992D03*
X1664253D03*
X1666753Y1382492D03*
X1664253D03*
X1666753Y1377492D03*
X1664253D03*
Y1374992D03*
X1666753D03*
X1673226Y1394411D03*
X1667405Y1394418D03*
X1659260Y1394693D03*
X1658390Y1420218D03*
Y1415018D03*
Y1412418D03*
Y1417618D03*
X1663590Y1420218D03*
X1660990D03*
Y1415018D03*
Y1417618D03*
Y1412418D03*
X1663590Y1415018D03*
Y1417618D03*
Y1412418D03*
X1657438Y1438156D03*
X1662496Y1428791D03*
Y1431291D03*
X1665612Y1437072D03*
X1660428Y1447566D03*
X1667577Y1447545D03*
X1662996Y1440922D03*
X1672786Y1442982D03*
X1668786Y1440290D03*
Y1443256D03*
X1657920Y1453405D03*
X1660920D03*
X1657860Y1466545D03*
Y1464045D03*
X1657950Y1456210D03*
X1657860Y1459045D03*
Y1461545D03*
X1660950Y1456210D03*
X1660860Y1466545D03*
Y1464045D03*
Y1459045D03*
Y1461545D03*
X1666123Y1497362D03*
Y1493362D03*
Y1501362D03*
X1666110Y1504662D03*
X1666123Y1533862D03*
Y1520862D03*
Y1541862D03*
Y1545862D03*
X1671673Y1550815D03*
X1666123Y1557557D03*
X1666198Y1561557D03*
Y1581321D03*
X1671866Y1737108D03*
X1678155Y16999D03*
Y21991D03*
X1683111Y16999D03*
Y21991D03*
X1676155Y19495D03*
X1685111D03*
X1676006Y23935D03*
X1685223D03*
X1678006Y25931D03*
X1683223D03*
X1677035Y28406D03*
Y37106D03*
X1684122Y28406D03*
Y37106D03*
X1677035Y40020D03*
Y48720D03*
X1684122Y40020D03*
Y48720D03*
X1688156Y69297D03*
X1674978D03*
X1677156Y75297D03*
X1686112D03*
X1684112Y77793D03*
Y72801D03*
X1679156Y77793D03*
Y72801D03*
X1678994Y217231D03*
X1676300Y219762D03*
X1681900Y227962D03*
X1686154Y434160D03*
X1689095Y462640D03*
X1683394Y469878D03*
X1683476Y473378D03*
X1684356Y476290D03*
X1682810Y465940D03*
X1684940Y463030D03*
X1681602Y485180D03*
X1684356Y485628D03*
X1677464Y491790D03*
X1685779Y491230D03*
X1690229Y481845D03*
X1687238Y485496D03*
X1681612Y499290D03*
X1682004Y537065D03*
X1682180Y543065D03*
X1676004D03*
X1682004Y531065D03*
X1676004D03*
X1689544Y543874D03*
X1689506Y539882D03*
X1676040Y569627D03*
X1683369Y566098D03*
X1676644Y655345D03*
Y652745D03*
X1679244Y655345D03*
X1681864Y655286D03*
X1679244Y652745D03*
X1676624Y642404D03*
X1676644Y644945D03*
Y647545D03*
Y650145D03*
X1679244Y642345D03*
X1681864Y642286D03*
X1679244Y644945D03*
Y647545D03*
X1681864Y644886D03*
Y647486D03*
Y650086D03*
Y652686D03*
X1679244Y650145D03*
X1688301Y722158D03*
X1683121D03*
X1680401D03*
X1673860Y726522D03*
X1681810Y752955D03*
X1688912Y1372492D03*
X1686362D03*
Y1367492D03*
Y1369992D03*
X1688912Y1367492D03*
Y1369992D03*
Y1377492D03*
Y1374992D03*
Y1382492D03*
Y1379992D03*
X1686362D03*
Y1382492D03*
Y1374992D03*
Y1377492D03*
X1686135Y1394418D03*
X1675926Y1394411D03*
X1678426D03*
X1687860Y1415179D03*
X1689210Y1417679D03*
X1687860Y1412579D03*
X1686820Y1436520D03*
X1688886Y1434790D03*
X1688986Y1437790D03*
X1675621Y1445150D03*
X1676928Y1442483D03*
X1675185Y1440215D03*
X1686820Y1439420D03*
X1679508Y1503421D03*
Y1498303D03*
Y1517803D03*
Y1522921D03*
Y1543921D03*
Y1538803D03*
Y1563380D03*
Y1583880D03*
X1674220Y1585321D03*
X1692328Y16999D03*
Y21991D03*
X1697284Y16999D03*
Y21991D03*
X1690328Y19495D03*
X1699284D03*
X1703617Y26459D03*
X1700217D03*
X1690179Y23935D03*
X1692179Y25931D03*
X1691208Y28406D03*
Y37106D03*
X1698295Y28406D03*
Y37106D03*
X1705381Y28406D03*
Y37106D03*
X1703570Y50649D03*
X1700170D03*
X1698295Y48720D03*
X1697824Y39974D03*
X1691208Y40020D03*
Y48720D03*
X1705381D03*
X1697112Y69297D03*
X1690156Y66801D03*
Y71793D03*
X1695112Y66801D03*
Y71793D03*
X1699156Y75297D03*
X1701156Y77793D03*
Y72801D03*
X1695950Y96437D03*
X1697725Y205120D03*
X1702490Y204780D03*
X1704223Y209707D03*
Y212207D03*
X1701164Y209758D03*
X1698566Y214904D03*
X1696066D03*
X1693725Y217409D03*
X1698566Y212404D03*
X1696066D03*
X1698725Y217409D03*
X1696225D03*
X1701164Y212258D03*
X1704264Y217458D03*
X1701264D03*
X1704264Y214958D03*
X1701264D03*
X1698566Y209704D03*
X1696066D03*
X1693466Y209504D03*
Y214704D03*
Y212204D03*
X1693987Y233174D03*
X1693725Y219909D03*
X1698725D03*
X1696225D03*
X1704264Y219958D03*
X1701264D03*
X1704185Y222710D03*
X1704444Y407045D03*
X1699809Y403985D03*
X1695579D03*
X1697914Y427155D03*
X1698014Y424055D03*
X1701124Y433650D03*
X1697214Y433655D03*
X1704624Y433650D03*
X1690140Y434160D03*
X1700846Y455894D03*
X1697220Y455862D03*
X1693648Y463724D03*
X1702760Y478207D03*
X1696760D03*
X1693236Y472650D03*
X1702760Y490207D03*
X1696760D03*
Y484207D03*
X1691151Y493678D03*
X1689943Y479304D03*
X1696120Y506937D03*
X1703720Y509362D03*
X1701811Y501318D03*
X1701635Y497177D03*
X1699300Y498632D03*
X1694050Y501422D03*
X1693711Y498527D03*
X1691129Y501697D03*
X1699265Y525507D03*
X1696851Y515607D03*
X1693701D03*
X1699265Y521507D03*
X1690999Y525507D03*
X1699291Y537507D03*
X1699251Y529507D03*
X1699666Y541507D03*
X1699251Y533642D03*
X1691104Y530503D03*
X1691445Y535011D03*
X1704886Y534564D03*
X1689769Y537339D03*
X1699297Y549507D03*
X1702270Y552742D03*
X1703452Y639381D03*
X1700852D03*
X1698232Y639440D03*
X1700852Y655141D03*
X1703452Y647341D03*
Y649941D03*
Y652541D03*
Y644741D03*
X1700852Y647341D03*
Y649941D03*
Y652541D03*
Y644741D03*
X1698232Y655200D03*
Y644800D03*
Y647400D03*
Y650000D03*
Y652600D03*
X1703452Y641981D03*
X1700852D03*
X1698232Y642040D03*
X1700922Y657781D03*
X1698302Y657840D03*
X1698048Y705662D03*
X1698920Y698562D03*
X1698020Y702962D03*
X1695227Y722325D03*
X1699307Y722465D03*
X1698137Y718345D03*
X1701087Y719055D03*
X1695367Y719345D03*
X1691021Y722158D03*
X1699110Y727452D03*
X1705035Y729210D03*
X1704973Y753019D03*
X1703310Y749455D03*
X1698537Y766015D03*
X1690620Y760702D03*
X1691412Y1372492D03*
Y1367492D03*
Y1369992D03*
Y1377492D03*
Y1374992D03*
Y1382492D03*
Y1379992D03*
X1690809Y1393970D03*
X1699150Y1393613D03*
X1690460Y1415179D03*
Y1412579D03*
X1691918Y1417676D03*
X1692960Y1415179D03*
Y1412579D03*
X1693404Y1421939D03*
X1699593Y1428384D03*
X1697820Y1423616D03*
X1699545Y1425868D03*
X1699437Y1431295D03*
X1691086Y1436290D03*
Y1433390D03*
X1693392Y1429808D03*
X1691086Y1439190D03*
X1691988Y1498303D03*
X1704723Y1500862D03*
Y1520362D03*
Y1541362D03*
X1705003Y1564057D03*
X1691866Y1737108D03*
X1707220Y15662D03*
X1714589Y21562D03*
X1714520Y37162D03*
X1719589Y25862D03*
X1717089D03*
X1710106Y48720D03*
Y40020D03*
X1716875Y68062D03*
X1710920Y82162D03*
X1708112Y75297D03*
X1706112Y77793D03*
Y72801D03*
X1708000Y99122D03*
X1712520Y117862D03*
X1719943Y112667D03*
Y116667D03*
X1713418Y130862D03*
X1721418Y135327D03*
X1717418D03*
X1714490Y142920D03*
X1717140Y148910D03*
X1711700Y140200D03*
X1717619Y165909D03*
X1718110Y159040D03*
X1719530Y162950D03*
X1717280Y174970D03*
X1722078Y189483D03*
X1720310Y191252D03*
X1707159Y217580D03*
Y215080D03*
Y210080D03*
Y222580D03*
Y225080D03*
Y220080D03*
X1721400Y374462D03*
X1713720Y381152D03*
X1717220D03*
X1719200Y371162D03*
X1713720Y391652D03*
Y384652D03*
Y388152D03*
X1717220Y391652D03*
Y388152D03*
Y384652D03*
X1707444Y407045D03*
X1709000Y413362D03*
X1706500D03*
X1711144Y425945D03*
X1709000Y415862D03*
X1706500D03*
X1711477Y465229D03*
Y468379D03*
X1708760Y478031D03*
X1721936Y469263D03*
X1716134Y478443D03*
X1715711Y474399D03*
X1708760Y490207D03*
Y484207D03*
X1716148Y483720D03*
X1716087Y495665D03*
X1716156Y487685D03*
X1716278Y491676D03*
X1707552Y503331D03*
X1709844Y516106D03*
X1710500Y538162D03*
X1707610Y534113D03*
X1709680Y545432D03*
X1716110Y532632D03*
X1707346Y547504D03*
X1717987Y569705D03*
X1709027Y655141D03*
X1706720Y703762D03*
X1710550Y691327D03*
X1712824Y696476D03*
X1710122Y703509D03*
X1713920Y700962D03*
X1709107Y728449D03*
X1713450Y728222D03*
X1719727Y1472088D03*
X1720174Y1505895D03*
Y1513945D03*
X1714988Y1520951D03*
X1708988D03*
X1714988Y1530445D03*
X1708988D03*
X1711866Y1737108D03*
X1727768Y3010D03*
X1732320Y28162D03*
X1728820D03*
X1725320D03*
X1726720Y49862D03*
X1733720D03*
X1730220D03*
X1736040Y41792D03*
X1732810Y52482D03*
X1736040Y44292D03*
X1730140Y52552D03*
X1727600Y52582D03*
X1729520Y61762D03*
X1729620Y57262D03*
X1725320Y67962D03*
X1730820Y76362D03*
X1726918Y101967D03*
X1723018Y101667D03*
X1723218Y93267D03*
X1738220Y98862D03*
X1736720Y101862D03*
X1733378Y134907D03*
X1736508D03*
X1730765Y151362D03*
X1723670Y149102D03*
X1723240Y185200D03*
X1737704Y183139D03*
X1723090Y173072D03*
Y177072D03*
X1734857Y184865D03*
X1738200Y193862D03*
X1737500Y217962D03*
Y214962D03*
Y211962D03*
Y208962D03*
Y226962D03*
Y223962D03*
Y220962D03*
X1737260Y368132D03*
X1732660Y372692D03*
X1725400Y372062D03*
X1728300Y377787D03*
X1725500Y383662D03*
X1733780Y390620D03*
X1737434Y398990D03*
X1727760Y420415D03*
X1727700Y417265D03*
X1725473Y474859D03*
X1730954Y478062D03*
X1725522Y482869D03*
X1733354Y490869D03*
Y486869D03*
X1738014Y1287344D03*
X1724431Y1336311D03*
X1734717Y1404340D03*
X1729700Y1462932D03*
X1733200D03*
X1736700D03*
X1736400Y1458942D03*
Y1455442D03*
X1731600Y1457230D03*
X1726120Y1490262D03*
X1726149Y1496270D03*
X1724649Y1513945D03*
Y1505895D03*
X1727674D03*
X1726310Y1530445D03*
X1732310D03*
X1726310Y1520951D03*
X1732310D03*
X1731866Y1737108D03*
X1747768Y3010D03*
X1754090Y16302D03*
X1753388Y28360D03*
X1748400Y37262D03*
X1751065Y39017D03*
X1754620Y39062D03*
X1747720Y31862D03*
Y34362D03*
X1753398Y48720D03*
X1740858Y72330D03*
Y79830D03*
Y74830D03*
Y82330D03*
X1754398Y100307D03*
X1745220Y98862D03*
X1741720D03*
X1743720Y101862D03*
X1740220D03*
X1745485Y119539D03*
X1747482Y121367D03*
X1741222Y151527D03*
X1738520Y151362D03*
X1751220Y147562D03*
X1748465D03*
X1754120Y171562D03*
X1750920Y171662D03*
X1751084Y190928D03*
X1752200Y197762D03*
X1748500Y193862D03*
X1745500D03*
X1741200D03*
X1754234Y190836D03*
X1752078Y216728D03*
X1740500Y217962D03*
Y214962D03*
Y211962D03*
Y208962D03*
X1747600Y209062D03*
X1744600D03*
X1751800Y206762D03*
X1752078Y226728D03*
Y224228D03*
Y221728D03*
Y219228D03*
X1740500Y226962D03*
Y223962D03*
Y220962D03*
X1754307Y262186D03*
X1751068Y266048D03*
X1754307Y266111D03*
X1754414Y275329D03*
X1752165Y273901D03*
X1749565D03*
X1751006Y269661D03*
X1749595Y276711D03*
X1752195D03*
X1745000Y299862D03*
X1749450Y293862D03*
X1752000Y306562D03*
X1748989Y380206D03*
X1740831Y489362D03*
X1752316Y703969D03*
Y695669D03*
X1752217Y692988D03*
X1752276Y720529D03*
X1752316Y712269D03*
X1747814Y1287344D03*
X1742714Y1287244D03*
X1754165Y1304422D03*
Y1307422D03*
Y1301422D03*
Y1295422D03*
Y1298422D03*
Y1310422D03*
X1738740Y1451742D03*
X1740200Y1462932D03*
X1745111Y1463262D03*
X1744677Y1507388D03*
X1744304Y1524976D03*
X1751866Y1737108D03*
X1767768Y3010D03*
X1762420Y21562D03*
X1765238Y22062D03*
X1758672Y26431D03*
X1755272D03*
X1760475Y28360D03*
X1769900Y37732D03*
X1767220Y26962D03*
X1758669Y50649D03*
X1755269D03*
X1760485Y48720D03*
X1762738Y53262D03*
X1767220Y53342D03*
X1767400Y39915D03*
X1769274Y50742D03*
X1759700Y57662D03*
X1764400Y57462D03*
X1758063Y68637D03*
X1758573Y87107D03*
Y83607D03*
X1768168Y80497D03*
X1758568Y79697D03*
X1765068Y80397D03*
X1758063Y72623D03*
X1770368Y72691D03*
X1766278Y93627D03*
X1757978Y116727D03*
X1760978D03*
X1763678Y106127D03*
X1769278Y108027D03*
Y110927D03*
Y113727D03*
X1755978Y108427D03*
Y111027D03*
X1760478Y106127D03*
X1764678Y122927D03*
X1758300Y128242D03*
X1763435Y166862D03*
X1765870Y179392D03*
X1755078Y216928D03*
X1761500Y214062D03*
X1765000D03*
X1768500D03*
X1766880Y234842D03*
Y231842D03*
X1758500Y231822D03*
Y234822D03*
X1755378Y233528D03*
X1755078Y219428D03*
Y221928D03*
Y224428D03*
X1763731Y283817D03*
X1766725Y282981D03*
X1763731Y279517D03*
X1760398Y279548D03*
X1766765Y279433D03*
X1757439Y279611D03*
X1760398Y283848D03*
X1759509Y292434D03*
X1762549Y286704D03*
X1757439Y283911D03*
X1768045Y295238D03*
X1765053Y295188D03*
X1762285Y295137D03*
X1759629Y295164D03*
X1767309Y290994D03*
X1763045Y289691D03*
X1759529Y289864D03*
X1766655Y286531D03*
X1767455Y302651D03*
X1764955Y301951D03*
X1758563Y310478D03*
X1754963D03*
X1761936Y310709D03*
X1769230Y310478D03*
X1756800Y364048D03*
X1770520Y368148D03*
X1768757Y380498D03*
X1756800Y368048D03*
X1770280Y372452D03*
X1770220Y377452D03*
Y382952D03*
X1757066Y435721D03*
X1767300Y461393D03*
X1757650D03*
X1768560Y539042D03*
X1766060D03*
X1764112Y703948D03*
X1761612D03*
X1764112Y695648D03*
X1763570Y693192D03*
X1761612Y695648D03*
X1755112Y703948D03*
Y695648D03*
X1755013Y692967D03*
X1757612Y703948D03*
Y695648D03*
X1764072Y720508D03*
X1761572D03*
X1764112Y712248D03*
X1761612D03*
X1755072Y720508D03*
X1755112Y712248D03*
X1757572Y720508D03*
X1757612Y712248D03*
X1757165Y1304422D03*
X1760165D03*
Y1307422D03*
X1757165D03*
X1769165Y1301422D03*
X1766165D03*
X1763165D03*
X1757165D03*
X1760165D03*
X1769165Y1295422D03*
X1766165D03*
X1763165D03*
X1760165D03*
X1757165D03*
X1760165Y1298422D03*
X1757165D03*
X1763165D03*
X1766165D03*
X1769165D03*
X1757165Y1310422D03*
X1760165D03*
X1759987Y1325375D03*
Y1328275D03*
X1763829Y1337548D03*
X1766829D03*
Y1340448D03*
X1769829Y1337548D03*
Y1340448D03*
X1766829Y1343348D03*
X1769829Y1346248D03*
Y1343348D03*
Y1349148D03*
Y1351858D03*
X1782305Y13647D03*
X1777754Y37746D03*
X1781774Y54462D03*
X1774274Y50742D03*
X1776710Y53562D03*
X1774328Y60087D03*
X1779778Y70027D03*
X1785178Y86927D03*
X1779778Y72927D03*
X1785178Y89927D03*
X1778578Y97927D03*
X1778478Y90627D03*
X1784178Y108227D03*
Y111127D03*
Y113927D03*
X1782000Y128455D03*
X1771915Y128393D03*
X1782000Y125955D03*
Y123455D03*
X1771915Y125893D03*
Y123393D03*
X1784238Y150744D03*
X1780320Y177602D03*
X1777520Y178403D03*
Y173903D03*
X1778778Y216928D03*
X1783878D03*
X1772000Y214062D03*
X1786690Y234782D03*
Y231782D03*
X1783800Y231762D03*
Y234762D03*
X1775140Y234792D03*
Y231792D03*
X1778778Y219428D03*
Y221928D03*
X1783878Y224428D03*
Y226928D03*
Y219428D03*
Y221928D03*
X1779226Y275604D03*
X1783563Y273471D03*
X1786089D03*
X1771029Y295164D03*
X1771229Y291064D03*
X1786089Y287641D03*
X1783563D03*
X1772863Y310478D03*
X1783018Y301729D03*
X1782324Y410432D03*
Y403932D03*
Y425432D03*
Y418932D03*
X1782420Y447137D03*
X1781470Y452065D03*
X1776160Y592792D03*
X1778310Y591152D03*
X1778165Y1307422D03*
Y1304422D03*
Y1301422D03*
X1775165D03*
X1772165D03*
X1778165Y1295422D03*
X1775165D03*
X1772165D03*
Y1298422D03*
X1775165D03*
X1778165D03*
X1784165Y1307422D03*
Y1304422D03*
X1781165Y1307422D03*
Y1304422D03*
X1784165Y1301422D03*
Y1295422D03*
Y1298422D03*
X1781165Y1301422D03*
Y1295422D03*
Y1298422D03*
X1781829Y1324448D03*
X1784829D03*
X1778829D03*
X1778165Y1310422D03*
Y1312922D03*
X1784165Y1310422D03*
Y1312922D03*
X1781165Y1310422D03*
Y1312922D03*
X1781829Y1333148D03*
Y1330248D03*
Y1327348D03*
X1784829Y1333148D03*
Y1330248D03*
Y1327348D03*
X1781829Y1337548D03*
Y1340448D03*
X1784829Y1337548D03*
Y1340448D03*
X1778829Y1333148D03*
Y1330248D03*
Y1327348D03*
Y1337548D03*
X1772829D03*
X1775829D03*
X1778829Y1340448D03*
X1775829D03*
X1772829D03*
X1781829Y1346248D03*
Y1343348D03*
Y1349148D03*
Y1351858D03*
Y1354758D03*
X1772829Y1346248D03*
X1775829D03*
X1778829D03*
X1772829Y1343348D03*
X1775829D03*
X1778829D03*
X1772829Y1349148D03*
X1775829D03*
X1778829D03*
X1772829Y1351858D03*
X1775829D03*
X1778829D03*
X1772829Y1354758D03*
X1775829D03*
X1778829D03*
X1771866Y1737108D03*
X1787768Y3010D03*
X1793061Y24659D03*
X1794910Y44573D03*
X1799920Y52594D03*
X1788238Y82292D03*
Y78062D03*
Y74912D03*
X1803215Y154032D03*
X1797663Y269571D03*
X1800189D03*
X1790563Y273471D03*
X1793089D03*
X1793269Y287641D03*
X1790743D03*
X1791619Y294441D03*
X1789093D03*
X1802763Y308671D03*
X1795763D03*
X1798289D03*
X1788763D03*
X1791289D03*
X1800160Y362542D03*
X1800340Y387062D03*
X1791494Y386536D03*
X1795479Y408056D03*
X1795468Y421334D03*
X1796020Y451162D03*
X1791888Y683805D03*
X1800107Y1256426D03*
X1798450Y1524830D03*
X1801450D03*
Y1527830D03*
X1814322Y49388D03*
X1807549Y56415D03*
X1807580Y59397D03*
X1806365Y154032D03*
X1807220Y179897D03*
X1814349Y269634D03*
X1811823D03*
X1807249D03*
X1804723D03*
X1812349Y308734D03*
X1809823D03*
X1805289Y308671D03*
X1817157Y373829D03*
X1816224Y410432D03*
X1816994Y398052D03*
X1815724Y423932D03*
X1812161Y472521D03*
X1803517Y1495567D03*
X1813700Y1494762D03*
X1818289Y1501591D03*
X1811494Y1505349D03*
X1813994Y1507891D03*
X1812250Y1521830D03*
X1811250Y1524830D03*
Y1527830D03*
X1807850D03*
X1804650D03*
Y1524830D03*
X1807850D03*
X1814370Y1528900D03*
X1814210Y1525815D03*
X1818524Y1528991D03*
X1834322Y49388D03*
X1828777Y156520D03*
X1823508Y158868D03*
X1825762Y167662D03*
X1835760Y185772D03*
X1829695Y226333D03*
X1832295D03*
X1827095D03*
X1824095D03*
X1834895D03*
Y223733D03*
X1824095D03*
X1827095D03*
X1832295D03*
X1829695D03*
X1832295Y233933D03*
X1829695D03*
X1827095D03*
X1824095D03*
X1829695Y231433D03*
X1832295D03*
X1829695Y228933D03*
X1832295D03*
X1827095Y231433D03*
X1824095D03*
X1827095Y228933D03*
X1824095D03*
X1834895Y233933D03*
Y231433D03*
Y228933D03*
X1829026Y367701D03*
X1829434Y406348D03*
X1834005Y401421D03*
X1821280Y413432D03*
X1834600Y406442D03*
X1826914Y431718D03*
X1829514Y1498198D03*
Y1500807D03*
X1832114Y1498198D03*
Y1500807D03*
X1824995Y1502201D03*
X1823426Y1507916D03*
X1831994Y1525977D03*
X1835334Y1520921D03*
X1821710Y1525915D03*
X1830466Y1606658D03*
X1828880Y1626595D03*
Y1646595D03*
Y1666595D03*
Y1686595D03*
X1846691Y166450D03*
X1848435Y172187D03*
X1838880Y195162D03*
X1837895Y226333D03*
Y223733D03*
Y233933D03*
Y231433D03*
Y228933D03*
X1843134Y244362D03*
X1850331Y311946D03*
X1840691Y329470D03*
Y349470D03*
Y369470D03*
X1836750Y373632D03*
X1836294Y383592D03*
X1840691Y389470D03*
Y409470D03*
Y429470D03*
Y449470D03*
X1838020Y459121D03*
X1838379Y453921D03*
X1840691Y469470D03*
Y489470D03*
Y509470D03*
Y529470D03*
Y549470D03*
Y569470D03*
Y589470D03*
Y669470D03*
Y1329470D03*
Y1409470D03*
Y1429470D03*
Y1449470D03*
Y1469470D03*
Y1489470D03*
Y1509470D03*
Y1529470D03*
Y1549470D03*
Y1569470D03*
Y1589470D03*
X1854096Y52383D03*
X1854470Y112379D03*
Y152379D03*
Y172379D03*
Y192379D03*
Y212379D03*
Y232379D03*
Y252379D03*
Y272379D03*
Y292379D03*
G54D20*
X40120Y744554D03*
Y1000853D03*
Y1287664D03*
X69820Y744554D03*
Y1000853D03*
Y1287664D03*
X99520Y744554D03*
Y1000853D03*
Y1287664D03*
X129220Y744554D03*
Y1000853D03*
Y1287664D03*
X158920Y744554D03*
Y1000853D03*
Y1287664D03*
X188620Y744554D03*
Y1000853D03*
Y1287664D03*
X218320Y744554D03*
Y1000853D03*
Y1287664D03*
X248020Y744554D03*
Y1000853D03*
Y1287664D03*
X633320Y744554D03*
Y1000853D03*
Y1287664D03*
X663020Y744554D03*
Y1000853D03*
Y1287664D03*
X692720Y744554D03*
Y1000853D03*
Y1287664D03*
X722420Y744554D03*
Y1000853D03*
Y1287664D03*
X752120Y744554D03*
Y1000853D03*
Y1287664D03*
X781820Y744554D03*
Y1000853D03*
Y1287664D03*
X811520Y744554D03*
Y1000853D03*
Y1287664D03*
X841220Y744554D03*
Y1000853D03*
Y1287664D03*
X1016262Y744554D03*
Y1000853D03*
Y1287664D03*
X1045962Y744554D03*
Y1000853D03*
Y1287664D03*
X1075662Y744554D03*
Y1000853D03*
Y1287664D03*
X1105362Y744554D03*
Y1000853D03*
Y1287664D03*
X1135062Y744554D03*
Y1000853D03*
Y1287664D03*
X1164762Y744554D03*
Y1000853D03*
Y1287664D03*
X1194462Y744554D03*
Y1000853D03*
Y1287664D03*
X1224162Y744554D03*
Y1000853D03*
Y1287664D03*
X1609462Y744554D03*
Y1000853D03*
Y1287664D03*
X1639162Y744554D03*
Y1000853D03*
Y1287664D03*
X1668862Y744554D03*
Y1000853D03*
Y1287664D03*
X1698562Y744554D03*
Y1000853D03*
Y1287664D03*
X1728262Y744554D03*
Y1000853D03*
Y1287664D03*
X1757962Y744554D03*
Y1000853D03*
Y1287664D03*
X1787662Y744554D03*
Y1000853D03*
Y1287664D03*
X1817362Y744554D03*
Y1000853D03*
Y1287664D03*
G54D123*
G01X1900275Y-9342D02*
X1904140D01*
X1904580Y-8902D01*
Y582418D01*
X1904140Y582858D01*
X1900275D01*
G01X1910275Y-9342D02*
X1906410D01*
X1905970Y-8902D01*
Y582418D01*
X1906410Y582858D01*
X1910275D01*
G54D114*
G01X34790Y666595D02*
X33840Y667545D01*
Y669142D01*
X45950Y681252D01*
X128568D01*
X143310Y666510D01*
Y656942D01*
X141793Y655425D01*
X139772D01*
X138766Y656431D01*
G01X31390Y666595D02*
X32340Y667545D01*
Y669764D01*
X45328Y682752D01*
X129190D01*
X144810Y667132D01*
Y656320D01*
X142415Y653925D01*
X139772D01*
X138766Y652919D01*
G01X110689Y498271D02*
Y496138D01*
X108025Y493474D01*
G01X112480Y507792D02*
X112400D01*
X112186Y508006D01*
X109393D01*
X108025Y509374D01*
G01X110464Y505374D02*
X108025D01*
G01X112590Y503248D02*
X110464Y505374D01*
G01X99880Y526300D02*
X100350Y526770D01*
X109432D01*
X117179Y519023D01*
Y512983D01*
G01X108025Y517925D02*
Y513374D01*
G01X110060Y515279D02*
X110000Y515219D01*
Y514107D01*
X109267Y513374D01*
X108025D01*
G01X109087Y522620D02*
Y518987D01*
X108025Y517925D01*
G01X105587Y520727D02*
X104875Y520015D01*
Y517925D01*
G01X117179Y512983D02*
X114833Y510637D01*
X112483D01*
G01D02*
X112497Y510651D01*
Y513689D01*
G01X117179Y507877D02*
X112505D01*
X112480Y507852D01*
Y507792D01*
G01X117149Y501638D02*
X114200D01*
X112590Y503248D01*
G01X121400Y638062D02*
X125056Y641718D01*
X126092D01*
G01X130530Y658172D02*
X128381Y656023D01*
X125852D01*
X125760Y656115D01*
G01D02*
X123784D01*
X122329Y654660D01*
G01D02*
X119439Y657550D01*
X118022D01*
G01X125760Y652965D02*
X127653D01*
X127850Y653162D01*
X130570D01*
G01X118022Y651734D02*
X118222Y651934D01*
X122280D01*
G01D02*
X124729D01*
X125760Y652965D01*
G01X124431Y649569D02*
Y647228D01*
X124025Y646822D01*
G01X124431Y649569D02*
X124416Y649554D01*
X119069Y647338D01*
X118058Y646327D01*
G01X124431Y649570D02*
Y649569D01*
G01X163926Y443319D02*
X160877Y446368D01*
X145956D01*
X142710Y443122D01*
Y415312D01*
X135220Y407822D01*
Y397071D01*
G01X144640Y510230D02*
X144092D01*
X141462Y507600D01*
G01X130530Y658172D02*
X132850Y655852D01*
X135037D01*
X135616Y656431D01*
G01X130570Y653162D02*
X131760Y654352D01*
X134183D01*
X135616Y652919D01*
G01X131600Y646861D02*
X127214D01*
X127175Y646822D01*
G01X163926Y439397D02*
X158600Y434071D01*
Y416842D01*
X154220Y412462D01*
Y375682D01*
G01X152826Y439397D02*
X156560Y435663D01*
Y418472D01*
X149840Y411752D01*
Y374462D01*
X151980Y372322D01*
X155540D01*
X158110Y374892D01*
Y376172D01*
G01X163926Y435383D02*
X161560Y433017D01*
Y416222D01*
X157660Y412322D01*
Y383752D01*
X161670Y379742D01*
Y344542D01*
G01X144640Y510230D02*
Y506960D01*
X143972Y506292D01*
Y505550D01*
G01X149568Y1395145D02*
X150362Y1394351D01*
X153789D01*
G01X149568Y1397695D02*
X149762Y1397501D01*
X153789D01*
G01X164686Y394320D02*
X168454D01*
X168562Y394428D01*
G01X173275Y393497D02*
X172387Y394385D01*
X168605D01*
X168562Y394428D01*
G01X164686Y391170D02*
X160090D01*
G01X190880Y391082D02*
Y391992D01*
X185700Y397172D01*
X181630D01*
X173170Y405632D01*
X167870D01*
X166900Y406602D01*
Y412462D01*
X164000Y415362D01*
G01X164686Y397470D02*
X160090D01*
G01X416999Y1441908D02*
X416117Y1442790D01*
Y1448614D01*
X406388Y1458343D01*
X233925D01*
X225257Y1449675D01*
X206475D01*
X204937Y1451213D01*
X174648D01*
X173727Y1452134D01*
G01X413599Y1441908D02*
X414567Y1442876D01*
Y1447712D01*
X405511Y1456768D01*
X234937D01*
X226077Y1447908D01*
X205763D01*
X204033Y1449638D01*
X174631D01*
X173727Y1448734D01*
G01X187711Y1395170D02*
X188555Y1394326D01*
X190332D01*
G01X190971Y1410745D02*
X190426Y1410200D01*
X190090D01*
X188211Y1408321D01*
Y1406691D01*
G01X202338Y568746D02*
X202965Y568119D01*
Y565982D01*
G01X205251Y577002D02*
Y576350D01*
X207659Y573942D01*
X209356D01*
X210679Y572619D01*
G01X201622Y581009D02*
X205251Y577380D01*
Y577002D01*
G01X202338Y602746D02*
X202538Y602546D01*
X202816D01*
X204561Y600801D01*
G01X205251Y611002D02*
Y610350D01*
X207549Y608052D01*
X209246D01*
X210679Y606619D01*
G01X204610Y605097D02*
X206716D01*
X207619Y604194D01*
Y600893D01*
X207711Y600801D01*
G01X201622Y615009D02*
X205251Y611380D01*
Y611002D01*
G01X202338Y636746D02*
X202538Y636546D01*
X203133D01*
X204421Y635258D01*
Y634932D01*
X204471Y634882D01*
G01X204610Y639097D02*
X206716D01*
X207479Y638334D01*
Y636916D01*
X207529Y636866D01*
Y634974D01*
X207621Y634882D01*
G01X205251Y642969D02*
X206746Y641474D01*
X209824D01*
X210679Y640619D01*
G01X201622Y649009D02*
X204056Y646575D01*
Y644164D01*
X205251Y642969D01*
G01X212891Y566632D02*
Y567981D01*
X213829Y568919D01*
Y572619D01*
G01X210391Y567981D02*
X210679Y568269D01*
Y572619D01*
G01X212891Y601981D02*
X213829Y602919D01*
Y606619D01*
G01X210391Y601981D02*
X210679Y602269D01*
Y606619D01*
G01X210391Y635981D02*
X210679Y636269D01*
Y640619D01*
G01X212891Y635981D02*
X213829Y636919D01*
Y640619D01*
G01X396822Y1439340D02*
X392537Y1443625D01*
X240627D01*
X232404Y1435402D01*
X219587D01*
G01X224780Y1443402D02*
X219587D01*
G01X233158Y1441976D02*
X230584Y1439402D01*
X219587D01*
G01X427546Y1443411D02*
X426677Y1444280D01*
Y1450283D01*
X409887Y1467073D01*
X225247D01*
X218417Y1460243D01*
Y1455673D01*
X217469Y1454725D01*
G01X424146Y1443411D02*
X425117Y1444382D01*
Y1449694D01*
X409268Y1465543D01*
X225968D01*
X219967Y1459542D01*
Y1455627D01*
X220869Y1454725D01*
G01X440164Y1433982D02*
Y1440188D01*
X437427Y1442925D01*
X432647D01*
X429537Y1439815D01*
X420397D01*
X419521Y1438939D01*
X417404Y1438062D01*
X411870D01*
X408007Y1441925D01*
Y1444755D01*
X402567Y1450195D01*
X235923D01*
X229130Y1443402D01*
X224780D01*
G01X433539Y1430613D02*
X431899Y1428973D01*
X423927D01*
X420747Y1432153D01*
X417727D01*
X415255Y1434625D01*
X409977D01*
X404816Y1439786D01*
Y1442224D01*
X399945Y1447095D01*
X238277D01*
X233158Y1441976D01*
G01X395459Y1142827D02*
X310045D01*
X284107Y1168765D01*
Y1366248D01*
X296850Y1378991D01*
X301855D01*
X302805Y1379941D01*
G01X395459Y1144327D02*
X310667D01*
X285607Y1169387D01*
Y1365626D01*
X297472Y1377491D01*
X301855D01*
X302805Y1376541D01*
G01X295685Y165447D02*
X293935Y167197D01*
Y170297D01*
X295540Y171902D01*
Y177881D01*
X296188Y178529D01*
X297386D01*
X298211Y177704D01*
G01X290685Y165447D02*
X292435Y167197D01*
Y170919D01*
X294040Y172524D01*
Y178503D01*
X295566Y180029D01*
X297386D01*
X298211Y180854D01*
G01X302136Y177279D02*
X301711Y177704D01*
X298211D01*
G01X302136Y181279D02*
X301711Y180854D01*
X298211D01*
G01X414333Y1385292D02*
Y1383530D01*
X413380Y1382577D01*
Y1380262D01*
X411590Y1378472D01*
X403566D01*
X383569Y1398469D01*
Y1417656D01*
X376967Y1424258D01*
X321889D01*
X302646Y1405015D01*
Y1387754D01*
X310647Y1379753D01*
Y1376005D01*
X306037Y1371395D01*
X298867D01*
X292724Y1365252D01*
Y1317346D01*
X295947Y1314123D01*
X299346D01*
X300839Y1315616D01*
G01X412212Y1137469D02*
Y1142592D01*
X406893Y1147911D01*
X398267D01*
X396203Y1149975D01*
X315857D01*
X308807Y1157025D01*
Y1311659D01*
X306243Y1314223D01*
X302232D01*
X300839Y1315616D01*
G01X414062Y1127856D02*
Y1131060D01*
G03X413156Y1132651I-1850J0D01*
G01X413118Y1132673D01*
G02X412212Y1134264I944J1591D01*
G03X411306Y1135855I-1850J0D01*
G01X411287Y1135866D01*
G02X410362Y1137416I925J1603D01*
G01Y1138177D01*
G03X409436Y1139221I-1850J-708D01*
G01Y1139267D01*
X408515Y1140188D01*
Y1144167D01*
X406271Y1146411D01*
X397767D01*
X395703Y1148475D01*
X315235D01*
X307307Y1156403D01*
Y1310737D01*
X305321Y1312723D01*
X302431D01*
X300839Y1311131D01*
G01X410933Y1384648D02*
Y1383530D01*
X411880Y1382583D01*
Y1380884D01*
X410968Y1379972D01*
X404188D01*
X385069Y1399091D01*
Y1418278D01*
X377589Y1425758D01*
X321267D01*
X301146Y1405637D01*
Y1387132D01*
X309147Y1379131D01*
Y1376627D01*
X305415Y1372895D01*
X298245D01*
X291224Y1365874D01*
Y1316724D01*
X295325Y1312623D01*
X299347D01*
X300839Y1311131D01*
G01X302401Y1363111D02*
X304051Y1364761D01*
Y1365453D01*
G01X339366Y871025D02*
X329127Y860786D01*
Y827513D01*
X338327Y818313D01*
Y801574D01*
X351267Y788634D01*
Y756742D01*
X351817Y756192D01*
Y735160D01*
X350817Y734160D01*
X349668D01*
X348730Y735098D01*
G01X340426Y869964D02*
X340072Y869610D01*
Y869609D01*
X330627Y860164D01*
Y828135D01*
X339827Y818935D01*
Y802196D01*
X352767Y789256D01*
Y757364D01*
X353317Y756814D01*
Y734538D01*
X351439Y732660D01*
X349692D01*
X348730Y731698D01*
G01X336179Y1340093D02*
Y1342753D01*
G01X510579Y838643D02*
Y783725D01*
X414548Y687694D01*
X360619D01*
X359669Y686744D01*
G01X509079Y838643D02*
Y784347D01*
X413926Y689194D01*
X360559D01*
X359639Y690114D01*
G01X501679Y838203D02*
Y784707D01*
X413370Y696398D01*
X364051D01*
X363101Y697348D01*
G01X503179Y838203D02*
Y784085D01*
X413992Y694898D01*
X364051D01*
X363101Y693948D01*
G01X370923Y1325373D02*
Y1323451D01*
X369828Y1322356D01*
X368391D01*
G01Y1325506D02*
Y1328161D01*
G01X400073Y1327653D02*
X400173Y1327553D01*
Y1327543D01*
X400462Y1327254D01*
Y1325167D01*
G01X416856Y1415275D02*
Y1411969D01*
X416127Y1411240D01*
G01X415856Y1420283D02*
X416856Y1419283D01*
Y1415275D01*
G01X410912Y1418177D02*
X411062D01*
X413168Y1420283D01*
X415856D01*
G01X435179Y1325373D02*
Y1323647D01*
X433524Y1321992D01*
X431728D01*
G01X435570Y1398366D02*
X432737D01*
X430910Y1400193D01*
Y1401997D01*
G01X435570Y1398366D02*
X439291D01*
X439391Y1398266D01*
G01X441369Y1394260D02*
X439787Y1395842D01*
X428540D01*
X424320Y1400062D01*
Y1401987D01*
G01X445339Y1415731D02*
X445319Y1415751D01*
X444939D01*
X443673Y1414485D01*
X442277D01*
X440514Y1412722D01*
Y1411504D01*
G01X445230Y1411719D02*
X449933D01*
X449974Y1411678D01*
G01X450294Y1420544D02*
X446937D01*
X446123Y1419730D01*
X445723D01*
G01D02*
X445323Y1419330D01*
X444084D01*
X440029Y1415275D01*
X438059D01*
G01X443850Y1423404D02*
X443350Y1422904D01*
X442362D01*
X441029Y1421571D01*
Y1420659D01*
G01X446395Y1424269D02*
X446155Y1424029D01*
X444975D01*
X444350Y1423404D01*
X443850D01*
G01X464191Y1325167D02*
Y1327793D01*
G01X478475Y1408172D02*
Y1411613D01*
X479646Y1412784D01*
G01X481997Y1409955D02*
X480214Y1408172D01*
X478475D01*
G01X475325D02*
Y1411705D01*
X474246Y1412784D01*
G01X470987Y1409965D02*
X470597Y1409575D01*
Y1407163D01*
X470780Y1406980D01*
G01D02*
X472720D01*
X473912Y1408172D01*
X475325D01*
G01X496319Y1338593D02*
Y1341264D01*
G01X528929Y1361666D02*
Y1364212D01*
G01X542620Y103352D02*
Y106882D01*
X546878Y111140D01*
X550700D01*
G01X546370Y117157D02*
Y115257D01*
X547338Y114289D01*
X550700D01*
G01X564988Y118670D02*
X569832D01*
X570540Y117962D01*
Y114132D01*
G01D02*
Y109682D01*
X570480Y109622D01*
G01X663187Y1395170D02*
X663981Y1394376D01*
X667408D01*
G01X663187Y1397720D02*
X663381Y1397526D01*
X667408D01*
G01X701830Y1404770D02*
Y1407326D01*
G01X701330Y1395195D02*
X702174Y1394351D01*
X703951D01*
G01X708830Y1623115D02*
X702555D01*
X698800Y1619360D01*
Y1565870D01*
X701515Y1563155D01*
Y1554235D01*
X702730Y1553020D01*
X711650D01*
X717300Y1547370D01*
G01X704537Y1591683D02*
Y1595223D01*
X704937Y1595623D01*
G01D02*
X704877Y1595683D01*
X702112D01*
G01X706137Y1601983D02*
X704370Y1603750D01*
Y1604580D01*
G01X725910Y1611900D02*
Y1608856D01*
X724392Y1607338D01*
G01X985480Y1653580D02*
Y1657370D01*
X983740Y1659110D01*
X963690D01*
X960000Y1662800D01*
Y1668900D01*
X947670Y1681230D01*
Y1722180D01*
X944140Y1725710D01*
X776990D01*
X747290Y1696010D01*
Y1670590D01*
X750970Y1666910D01*
Y1663010D01*
X743550Y1655590D01*
X740840D01*
G01X754537Y1581783D02*
X754629Y1581691D01*
Y1577295D01*
X754537Y1577203D01*
G01X758360Y1589661D02*
X754537Y1585838D01*
Y1581783D01*
G01X758360Y1589661D02*
X758361Y1589660D01*
X760802D01*
X762277Y1588185D01*
X765097D01*
X765188Y1588276D01*
G01X769452Y1584393D02*
X768719Y1585126D01*
X765188D01*
G01X806588Y351097D02*
X813855Y354008D01*
G01X808297Y1591358D02*
X808206Y1591267D01*
X806126D01*
X804652Y1589793D01*
G01X808297Y1588208D02*
X811537D01*
X812698Y1587047D01*
G01X813855Y354008D02*
X820936Y356956D01*
G01D02*
X828222Y359960D01*
G01D02*
X835471Y363003D01*
G01D02*
X843133Y366158D01*
G01X855858Y212425D02*
X852795Y209362D01*
G01X855933Y215375D02*
X853682D01*
X852695Y216362D01*
G01X843133Y366158D02*
X851396Y369614D01*
G01D02*
X859734Y373032D01*
G01X850415Y1590822D02*
X847681D01*
X846652Y1589793D01*
G01X854777Y1586968D02*
X854073Y1587672D01*
X850415D01*
G01X859734Y373032D02*
X867922Y376450D01*
G01D02*
X875922Y379793D01*
G01D02*
X883472Y382910D01*
G01D02*
X887869Y386618D01*
G01X892332Y1591218D02*
X890077D01*
X888652Y1589793D01*
G01X896672Y1587073D02*
X895677Y1588068D01*
X892332D01*
G01X919300Y990077D02*
Y986267D01*
G01X919325Y986242D02*
X919300Y986267D01*
G01D02*
X919078Y986489D01*
X915338D01*
X914838Y985989D01*
G01X1019802Y214099D02*
X1014120D01*
X1011630Y216589D01*
Y218253D01*
G01X1010470Y224169D02*
X1008572Y222271D01*
Y218345D01*
X1008480Y218253D01*
G01X1011720Y229699D02*
X1010470Y228449D01*
Y224169D01*
G01X1032317Y291284D02*
Y294475D01*
X1032260Y294532D01*
G01D02*
X1034315Y296587D01*
X1037000D01*
G01X1036278Y303993D02*
X1035022Y305249D01*
X1030822D01*
X1028994Y307077D01*
Y310397D01*
X1031064Y312467D01*
X1045728D01*
X1048483Y309712D01*
X1125082D01*
X1135152Y319782D01*
X1180899D01*
X1190969Y309712D01*
X1227353D01*
X1248913Y288152D01*
X1269268D01*
X1274184Y293068D01*
X1277589D01*
X1279289Y294768D01*
G01X1036278Y307393D02*
X1035634Y306749D01*
X1031452D01*
X1030494Y307707D01*
Y309775D01*
X1031686Y310967D01*
X1045106D01*
X1047861Y308212D01*
X1125704D01*
X1135774Y318282D01*
X1180277D01*
X1190347Y308212D01*
X1226730D01*
X1248290Y286652D01*
X1269890D01*
X1274806Y291568D01*
X1277305D01*
X1279289Y289584D01*
Y289368D01*
G01X1069216Y1256944D02*
X1071673D01*
X1071991Y1257262D01*
G01D02*
X1073029Y1256224D01*
Y1254504D01*
G01X1122879Y1431474D02*
X1123581Y1430772D01*
X1127008D01*
X1127100Y1430680D01*
G01X1122879Y1434024D02*
X1126824D01*
X1127018Y1433830D01*
X1127100D01*
G01X1129169Y1442998D02*
X1129105Y1442934D01*
X1126808D01*
X1126100Y1443642D01*
Y1444707D01*
G01X1132187Y1582738D02*
X1132560Y1583111D01*
Y1584290D01*
X1131687Y1585163D01*
G01X1135687D02*
X1134970Y1584446D01*
Y1582955D01*
X1135187Y1582738D01*
G01X1131687Y1588313D02*
Y1590238D01*
X1132187Y1590738D01*
G01X1135687Y1588313D02*
Y1590238D01*
X1135187Y1590738D01*
G01X1151687Y1577163D02*
Y1575238D01*
X1152187Y1574738D01*
G01X1141687Y1577163D02*
Y1575238D01*
X1142187Y1574738D01*
G01X1145687Y1577163D02*
Y1575238D01*
X1145187Y1574738D01*
G01X1141687Y1585163D02*
X1142187Y1584663D01*
Y1582738D01*
G01X1141687Y1580313D02*
X1142187Y1580813D01*
Y1582738D01*
G01X1145687Y1585163D02*
X1145187Y1584663D01*
Y1582738D01*
G01X1145687Y1580313D02*
X1145187Y1580813D01*
Y1582738D01*
G01X1151687Y1580313D02*
X1152187Y1580813D01*
Y1582738D01*
G01X1141687Y1588313D02*
Y1590238D01*
X1142187Y1590738D01*
G01X1151687Y1588313D02*
Y1590238D01*
X1152187Y1590738D01*
G01X1145687Y1588313D02*
Y1590238D01*
X1145187Y1590738D01*
G01X1151687Y1585163D02*
X1152187Y1584663D01*
Y1582738D01*
G01X1161022Y1431499D02*
X1161866Y1430655D01*
X1163643D01*
G01X1164172Y1447104D02*
X1164112Y1447044D01*
X1163852D01*
X1161522Y1444714D01*
Y1443630D01*
G01X1161095Y1577163D02*
Y1575238D01*
X1161595Y1574738D01*
G01X1155687Y1577163D02*
Y1575238D01*
X1155187Y1574738D01*
G01X1165095Y1577163D02*
X1164595Y1576663D01*
Y1574738D01*
G01X1161095Y1580313D02*
X1161595Y1580813D01*
Y1582738D01*
G01X1161095Y1585163D02*
X1161595Y1584663D01*
Y1582738D01*
G01X1165095Y1580313D02*
X1164595Y1580813D01*
Y1582738D01*
G01X1165095Y1585163D02*
X1164595Y1584663D01*
Y1582738D01*
G01X1155687Y1580313D02*
X1155187Y1580813D01*
Y1582738D01*
G01X1155687Y1585163D02*
X1155187Y1584663D01*
Y1582738D01*
G01X1161095Y1588313D02*
Y1590238D01*
X1161595Y1590738D01*
G01X1155687Y1588313D02*
Y1590238D01*
X1155187Y1590738D01*
G01X1165095Y1588313D02*
Y1590238D01*
X1164595Y1590738D01*
G01X1171095Y1577163D02*
Y1575238D01*
X1171595Y1574738D01*
G01X1175095Y1577163D02*
X1174595Y1576663D01*
Y1574738D01*
G01X1171095Y1585163D02*
X1171595Y1584663D01*
Y1582738D01*
G01X1171095Y1580313D02*
X1171595Y1580813D01*
Y1582738D01*
G01X1175095Y1585163D02*
X1174595Y1584663D01*
Y1582738D01*
G01X1175095Y1580313D02*
X1174595Y1580813D01*
Y1582738D01*
G01X1171095Y1588313D02*
Y1590238D01*
X1171595Y1590738D01*
G01X1175095Y1588313D02*
Y1590238D01*
X1174595Y1590738D01*
G01X1269012Y1371693D02*
X1268158Y1370839D01*
X1265486D01*
X1261237Y1366590D01*
Y1336054D01*
X1263266Y1334025D01*
Y1182424D01*
X1302667Y1143023D01*
X1374440D01*
G01Y1144523D02*
X1303289D01*
X1264766Y1183046D01*
Y1334647D01*
X1262737Y1336676D01*
Y1365968D01*
X1266108Y1369339D01*
X1267966D01*
X1269012Y1368293D01*
G01X1387074Y1384272D02*
Y1383530D01*
X1388050Y1382554D01*
Y1380514D01*
X1386934Y1379398D01*
X1381196D01*
X1362846Y1397748D01*
Y1424157D01*
X1352169Y1434834D01*
X1306077D01*
X1278531Y1407288D01*
Y1372292D01*
X1266487Y1360248D01*
Y1338465D01*
X1267906Y1337046D01*
Y1312132D01*
X1271354Y1308684D01*
X1275488D01*
X1276980Y1307192D01*
G01X1390204Y1127856D02*
Y1131060D01*
G03X1389298Y1132651I-1850J0D01*
G01X1389260Y1132673D01*
G02X1388354Y1134264I944J1591D01*
G03X1387448Y1135855I-1850J0D01*
G01X1387429Y1135866D01*
G02X1386504Y1137416I925J1603D01*
G01Y1138177D01*
G03X1385578Y1139221I-1850J-708D01*
G01Y1139267D01*
X1384635Y1140210D01*
Y1141821D01*
X1379932Y1146524D01*
X1307714D01*
X1283366Y1170872D01*
Y1306327D01*
X1281004Y1308689D01*
X1278477D01*
X1276980Y1307192D01*
G01X1388354Y1137469D02*
Y1142592D01*
X1387836Y1143110D01*
X1385468D01*
X1380554Y1148024D01*
X1308336D01*
X1284866Y1171494D01*
Y1306949D01*
X1281626Y1310189D01*
X1278468D01*
X1276980Y1311677D01*
G01X1390474Y1385142D02*
Y1383516D01*
X1389550Y1382592D01*
Y1379892D01*
X1387556Y1377898D01*
X1380574D01*
X1361346Y1397126D01*
Y1423535D01*
X1351547Y1433334D01*
X1306699D01*
X1280031Y1406666D01*
Y1371670D01*
X1267987Y1359626D01*
Y1339087D01*
X1269406Y1337668D01*
Y1312754D01*
X1271976Y1310184D01*
X1275487D01*
X1276980Y1311677D01*
G01X1282928Y1361833D02*
X1280836Y1359741D01*
X1280192D01*
G01X1312650Y1342572D02*
Y1340423D01*
X1312320Y1340093D01*
G01X1339727Y168549D02*
X1339395D01*
X1337547Y170397D01*
G01X1342903Y170399D02*
Y171333D01*
X1343411Y173258D01*
Y175451D01*
G01X1337547Y170397D02*
Y170739D01*
X1340683Y173875D01*
G01X1717140Y148910D02*
Y153952D01*
X1722690Y159502D01*
Y167870D01*
X1720730Y169830D01*
Y185919D01*
X1717560Y189089D01*
Y195380D01*
X1713320Y199620D01*
Y223402D01*
X1706242Y230480D01*
Y302070D01*
X1685959Y322353D01*
X1597501D01*
X1513198Y406656D01*
Y429234D01*
X1499630Y442802D01*
X1434044D01*
X1398704Y407462D01*
X1347212D01*
X1337220Y417454D01*
Y423162D01*
G01X1717418Y135327D02*
X1719520Y137429D01*
Y153442D01*
X1725990Y159912D01*
Y189600D01*
X1715820Y199770D01*
Y224438D01*
X1710024Y230234D01*
Y304517D01*
X1685524Y329017D01*
X1594373D01*
X1515698Y407692D01*
Y430270D01*
X1500666Y445302D01*
X1433008D01*
X1397668Y409962D01*
X1348248D01*
X1339720Y418490D01*
Y423162D01*
G01X1723670Y149102D02*
X1724580D01*
X1732540Y157062D01*
Y190393D01*
X1721373Y201560D01*
Y225957D01*
X1719145Y228185D01*
Y309411D01*
X1691115Y337441D01*
X1593021D01*
X1520698Y409764D01*
Y432342D01*
X1502738Y450302D01*
X1430936D01*
X1395596Y414962D01*
X1350320D01*
X1344720Y420562D01*
Y423162D01*
G01X1721418Y135327D02*
Y152941D01*
X1730660Y162183D01*
Y188971D01*
X1718320Y201311D01*
Y225474D01*
X1714251Y229543D01*
Y306742D01*
X1687319Y333674D01*
X1593252D01*
X1518198Y408728D01*
Y431306D01*
X1501702Y447802D01*
X1431972D01*
X1396632Y412462D01*
X1349284D01*
X1342220Y419526D01*
Y423162D01*
G01X1344532Y1325506D02*
Y1328161D01*
G01X1377214Y1327653D02*
Y1329922D01*
X1377003Y1330133D01*
G01X1416272Y1433949D02*
X1416640Y1434317D01*
Y1449164D01*
X1408997Y1456807D01*
X1388645D01*
X1381099Y1449261D01*
X1368842D01*
G01X1409680Y1430613D02*
X1408468D01*
X1406020Y1433061D01*
Y1446692D01*
X1401690Y1451022D01*
X1387810D01*
X1381449Y1444661D01*
X1368351D01*
X1364800Y1448212D01*
Y1449231D01*
G01X1503514Y801361D02*
X1502564Y800411D01*
X1498653D01*
X1486721Y812343D01*
Y838075D01*
G01X1408969Y1327645D02*
Y1329902D01*
X1409166Y1330099D01*
Y1330159D01*
G01X1415620Y1396652D02*
X1414130Y1398142D01*
X1410791D01*
X1406963Y1401970D01*
G01X1503514Y797961D02*
X1502564Y798911D01*
X1498031D01*
X1485221Y811721D01*
Y838075D01*
G01X1515940Y799215D02*
X1514990Y798265D01*
X1512218D01*
X1506670Y792717D01*
X1494471D01*
X1479321Y807867D01*
Y838203D01*
G01X1421480Y1415731D02*
X1417253Y1411504D01*
X1416655D01*
G01X1421371Y1411719D02*
X1423812D01*
X1424201Y1412108D01*
X1426101D01*
G01X1414200Y1415275D02*
X1415666D01*
X1420121Y1419730D01*
X1421864D01*
G01D02*
X1422678Y1420544D01*
X1426435D01*
G01X1419991Y1423404D02*
X1419915D01*
X1417170Y1420659D01*
G01X1421435Y1430415D02*
Y1428919D01*
X1422406Y1427948D01*
G01Y1424249D02*
X1422186Y1424029D01*
X1420616D01*
X1419991Y1423404D01*
G01X1515940Y795815D02*
X1514990Y796765D01*
X1512840D01*
X1507292Y791217D01*
X1493849D01*
X1477821Y807245D01*
Y838203D01*
G01X1441332Y1327793D02*
Y1330013D01*
X1441143Y1330202D01*
Y1330312D01*
G01X1454548Y1408139D02*
Y1411505D01*
X1455787Y1412744D01*
G01X1458138Y1409955D02*
X1456322Y1408139D01*
X1454548D01*
G01X1450387Y1412744D02*
X1451387Y1411744D01*
Y1408139D01*
G01D02*
X1451398D01*
G01X1445020Y1412672D02*
Y1412011D01*
X1448892Y1408139D01*
X1451387D01*
G01X1473956Y1341068D02*
X1473187Y1340299D01*
Y1339320D01*
X1472460Y1338593D01*
G01X1461062Y1413246D02*
X1465203D01*
X1465747Y1413790D01*
G01X1505570Y1364212D02*
X1505070Y1363712D01*
Y1361666D01*
G01X1624353Y1428766D02*
X1625066Y1428052D01*
X1628600D01*
G01X1624353Y1431316D02*
X1626411D01*
X1626616Y1431111D01*
X1628509D01*
X1628600Y1431202D01*
G01X1653230Y549322D02*
X1654654Y547898D01*
Y544622D01*
G01X1651635Y685836D02*
X1651435Y686036D01*
X1651079D01*
X1649373Y687742D01*
G01X1651635Y719836D02*
X1651435Y720036D01*
X1651216D01*
X1649491Y721761D01*
G01X1681363Y488288D02*
X1674225D01*
X1671726Y485789D01*
Y463594D01*
X1688666Y446654D01*
X1737812D01*
X1769276Y478118D01*
Y528034D01*
X1789650Y548408D01*
Y658792D01*
X1822220Y691362D01*
Y733862D01*
X1836850Y748492D01*
Y1299792D01*
X1814537Y1322105D01*
G01X1658275Y527195D02*
X1659091Y526379D01*
X1662997D01*
X1666368Y527775D01*
X1666928Y528335D01*
G01X1662262Y537334D02*
X1662276Y537348D01*
Y540386D01*
G01X1666958Y539680D02*
Y544214D01*
X1666840Y544332D01*
G01D02*
X1662894Y540386D01*
X1662276D01*
G01X1659740Y542222D02*
Y541163D01*
X1658648Y540071D01*
X1657804D01*
G01Y544622D02*
X1657660Y544478D01*
Y540215D01*
X1657804Y540071D01*
G01Y536071D02*
X1659172Y534703D01*
X1661872D01*
G01X1666472Y534524D02*
Y534306D01*
X1662467Y530301D01*
G01D02*
Y534108D01*
X1661872Y534703D01*
G01X1657804Y532071D02*
X1660243D01*
G01D02*
X1658275Y527318D01*
Y527195D01*
G01X1658450Y549550D02*
X1657804Y548904D01*
Y544622D01*
G01X1662496Y1428791D02*
X1663340Y1427947D01*
X1665117D01*
G01X1665666Y1444356D02*
X1664980Y1443670D01*
X1664740D01*
X1662996Y1441926D01*
Y1440922D01*
G01X1679103Y479078D02*
X1678439D01*
X1677495Y478134D01*
Y466107D01*
X1691005Y452597D01*
X1727819D01*
X1760236Y485014D01*
Y541177D01*
X1784330Y565271D01*
Y664308D01*
X1795987Y675965D01*
Y738781D01*
X1808977Y751771D01*
Y993015D01*
X1807520Y994472D01*
Y1007026D01*
X1808850Y1008356D01*
Y1227381D01*
X1811591Y1230122D01*
X1816986D01*
X1819069Y1228039D01*
X1823047D01*
X1824557Y1229549D01*
Y1249551D01*
X1832240Y1257234D01*
Y1274447D01*
X1825867Y1280820D01*
Y1292606D01*
X1799535Y1318938D01*
X1759922D01*
X1758352Y1317368D01*
G01X1679103Y482590D02*
X1678463D01*
X1676000Y480127D01*
Y465480D01*
X1690383Y451097D01*
X1728441D01*
X1761736Y484392D01*
Y540555D01*
X1785830Y564649D01*
Y663686D01*
X1797487Y675343D01*
Y738159D01*
X1810477Y751149D01*
Y993637D01*
X1809020Y995094D01*
Y1006404D01*
X1810350Y1007734D01*
Y1226759D01*
X1812213Y1228622D01*
X1816364D01*
X1818447Y1226539D01*
X1823669D01*
X1826057Y1228927D01*
Y1248929D01*
X1833740Y1256612D01*
Y1275069D01*
X1827367Y1281442D01*
Y1293228D01*
X1800157Y1320438D01*
X1760082D01*
X1758352Y1322168D01*
G01X1682253Y479078D02*
X1685686D01*
G01D02*
X1685778Y479170D01*
X1687694D01*
X1687828Y479304D01*
X1689943D01*
G01X1685686Y482228D02*
X1685777Y482137D01*
X1687670D01*
X1687962Y481845D01*
X1690229D01*
G01X1685686Y482228D02*
X1685440Y482474D01*
X1682369D01*
X1682253Y482590D01*
G01X1684513Y488288D02*
X1689121D01*
G01X1693611Y486806D02*
Y486176D01*
X1692931Y485496D01*
X1687238D01*
G01X1686564Y497580D02*
Y498261D01*
X1685094Y499731D01*
Y502279D01*
G01X1691151Y493678D02*
X1690969D01*
X1687067Y497580D01*
X1686564D01*
G01X1693647Y475583D02*
X1692315Y476915D01*
X1691470D01*
X1689093Y474538D01*
G01D02*
Y478454D01*
X1689943Y479304D01*
G01X1690229Y481845D02*
X1693201D01*
X1693624Y481422D01*
X1694385D01*
G01X1689121Y488288D02*
X1692919D01*
X1693611Y487596D01*
Y486806D01*
G01X1800450Y1505230D02*
X1799814Y1505866D01*
X1795759D01*
X1795545Y1505652D01*
G54D21*
X37721Y754822D03*
Y763090D03*
X54847Y754822D03*
Y763090D03*
X1446071Y732802D03*
Y741070D03*
X1463197Y732802D03*
Y741070D03*
G54D30*
X61157Y69340D03*
X61470Y84622D03*
X62812Y412708D03*
X62813Y415750D03*
X78269Y26474D03*
X74869D03*
X64557Y69340D03*
X72157Y75340D03*
X75557D03*
X64870Y84622D03*
X78120Y1515436D03*
Y1518836D03*
X76369Y1507456D03*
X75922Y1558974D03*
Y1562374D03*
X77618Y1572504D03*
X74218D03*
X85374Y19538D03*
X81974D03*
X92442Y26474D03*
X89042D03*
X86557Y69340D03*
X83157D03*
X94157Y75340D03*
X90998Y1518937D03*
Y1515537D03*
X89264Y1507611D03*
X92664D03*
X79769Y1507456D03*
X99547Y19538D03*
X110320D03*
X96147D03*
X106615Y26474D03*
X103215D03*
X108557Y69340D03*
X105157D03*
X97557Y75340D03*
X102251Y1576504D03*
X105651D03*
X113720Y19538D03*
X127894D03*
X124494D03*
X120789Y26474D03*
X117389D03*
X127157Y69340D03*
X116157Y75340D03*
X119557D03*
X130557Y69340D03*
X138157Y75340D03*
X141557D03*
X160360Y19538D03*
X156655Y26474D03*
X153255D03*
X152557Y69340D03*
X149157D03*
X145538Y1517374D03*
X148938D03*
X146312Y1569525D03*
X149712D03*
X163760Y19538D03*
X174533D03*
X170828Y26474D03*
X167428D03*
X175761Y69340D03*
X172361D03*
X161361Y75340D03*
X164761D03*
X164710Y1518014D03*
X168110D03*
X167266Y1569968D03*
X170666D03*
X177933Y19538D03*
X183361Y75340D03*
X186761D03*
X188897Y1578182D03*
X192297D03*
X188897Y1590094D03*
X192297D03*
X207894Y19538D03*
X204494D03*
X200789Y26474D03*
X197389D03*
X197761Y69340D03*
X194361D03*
X205495Y75340D03*
X208895D03*
X200957Y1578182D03*
X204357D03*
X200957Y1590094D03*
X204357D03*
X194197Y1614292D03*
X197597D03*
X206257D03*
X194197Y1602380D03*
X197597D03*
X206257D03*
X222067Y19538D03*
X218667D03*
X214962Y26474D03*
X211562D03*
X219895Y69340D03*
X216495D03*
X225077Y1578182D03*
X213017D03*
X216417D03*
X225077Y1590094D03*
X213017D03*
X216417D03*
X209657Y1614292D03*
X218317D03*
X221717D03*
X209657Y1602380D03*
X218317D03*
X221717D03*
X227495Y75340D03*
X230895D03*
X237137Y1578182D03*
X240537D03*
X228477D03*
X237137Y1590094D03*
X240537D03*
X228477D03*
X230377Y1614292D03*
X233777D03*
X230377Y1602380D03*
X233777D03*
X249197Y1578182D03*
X252597D03*
X249197Y1590094D03*
X252597D03*
X242437Y1614292D03*
X254497D03*
X245837D03*
X242437Y1602380D03*
X254497D03*
X245837D03*
X273317Y1578182D03*
X261257D03*
X264657D03*
X273317Y1590094D03*
X261257D03*
X264657D03*
X266557Y1614292D03*
X257897D03*
X269957D03*
X266557Y1602380D03*
X257897D03*
X269957D03*
X285377Y1578182D03*
X288777D03*
X276717D03*
X285377Y1590094D03*
X288777D03*
X276717D03*
X278617Y1614292D03*
X282017D03*
X278617Y1602380D03*
X282017D03*
X297437Y1578182D03*
X300837D03*
X297437Y1590094D03*
X300837D03*
X290677Y1614292D03*
X302737D03*
X294077D03*
X306137D03*
X290677Y1602380D03*
X302737D03*
X294077D03*
X306137D03*
X321557Y1578182D03*
X309497D03*
X312897D03*
X321557Y1590094D03*
X309497D03*
X312897D03*
X314797Y1614292D03*
X318197D03*
X314797Y1602380D03*
X318197D03*
X333617Y1578182D03*
X337017D03*
X324957D03*
X333617Y1590094D03*
X337017D03*
X324957D03*
X330257Y1614292D03*
X338917D03*
X326857D03*
X330257Y1602380D03*
X338917D03*
X326857D03*
X345677Y1578182D03*
X349077D03*
X345677Y1590094D03*
X349077D03*
X350977Y1614292D03*
X342317D03*
X354377D03*
X350977Y1602380D03*
X342317D03*
X354377D03*
X369797Y1578182D03*
X357737D03*
X361137D03*
X369797Y1590094D03*
X357737D03*
X361137D03*
X363037Y1614292D03*
X366437D03*
X363037Y1602380D03*
X366437D03*
X373197Y1578182D03*
Y1590094D03*
X375097Y1614292D03*
X378497D03*
X375097Y1602380D03*
X378497D03*
X402590Y1618952D03*
X419780Y1602802D03*
X405990Y1618952D03*
X423180Y1602802D03*
X476451Y1578182D03*
X485111D03*
X473051D03*
X476451Y1590094D03*
X485111D03*
X473051D03*
X478351Y1614292D03*
X481751D03*
X478351Y1602380D03*
X481751D03*
X500571Y1578182D03*
X488511D03*
X497171D03*
X500571Y1590094D03*
X488511D03*
X497171D03*
X490411Y1614292D03*
X493811D03*
X490411Y1602380D03*
X493811D03*
X512631Y1578182D03*
X509231D03*
X512631Y1590094D03*
X509231D03*
X514531Y1614292D03*
X502471D03*
X517931D03*
X505871D03*
X514531Y1602380D03*
X502471D03*
X517931D03*
X505871D03*
X519764Y40328D03*
X523164D03*
X519742Y71436D03*
X523142D03*
X524691Y1578182D03*
X533351D03*
X521291D03*
X524691Y1590094D03*
X533351D03*
X521291D03*
X526591Y1614292D03*
X529991D03*
X526591Y1602380D03*
X529991D03*
X536751Y1578182D03*
X548811D03*
X545411D03*
X536751Y1590094D03*
X548811D03*
X545411D03*
X538651Y1614292D03*
X542051D03*
X538651Y1602380D03*
X542051D03*
X555175Y71436D03*
X558575D03*
X560871Y1578182D03*
X557471D03*
X560871Y1590094D03*
X557471D03*
X562771Y1614292D03*
X550711D03*
X566171D03*
X554111D03*
X562771Y1602380D03*
X550711D03*
X566171D03*
X554111D03*
X572931Y1578182D03*
X581591D03*
X569531D03*
X572931Y1590094D03*
X581591D03*
X569531D03*
X574831Y1614292D03*
X578231D03*
X574831Y1602380D03*
X578231D03*
X597051Y1578182D03*
X584991D03*
X593651D03*
X597051Y1590094D03*
X584991D03*
X593651D03*
X598951Y1614292D03*
X586891D03*
X590291D03*
X598951Y1602380D03*
X586891D03*
X590291D03*
X613970Y188752D03*
X609111Y1578182D03*
X605711D03*
X609111Y1590094D03*
X605711D03*
X611011Y1614292D03*
X614411D03*
X602351D03*
X611011Y1602380D03*
X614411D03*
X602351D03*
X617370Y188752D03*
X630040D03*
X626640D03*
X621171Y1578182D03*
X629831D03*
X617771D03*
X621171Y1590094D03*
X629831D03*
X617771D03*
X623071Y1614292D03*
X626471D03*
X623071Y1602380D03*
X626471D03*
X645291Y1578182D03*
X633231D03*
X641891D03*
X645291Y1590094D03*
X633231D03*
X641891D03*
X647191Y1614292D03*
X635131D03*
X638531D03*
X647191Y1602380D03*
X635131D03*
X638531D03*
X656439Y47264D03*
X659839D03*
X657351Y1578182D03*
X653951D03*
X657351Y1590094D03*
X653951D03*
X662651Y1614292D03*
X659251D03*
X650591D03*
X662651Y1602380D03*
X659251D03*
X650591D03*
X704770Y182999D03*
Y179599D03*
Y194810D03*
Y191410D03*
Y218432D03*
Y206621D03*
Y215032D03*
Y203221D03*
X723041Y-13200D03*
Y-9800D03*
X716698Y185687D03*
Y173687D03*
Y177087D03*
Y197187D03*
Y200587D03*
Y189087D03*
Y209021D03*
Y212421D03*
X840001Y20200D03*
Y16800D03*
X902350Y208294D03*
X907470Y211980D03*
X902350Y204894D03*
X907470Y215380D03*
X902350Y219068D03*
X907470Y226154D03*
X902350Y222468D03*
X907470Y229554D03*
X953970Y208275D03*
X947496Y215397D03*
X953970Y204875D03*
X947496Y211997D03*
X957156Y227163D03*
X947496Y226135D03*
X957156Y230563D03*
X947496Y229535D03*
X980899Y-13200D03*
Y-9800D03*
Y20200D03*
Y16800D03*
X1032433Y-23211D03*
Y-19811D03*
Y-3211D03*
Y189D03*
X1156770Y638192D03*
X1153370D03*
X1161860Y642112D03*
X1165260D03*
X1173220Y636052D03*
X1169820D03*
X1183360Y642062D03*
X1186760D03*
X1196772Y1578182D03*
X1200172D03*
X1196772Y1590094D03*
X1200172D03*
X1212232Y1578182D03*
X1208832D03*
X1212232Y1590094D03*
X1208832D03*
X1214132Y1614292D03*
X1202072D03*
X1217532D03*
X1205472D03*
X1214132Y1602380D03*
X1202072D03*
X1217532D03*
X1205472D03*
X1220892Y1578182D03*
X1232952D03*
X1224292D03*
X1220892Y1590094D03*
X1232952D03*
X1224292D03*
X1226192Y1614292D03*
X1229592D03*
X1226192Y1602380D03*
X1229592D03*
X1245012Y1578182D03*
X1236352D03*
X1248412D03*
X1245012Y1590094D03*
X1236352D03*
X1248412D03*
X1238252Y1614292D03*
X1241652D03*
X1238252Y1602380D03*
X1241652D03*
X1257072Y1578182D03*
X1260472D03*
X1257072Y1590094D03*
X1260472D03*
X1262372Y1614292D03*
X1250312D03*
X1265772D03*
X1253712D03*
X1262372Y1602380D03*
X1250312D03*
X1265772D03*
X1253712D03*
X1269132Y1578182D03*
X1281192D03*
X1272532D03*
X1269132Y1590094D03*
X1281192D03*
X1272532D03*
X1274432Y1614292D03*
X1277832D03*
X1274432Y1602380D03*
X1277832D03*
X1290291Y-23211D03*
Y-19811D03*
Y-3211D03*
Y189D03*
X1293252Y1578182D03*
X1284592D03*
X1296652D03*
X1293252Y1590094D03*
X1284592D03*
X1296652D03*
X1298552Y1614292D03*
X1286492D03*
X1289892D03*
X1298552Y1602380D03*
X1286492D03*
X1289892D03*
X1305312Y1578182D03*
X1308712D03*
X1305312Y1590094D03*
X1308712D03*
X1310612Y1614292D03*
X1314012D03*
X1301952D03*
X1310612Y1602380D03*
X1314012D03*
X1301952D03*
X1317372Y1578182D03*
X1320772D03*
X1329432D03*
X1317372Y1590094D03*
X1320772D03*
X1329432D03*
X1322672Y1614292D03*
X1326072D03*
X1322672Y1602380D03*
X1326072D03*
X1341752Y-19811D03*
Y-23211D03*
Y189D03*
Y-3211D03*
X1344684Y280259D03*
X1332832Y1578182D03*
X1341492D03*
X1344892D03*
X1332832Y1590094D03*
X1341492D03*
X1344892D03*
X1346792Y1614292D03*
X1334732D03*
X1338132D03*
X1346792Y1602380D03*
X1334732D03*
X1338132D03*
X1348084Y280259D03*
X1358624Y284644D03*
X1355224D03*
X1353552Y1578182D03*
X1356952D03*
X1353552Y1590094D03*
X1356952D03*
X1358852Y1614292D03*
X1362252D03*
X1350192D03*
X1358852Y1602380D03*
X1362252D03*
X1350192D03*
X1380522Y260236D03*
Y263636D03*
X1368524Y282744D03*
X1365124D03*
X1378306Y657608D03*
X1374668Y659708D03*
X1378306Y669608D03*
X1374668Y671708D03*
Y683708D03*
X1378306Y681608D03*
X1374668Y695708D03*
X1378306Y693608D03*
Y705608D03*
X1374668Y707708D03*
Y719708D03*
X1378306Y717608D03*
X1365612Y1578182D03*
X1377672D03*
X1369012D03*
X1365612Y1590094D03*
X1377672D03*
X1369012D03*
X1370912Y1614292D03*
X1374312D03*
X1370912Y1602380D03*
X1374312D03*
X1384002Y197668D03*
X1389256D03*
X1380602D03*
X1392656D03*
X1380638Y245694D03*
X1386630Y238651D03*
X1380638Y249094D03*
X1386630Y242051D03*
X1388754Y253803D03*
Y257203D03*
X1386273Y268670D03*
Y272070D03*
X1393206Y664708D03*
X1389568Y662608D03*
X1393206Y679208D03*
X1389568Y677108D03*
X1393206Y693708D03*
X1389568Y691608D03*
Y706108D03*
X1393206Y708208D03*
X1393199Y722708D03*
X1389561Y720608D03*
X1385338Y735098D03*
X1388976Y737198D03*
X1381072Y1578182D03*
Y1590094D03*
X1382972Y1614292D03*
X1386372D03*
X1382972Y1602380D03*
X1386372D03*
X1401341Y177159D03*
X1404829Y184263D03*
X1404741Y177159D03*
X1408229Y184263D03*
X1412284Y171696D03*
X1398006Y197668D03*
X1406786D03*
X1401406D03*
X1410186D03*
X1407420Y220018D03*
X1410820D03*
X1404385Y240929D03*
X1400985D03*
X1413950Y184263D03*
X1423110D03*
X1417350D03*
X1426510D03*
X1415684Y171696D03*
X1436060Y220018D03*
X1432660D03*
X1457176Y656992D03*
X1460814Y654892D03*
Y666892D03*
X1457176Y668992D03*
X1460814Y678892D03*
X1457176Y680992D03*
X1460814Y690892D03*
X1457176Y704992D03*
Y692992D03*
X1460814Y702892D03*
X1457176Y716992D03*
X1460814Y714892D03*
X1472076Y657392D03*
Y671892D03*
X1475714Y659492D03*
Y673992D03*
X1472076Y686392D03*
X1475714Y688492D03*
X1472076Y700892D03*
X1475714Y702992D03*
X1472076Y715392D03*
X1475714Y717492D03*
X1468876Y728392D03*
X1472514Y730492D03*
X1477755Y1578182D03*
X1462295D03*
X1474355D03*
X1465695D03*
X1477755Y1590094D03*
X1462295D03*
X1474355D03*
X1465695D03*
X1467595Y1614292D03*
X1470995D03*
X1467595Y1602380D03*
X1470995D03*
X1482650Y-19811D03*
Y-23211D03*
Y189D03*
Y-3211D03*
X1489815Y1578182D03*
X1486415D03*
X1489815Y1590094D03*
X1486415D03*
X1491715Y1614292D03*
X1479655D03*
X1483055D03*
X1491715Y1602380D03*
X1479655D03*
X1483055D03*
X1501875Y1578182D03*
X1498475D03*
X1501875Y1590094D03*
X1498475D03*
X1503775Y1614292D03*
X1507175D03*
X1495115D03*
X1503775Y1602380D03*
X1507175D03*
X1495115D03*
X1525995Y1578182D03*
X1513935D03*
X1522595D03*
X1510535D03*
X1525995Y1590094D03*
X1513935D03*
X1522595D03*
X1510535D03*
X1515835Y1614292D03*
X1519235D03*
X1515835Y1602380D03*
X1519235D03*
X1538996Y69297D03*
X1535596D03*
X1538055Y1578182D03*
X1534655D03*
X1538055Y1590094D03*
X1534655D03*
X1527895Y1614292D03*
X1539955D03*
X1531295D03*
X1527895Y1602380D03*
X1539955D03*
X1531295D03*
X1556413Y19495D03*
X1549308Y26431D03*
X1552708D03*
X1557596Y69297D03*
X1546596Y75297D03*
X1549996D03*
X1550115Y1578182D03*
X1558775D03*
X1546715D03*
X1550115Y1590094D03*
X1558775D03*
X1546715D03*
X1552015Y1614292D03*
X1555415D03*
X1543355D03*
X1552015Y1602380D03*
X1555415D03*
X1543355D03*
X1570586Y19495D03*
X1573986D03*
X1559813D03*
X1563481Y26431D03*
X1566881D03*
X1560996Y69297D03*
X1568596Y75297D03*
X1571996D03*
X1574235Y1578182D03*
X1562175D03*
X1570835D03*
X1574235Y1590094D03*
X1562175D03*
X1570835D03*
X1564075Y1614292D03*
X1567475D03*
X1564075Y1602380D03*
X1567475D03*
X1584759Y19495D03*
X1588159D03*
X1577654Y26431D03*
X1591828D03*
X1581054D03*
X1582996Y69297D03*
X1579596D03*
X1590596Y75297D03*
X1586295Y1578182D03*
X1582895D03*
X1586295Y1590094D03*
X1582895D03*
X1588195Y1614292D03*
X1576135D03*
X1591595D03*
X1579535D03*
X1588195Y1602380D03*
X1576135D03*
X1591595D03*
X1579535D03*
X1598933Y19495D03*
X1602333D03*
X1595228Y26431D03*
X1604996Y69297D03*
X1601596D03*
X1593996Y75297D03*
X1598355Y1578182D03*
X1607015D03*
X1594955D03*
X1598355Y1590094D03*
X1607015D03*
X1594955D03*
X1600255Y1614292D03*
X1603655D03*
X1600255Y1602380D03*
X1603655D03*
X1623596Y69297D03*
X1612596Y75297D03*
X1615996D03*
X1622475Y1578182D03*
X1610415D03*
X1619075D03*
X1622475Y1590094D03*
X1610415D03*
X1619075D03*
X1612315Y1614292D03*
X1615715D03*
X1612315Y1602380D03*
X1615715D03*
X1634799Y19495D03*
X1638199D03*
X1627694Y26431D03*
X1631094D03*
X1626996Y69297D03*
X1635800Y75297D03*
X1639200D03*
X1634535Y1578182D03*
X1631135D03*
X1634535Y1590094D03*
X1631135D03*
X1636435Y1614292D03*
X1624375D03*
X1639835D03*
X1627775D03*
X1636435Y1602380D03*
X1624375D03*
X1639835D03*
X1627775D03*
X1648972Y19495D03*
X1652372D03*
X1641867Y26431D03*
X1645267D03*
X1650200Y69297D03*
X1646800D03*
X1646595Y1578182D03*
X1643195D03*
X1646595Y1590094D03*
X1643195D03*
X1651895Y1614292D03*
X1648495D03*
X1651895Y1602380D03*
X1648495D03*
X1671828Y26431D03*
X1672200Y69297D03*
X1668800D03*
X1657800Y75297D03*
X1661200D03*
X1678933Y19495D03*
X1682333D03*
X1686001Y26431D03*
X1689401D03*
X1675228D03*
X1679934Y75297D03*
X1683334D03*
X1696506Y19495D03*
X1693106D03*
X1694334Y69297D03*
X1690934D03*
X1705334Y75297D03*
X1701934D03*
G54D12*
X14092Y287115D03*
X16925Y203366D03*
X17061Y196368D03*
X24720Y216362D03*
Y232362D03*
Y224362D03*
Y240362D03*
X29962Y401000D03*
X27520Y434992D03*
X30200Y754822D03*
X24647Y1262074D03*
X26050Y1252272D03*
X33500Y200862D03*
X33670Y192862D03*
Y208362D03*
Y232362D03*
X42500Y224409D03*
X33670Y240362D03*
X40000Y298707D03*
Y293392D03*
X36255Y304972D03*
X39320Y392269D03*
X40940Y387302D03*
X44350Y400582D03*
X38620Y447202D03*
X38340Y440992D03*
X33350Y434992D03*
X39000Y731600D03*
X48697Y952481D03*
Y959331D03*
X39505Y987865D03*
X39927Y1249845D03*
X40217Y1258925D03*
X47190Y1252034D03*
X47567Y1246625D03*
X48269Y1672771D03*
X54920Y185039D03*
Y177165D03*
X62020Y295952D03*
X53825Y421746D03*
X57920Y443702D03*
X55564Y449734D03*
X57595Y603476D03*
X51878Y733922D03*
X61539Y756113D03*
X63487Y761105D03*
X60997Y768875D03*
X54620Y1258892D03*
X56777Y1252098D03*
Y1314165D03*
X54478Y1663669D03*
X54535Y1658447D03*
X53333Y1671862D03*
X65000Y1681900D03*
X58325Y1679275D03*
X65881Y305426D03*
X71500Y390812D03*
X71772Y421746D03*
X75490Y432519D03*
X72981Y466385D03*
X80300Y641862D03*
X80241Y659011D03*
X80123Y664031D03*
X80135Y667933D03*
X74559Y667814D03*
X76565Y717949D03*
X78397Y952481D03*
Y959331D03*
X70852Y1250055D03*
X69877Y1259125D03*
X76890Y1252034D03*
X65600Y1318588D03*
X65240Y1326068D03*
X74100Y1613300D03*
X86490Y200787D03*
Y208661D03*
X85960Y224409D03*
X85788Y240157D03*
X87620Y285321D03*
X87845Y278798D03*
Y295798D03*
X87820Y302821D03*
X87654Y376026D03*
X87520Y386502D03*
X85826Y420319D03*
X84410Y438519D03*
X94811Y510173D03*
X93069Y631917D03*
X90565Y636612D03*
X97560Y637624D03*
X91027Y643276D03*
X95725Y654540D03*
X95860Y659622D03*
X83165Y652564D03*
X91078Y649584D03*
X83208Y646436D03*
X83004Y705141D03*
X97295Y699786D03*
X90000Y766798D03*
X85747Y994357D03*
X92630Y1251615D03*
X84390Y1258982D03*
X82241Y1252037D03*
X87450Y1251692D03*
X81900Y1613300D03*
X85800D03*
X96420Y1693803D03*
X113490Y216596D03*
X113400Y232128D03*
X107200Y393562D03*
X107301Y388071D03*
X101317Y431727D03*
X110756Y465968D03*
X113597Y488434D03*
X107419Y487807D03*
X112480Y507792D03*
X110689Y498271D03*
X112590Y503248D03*
X99773Y515606D03*
X98490Y629496D03*
X102269Y634466D03*
X107045Y661917D03*
X99021Y663732D03*
X103397Y667272D03*
X101512Y702939D03*
X98134Y722501D03*
X107852Y767065D03*
X108097Y952481D03*
Y959331D03*
X98905Y987865D03*
X100287Y1249926D03*
X99577Y1259125D03*
X106590Y1252034D03*
X109320Y1246422D03*
X103902Y1584337D03*
X104318Y1589352D03*
X100620Y1596367D03*
X100020Y1615821D03*
X104400Y1632385D03*
X104318Y1637862D03*
X99600Y1668332D03*
X99645Y1663217D03*
X99980Y1698921D03*
X115850Y186362D03*
X122000Y207362D03*
X116920Y207462D03*
X114087Y285495D03*
X118920Y278875D03*
X114087Y302854D03*
X119220Y306236D03*
X125007Y384071D03*
Y396071D03*
X119457Y392071D03*
X114507Y404571D03*
X128145Y453722D03*
X125070Y486736D03*
X124124Y495883D03*
X118652Y528860D03*
X129762Y531942D03*
X117430Y636052D03*
X114021Y669409D03*
X116567Y763774D03*
X130147Y1249975D03*
X129277Y1259125D03*
X114020Y1259032D03*
X114604Y1251348D03*
X118927Y1308685D03*
X118727Y1316695D03*
X123220Y1324662D03*
X116798Y1589352D03*
X119500Y1622380D03*
X124795Y1681846D03*
X128195Y1674362D03*
X127195Y1696362D03*
Y1704362D03*
X117426Y1726622D03*
X125720Y1719262D03*
X132490Y420062D03*
X138042Y480238D03*
X132833D03*
X139370Y492560D03*
X136982Y497090D03*
X131737Y496295D03*
X131295Y487822D03*
X137672Y502106D03*
X135428Y510312D03*
X138878Y512550D03*
X138408Y507366D03*
X139153Y516453D03*
X132600Y537072D03*
X131740Y640103D03*
X130530Y658172D03*
X130570Y653162D03*
X131600Y646861D03*
X130325Y699824D03*
Y708624D03*
Y717424D03*
X145181Y950660D03*
X145485Y959265D03*
X145147Y994357D03*
X136010Y1249882D03*
X141641Y1252037D03*
X144359Y1246662D03*
X143680Y1262582D03*
X145087Y1343175D03*
X144263Y1412275D03*
X136518Y1602410D03*
X136522Y1598410D03*
X137420Y1708362D03*
X144520Y1717562D03*
X134557Y1722778D03*
X137852Y1726572D03*
X154220Y375682D03*
X160090Y391170D03*
Y397470D03*
X152826Y439397D03*
Y434362D03*
X156306Y449045D03*
X161267Y503143D03*
X151378Y526924D03*
X149400Y766798D03*
X160465Y985165D03*
X159780Y1241732D03*
X157610Y1246842D03*
X158977Y1259125D03*
X159587Y1403924D03*
X152026Y1614138D03*
X158335Y1614452D03*
X161310Y1708022D03*
X148145Y1701862D03*
X173275Y393497D03*
X164000Y415362D03*
X163926Y425383D03*
X164000Y420362D03*
X163926Y430883D03*
Y443319D03*
X178546Y453806D03*
X174881Y950660D03*
X175185Y959265D03*
X164976Y1226342D03*
X165990Y1252034D03*
X171341Y1252037D03*
X173770Y1260192D03*
X176560Y1251812D03*
X171262Y1443390D03*
X164920Y1712017D03*
X163060Y1717017D03*
X178226Y1726517D03*
X172962Y1721234D03*
X169777Y1726517D03*
X178142Y1720652D03*
X187371Y425383D03*
Y430883D03*
X194440Y433895D03*
Y439565D03*
X193110Y672272D03*
X179100Y766798D03*
X188493Y1251400D03*
X188307Y1260475D03*
X182000Y1251762D03*
X182587Y1343945D03*
X193293Y1722197D03*
X188794Y1725092D03*
X204699Y423242D03*
Y428742D03*
X205251Y577002D03*
X204610Y571097D03*
X205251Y611002D03*
X198336Y608271D03*
X199164Y616481D03*
X205251Y642969D03*
X200654Y646271D03*
X200018Y677492D03*
X199541Y684554D03*
X208787Y768035D03*
X204332Y950909D03*
X205627Y959575D03*
X197317Y989785D03*
X203040Y1262074D03*
X195690Y1252034D03*
X201041Y1252037D03*
X209390Y1250614D03*
X197460Y1404675D03*
X203120Y1624782D03*
X208115Y1624217D03*
X195590Y1714517D03*
X196010Y1709017D03*
X208295Y1703362D03*
X199050Y1726431D03*
X224210Y431501D03*
X224305Y422977D03*
X219995Y426267D03*
X224210Y436619D03*
X218140Y440735D03*
X218010Y432735D03*
X223664Y443125D03*
X220000Y448735D03*
X212891Y566632D03*
X218159Y776523D03*
X218197Y952481D03*
Y959331D03*
X225057Y989205D03*
X226910Y1227939D03*
X218590Y1251362D03*
X219660Y1260492D03*
X225390Y1252034D03*
X221637Y1316075D03*
X223387Y1336305D03*
X223647Y1343905D03*
X227007Y1372165D03*
Y1382165D03*
X224780Y1443402D03*
X223590Y1635840D03*
X220142Y1640209D03*
X214120Y1713462D03*
X235701Y21582D03*
X241310Y20322D03*
X238063Y26232D03*
X239820Y54362D03*
X239720Y71862D03*
X239010Y78542D03*
X242215Y151788D03*
X230359Y461683D03*
X236267Y763585D03*
X237667Y1027975D03*
X239657Y1035555D03*
X233970Y1245182D03*
X240240Y1252562D03*
X230084Y1251546D03*
X232820Y1259352D03*
X233158Y1441976D03*
X246510Y20362D03*
X246360Y26852D03*
X253910Y115722D03*
X249735Y152694D03*
X259933Y141122D03*
X245490Y159702D03*
X255810Y405582D03*
X252500Y415862D03*
X258066Y426735D03*
X259845Y461117D03*
X257750Y450842D03*
X259510Y757822D03*
X254160Y959342D03*
X254520Y953922D03*
X248575Y988405D03*
X247667Y1027975D03*
X255530Y1057940D03*
X248047Y1261902D03*
X247973Y1249200D03*
X246867Y1632667D03*
X254625Y1632354D03*
X263240Y38122D03*
X266990Y41832D03*
X275120Y28562D03*
X275900Y48872D03*
X263320Y87662D03*
X273620Y96662D03*
X263550Y120922D03*
X269191Y121092D03*
X275797Y120245D03*
X265910Y125492D03*
X260600Y151062D03*
X264578Y159203D03*
X263430Y422235D03*
X262963Y443735D03*
X272500Y447735D03*
X263040Y448752D03*
X272500Y452862D03*
X268331Y738029D03*
X271057Y762425D03*
X273737Y779755D03*
X263747Y885135D03*
X269117Y881535D03*
X276147Y916225D03*
X269977Y965105D03*
X266486Y1038775D03*
X262170Y1255061D03*
X263790Y1248688D03*
X269427Y1381893D03*
X287000Y20862D03*
X290799Y28362D03*
X289400Y54222D03*
X287000Y139862D03*
X276825Y140462D03*
X290685Y165447D03*
X289137Y735275D03*
X288901Y774093D03*
X291215Y782792D03*
X284223Y784922D03*
X289797Y791505D03*
X282417Y880465D03*
X279217Y902685D03*
X289404Y1017414D03*
X281759Y1010061D03*
X291497Y1023995D03*
X276582Y1040899D03*
X284103Y1037625D03*
X289406Y1049524D03*
X290654Y1037501D03*
X287875Y1044423D03*
X299500Y22862D03*
X295520Y26362D03*
X300248Y28362D03*
X302720Y38182D03*
X293161Y50522D03*
X298550Y51602D03*
X303715Y50857D03*
X305247Y71567D03*
X301600Y82457D03*
X302310Y75673D03*
X295357Y88903D03*
X307820Y95724D03*
X305025Y144202D03*
X299628Y149203D03*
Y158703D03*
X295685Y165447D03*
X300520Y552262D03*
X307987Y577658D03*
X293805Y565997D03*
X298000Y587890D03*
X308417Y585158D03*
X308447Y592255D03*
X306144Y602225D03*
X297024Y603533D03*
X296664Y616633D03*
X294679Y685046D03*
X299900Y700962D03*
X306579Y740759D03*
X298197Y786070D03*
X308557Y793945D03*
X307030Y807499D03*
X303730Y887208D03*
X296604Y1029634D03*
X294343Y1044589D03*
X310400Y50362D03*
X323040Y73122D03*
X322875Y84318D03*
X316364Y89212D03*
X310459Y75892D03*
X320430Y78002D03*
X324733Y148598D03*
X309756Y177449D03*
X320270Y200462D03*
X323314Y210645D03*
X322658Y229254D03*
X319718Y223750D03*
X316444Y559125D03*
X317860Y572322D03*
X319520Y577658D03*
X312007Y588675D03*
X319520Y582658D03*
X316127Y592785D03*
X318560Y587632D03*
X311820Y598762D03*
X317386Y623207D03*
X310847Y716105D03*
X317967Y771875D03*
X311417Y782375D03*
X323576Y804265D03*
X315274Y803537D03*
X310049Y813653D03*
X316354Y812166D03*
X310694Y897810D03*
X313886Y904524D03*
X310482Y909310D03*
X325182Y978814D03*
X317202Y970250D03*
X310839Y1023569D03*
X316808Y1033357D03*
X321078Y1038165D03*
X324515Y1060974D03*
X319515D03*
X321739Y1056828D03*
X311117Y1323175D03*
X323247Y1320875D03*
X311117Y1333175D03*
X310608Y1361189D03*
X335575Y214170D03*
X328588Y209677D03*
X328939Y229139D03*
X335385Y235309D03*
X335412Y222176D03*
X341295Y290239D03*
X336270Y402992D03*
X329050Y607402D03*
X331839Y789287D03*
X335473Y782485D03*
X326097Y796665D03*
X341584Y832077D03*
X333877Y869405D03*
X330963Y887959D03*
X326277Y919725D03*
X329807Y968595D03*
Y958595D03*
X327617Y1017035D03*
X341027Y1048921D03*
X325637Y1040899D03*
X327108Y1056694D03*
X336727Y1063055D03*
X330667Y1064105D03*
X331693Y1087864D03*
X325693D03*
X343040Y122522D03*
X343450Y131167D03*
X355189Y144267D03*
X351100Y150412D03*
X356295Y219362D03*
X353145Y228362D03*
X354145Y290591D03*
X343354Y391643D03*
X351422Y700972D03*
X348730Y735098D03*
X344377Y785725D03*
X349637Y986855D03*
X342231Y1055058D03*
X342289Y1338168D03*
X366775Y127662D03*
X366675Y158702D03*
X364014Y366391D03*
X371370Y373622D03*
X364014Y378649D03*
X370200Y409582D03*
X373720Y431362D03*
X365720Y440562D03*
X359639Y690114D03*
X363101Y693948D03*
X360990Y726862D03*
X358902Y739755D03*
X365547Y787015D03*
X363359Y797204D03*
X368830Y792479D03*
X359637Y986855D03*
X380930Y122022D03*
X379295Y131002D03*
X385720Y320902D03*
X376500Y366391D03*
Y378649D03*
X376770Y387272D03*
X390220Y392062D03*
X389920Y461362D03*
X387500Y495362D03*
X389020Y522862D03*
X374590Y736928D03*
X377987Y1297695D03*
X375030Y1325211D03*
X386827Y1429525D03*
X374900Y1534102D03*
X375430Y1676462D03*
X399240Y62722D03*
X404910Y62562D03*
X396294Y281585D03*
X395520Y448362D03*
X402500Y495362D03*
X394500Y522862D03*
X400589Y575236D03*
X399756Y813625D03*
X393156D03*
X399756Y807025D03*
X393156D03*
X406356Y813625D03*
Y807025D03*
X400888Y1395508D03*
X392947Y1397827D03*
X400924Y1408227D03*
X405946Y1408955D03*
X390777Y1435152D03*
X396946Y1537632D03*
X404920Y1539362D03*
X394360Y1616380D03*
X396824Y1673662D03*
X413459Y129061D03*
X420752Y239562D03*
X412720Y439362D03*
X417880Y461942D03*
X418520Y473562D03*
X412956Y813625D03*
Y807025D03*
X408339Y1325927D03*
X418320Y1383862D03*
X410933Y1384648D03*
X414909Y1395658D03*
X408915Y1402606D03*
X411150Y1408163D03*
X415856Y1420283D03*
X416926Y1426471D03*
X412416Y1431645D03*
X419302Y1434700D03*
X410074Y1424993D03*
X413599Y1441908D03*
X409140Y1566892D03*
X416020Y1620862D03*
X412456Y1649838D03*
X417960Y1650072D03*
X422650Y1653040D03*
X421320Y1671699D03*
X410249Y1673082D03*
X427120Y59862D03*
X428500Y65016D03*
Y70016D03*
X435340Y125346D03*
X429780Y153477D03*
X429395Y236562D03*
X428720Y439362D03*
X437720Y435362D03*
X437520Y476337D03*
X431220Y496362D03*
Y507143D03*
Y512623D03*
Y501643D03*
X425550Y924546D03*
X439104Y1324785D03*
X426320Y1383862D03*
X439030Y1383692D03*
X436467Y1391687D03*
X438458Y1402169D03*
X435570Y1398366D03*
X438645Y1426890D03*
X437299Y1436774D03*
X425030Y1434292D03*
X424820Y1552605D03*
X431620Y1541362D03*
X433350Y1579509D03*
X432200Y1607060D03*
X432500Y1613822D03*
X435500Y1646962D03*
X446640Y104552D03*
X443678Y145710D03*
X446746Y152662D03*
X442220Y323362D03*
X448220Y323582D03*
X450500Y358862D03*
X446730Y382432D03*
X443770Y371042D03*
X443300Y410962D03*
X447750Y414112D03*
X453020Y414262D03*
X443744Y429553D03*
X451421D03*
X442520Y476337D03*
Y484837D03*
X451520D03*
X453680Y515072D03*
X439427Y793255D03*
X449427D03*
X441836Y841835D03*
X448436D03*
X443842Y1389106D03*
X448020Y1391862D03*
X443424Y1397869D03*
X441369Y1394260D03*
X442970Y1406832D03*
X453805Y1396730D03*
X448114Y1396812D03*
X445230Y1411719D03*
X445723Y1419730D03*
X449778Y1441606D03*
X452520Y1564862D03*
X454661Y1609235D03*
X448181Y1614401D03*
X443800Y1610712D03*
X444940Y1641842D03*
X462320Y115948D03*
X466992Y145888D03*
X458264Y254862D03*
X461736Y306098D03*
X469830Y366158D03*
X456660Y359172D03*
X460800Y375362D03*
X455720Y404762D03*
X458600Y414262D03*
X466520Y475812D03*
X461520Y484837D03*
X457456Y522516D03*
X470880Y572692D03*
X467130Y600122D03*
X469427Y793255D03*
X459427D03*
X467436Y925602D03*
X456327Y926551D03*
X471437Y1294035D03*
X471545Y1325025D03*
X459321Y1396409D03*
X458441Y1414893D03*
X468880Y1418400D03*
X467400Y1556700D03*
X466520Y1574862D03*
X457220Y1603562D03*
X455681Y1622492D03*
X458978Y1634481D03*
X463344Y1637622D03*
X469580Y1640272D03*
X466460Y1672332D03*
X466180Y1678392D03*
X484396Y161364D03*
X476220Y158772D03*
X486720Y360862D03*
X482920Y398060D03*
X485020Y414162D03*
X480393Y429412D03*
X471920Y416687D03*
X474169Y476196D03*
X479169D03*
X482780Y607012D03*
X479427Y793255D03*
X474703Y925819D03*
X480587Y1294035D03*
X477968Y1548122D03*
X486210Y1547960D03*
X482400Y1558320D03*
X477905Y1659242D03*
X475150Y1654302D03*
X494112Y88040D03*
X503310Y113262D03*
X497800Y113562D03*
X500500Y117962D03*
X492150Y336810D03*
X498720Y360862D03*
X497568Y397632D03*
X489520Y411862D03*
X494020Y414262D03*
X502070Y424787D03*
X488070Y429412D03*
X493169Y476196D03*
X498169D03*
X493169Y484696D03*
X503218Y1337798D03*
X490307Y1421499D03*
X488920Y1408742D03*
X507335Y88862D03*
X510600Y92782D03*
X504700Y93862D03*
X513700Y117862D03*
X510900Y111962D03*
X519010Y147912D03*
X518186Y139821D03*
X514850Y168443D03*
X519236Y202404D03*
X518670Y219192D03*
X507160Y332452D03*
X514720Y360862D03*
X513720Y390362D03*
X513173Y408740D03*
X514637Y1426345D03*
X505777Y1425579D03*
X529720Y43054D03*
X534720Y42922D03*
X523978Y59074D03*
X529078Y59282D03*
X523220Y170362D03*
X534765Y161067D03*
X526920Y161362D03*
X529480Y183921D03*
X536127Y247652D03*
X531298Y284280D03*
X526980Y322582D03*
X521820Y336762D03*
X531720Y360862D03*
X535220Y383552D03*
X525720Y390362D03*
X528145Y408705D03*
X526941Y447802D03*
X532650Y442376D03*
Y450330D03*
Y454270D03*
X536000Y520362D03*
X524820Y545319D03*
X533167Y1329625D03*
Y1337025D03*
X528975Y1369724D03*
X535339Y1361318D03*
X533826Y1423065D03*
X524317Y1420335D03*
X542050Y47452D03*
X539720Y42862D03*
X550971Y42902D03*
X544720Y42892D03*
X548609Y48082D03*
X546100Y106162D03*
X546110Y100647D03*
X548942Y97821D03*
X544700Y112362D03*
X543083Y146338D03*
X548390Y236512D03*
X546390Y231742D03*
X539830Y274912D03*
X549220Y339687D03*
X546758Y360502D03*
X550024Y369123D03*
Y401023D03*
X551046Y878964D03*
X549757Y894025D03*
X545778Y948495D03*
X541378Y951944D03*
X541477Y976940D03*
X549177Y1010925D03*
X538209Y1027241D03*
X539914Y1049923D03*
X545371Y1041871D03*
X543914Y1049923D03*
X541167Y1329625D03*
Y1337025D03*
X549167D03*
Y1329625D03*
X542867Y1420245D03*
X565184Y47982D03*
X553650Y48842D03*
X562500Y104962D03*
X562300Y109962D03*
X562200Y114962D03*
X558900Y118962D03*
X564890Y142173D03*
X555220Y167937D03*
X561324Y301149D03*
X555520Y309827D03*
X557701Y369123D03*
X569080Y414002D03*
X559300Y422732D03*
X563700Y538477D03*
X566762Y882180D03*
X557947Y882255D03*
X558697Y891555D03*
X556697Y943475D03*
X565937Y968755D03*
X553332Y1026465D03*
X562700Y1022464D03*
X561157Y1029735D03*
X567343Y1041819D03*
X556151Y1037465D03*
X565849Y1346968D03*
X566510Y1352217D03*
X573190Y42912D03*
X575330Y47672D03*
X570208Y47982D03*
X579930Y72052D03*
X578900Y60362D03*
X573360Y140532D03*
X581175Y164717D03*
X569965Y161232D03*
X569470Y171702D03*
X579481Y194378D03*
X578450Y218562D03*
X578390Y225362D03*
X577676Y300268D03*
X570440Y331930D03*
X571830Y348772D03*
X570200Y372229D03*
X571720Y381862D03*
X577720D03*
X574491Y376549D03*
X581090Y426970D03*
X571930Y421232D03*
X571110Y442656D03*
Y446706D03*
X577220Y449462D03*
X583220Y493212D03*
X584173Y498422D03*
X577470Y505592D03*
X581147Y880067D03*
X575374Y889216D03*
X577622Y896854D03*
X583377Y901635D03*
X570657Y903335D03*
X580302Y908535D03*
X574007Y911355D03*
X570067Y921425D03*
X579229Y964343D03*
X580027Y1039100D03*
X586260Y52222D03*
X599800Y43152D03*
X597955Y48047D03*
X593369Y45682D03*
X590680Y83591D03*
X598295Y171862D03*
X599720Y184887D03*
X593220D03*
X595415Y246515D03*
X593763Y293999D03*
X588850Y291622D03*
X593120Y342782D03*
X586070Y352302D03*
X591720Y430787D03*
X595380Y416660D03*
X599220Y444362D03*
X597220Y458688D03*
X590210Y484132D03*
X589260Y519421D03*
X598503Y768931D03*
X600406Y882536D03*
X595572Y893190D03*
X600850Y902101D03*
X587617Y895115D03*
X592307Y1031185D03*
X594081Y1042722D03*
X599924Y1058989D03*
X586079Y1055076D03*
X591675Y1056610D03*
X601900Y1079662D03*
X611810Y34400D03*
X615530Y52792D03*
X614400Y46012D03*
X603063Y48023D03*
X606020Y84562D03*
X603720Y98362D03*
X608620Y94162D03*
X617409D03*
X602580Y151052D03*
X603019Y146399D03*
X606260Y161652D03*
X605350Y293092D03*
X605870Y298172D03*
X605560Y303372D03*
X607590Y314732D03*
X614130Y328762D03*
X605305Y331162D03*
X615180Y336812D03*
X605898Y372984D03*
X609690Y402812D03*
X604779Y423862D03*
X604360Y452120D03*
X609520Y515162D03*
X613220Y654662D03*
X603276Y741375D03*
X602768Y758385D03*
X608709Y769103D03*
X605555Y779324D03*
X603592Y1045812D03*
X609954Y1047613D03*
X614678Y1050637D03*
X605050Y1065867D03*
X612317Y1068895D03*
X626490Y51572D03*
X624860Y56712D03*
X625000Y43952D03*
X623300Y95762D03*
X620540Y100112D03*
X632300Y104472D03*
X627645Y236862D03*
X622730Y230362D03*
X629564Y256277D03*
X633150Y301457D03*
X627950Y298897D03*
X627600Y309134D03*
X632143Y306575D03*
X619474Y331162D03*
X622490Y402162D03*
X623220Y426362D03*
X625620Y447862D03*
Y442862D03*
X626400Y462812D03*
X625620Y457862D03*
Y452862D03*
X622860Y487310D03*
X623670Y507862D03*
X633000Y508700D03*
X628070Y760251D03*
X631231Y764219D03*
X632080Y1262074D03*
X626260Y1248762D03*
X628970Y1670880D03*
X643880Y42142D03*
X635800Y45762D03*
X647447Y46322D03*
X641200Y46762D03*
X637000Y68142D03*
X634500Y73422D03*
X645330Y77132D03*
X640220Y85542D03*
X634690D03*
X639901Y103462D03*
X640000Y108542D03*
X639970Y113892D03*
X635600Y151012D03*
X649870Y181942D03*
X645263Y235689D03*
X640295Y234237D03*
X636075Y389862D03*
X649075Y389937D03*
X638700Y400962D03*
X637220Y411362D03*
Y416362D03*
Y426362D03*
X640720Y452862D03*
X641235Y477377D03*
X640620Y483422D03*
X649218Y504277D03*
X642580Y508172D03*
X636960Y516002D03*
X648296Y528255D03*
X640785Y952415D03*
Y959265D03*
X647689Y997251D03*
X647690Y1260812D03*
X637041Y1248685D03*
X642548Y1248785D03*
X649197Y1251276D03*
X643725Y1643467D03*
X648225Y1658482D03*
X642725Y1658562D03*
X635410Y1664220D03*
X637540Y1669480D03*
X645725Y1691182D03*
X640725Y1691452D03*
X650725Y1690682D03*
X642225Y1708457D03*
X648220Y1716912D03*
X636160Y1710662D03*
X648220Y1722921D03*
X651680Y73812D03*
X656500Y69662D03*
X661587D03*
X661600Y75562D03*
X656426Y75431D03*
X652320Y123362D03*
X651730Y177212D03*
X659877Y188372D03*
X659871Y192372D03*
X660490Y200172D03*
X652000Y402362D03*
X653100Y407862D03*
X654780Y422722D03*
X654510Y431362D03*
X659970Y419602D03*
X654300Y447002D03*
X664990Y454252D03*
X655820Y452662D03*
X655800Y461432D03*
X662480Y449782D03*
X662500Y467030D03*
X664140Y475362D03*
X657740Y473132D03*
X665610Y482662D03*
X661865Y505334D03*
X656877Y514716D03*
X665990Y517131D03*
X661220Y526862D03*
X650794Y515039D03*
X664630Y1259442D03*
X664709Y1249918D03*
X661400Y1263522D03*
X651725Y1643397D03*
X677560Y40572D03*
X672250Y40812D03*
X682290Y46822D03*
X674035Y74522D03*
X677820Y89462D03*
X680578Y75992D03*
X674540Y80652D03*
X670800Y85932D03*
X667940Y80142D03*
X671320Y91192D03*
X673720Y110362D03*
X668300Y132400D03*
X673713Y237725D03*
X683100Y369550D03*
X670940Y406452D03*
X681610Y446062D03*
X675220Y508862D03*
X680220D03*
X673340Y530922D03*
X676535Y769812D03*
X670485Y952415D03*
Y959265D03*
X676309Y994386D03*
X678683Y1254408D03*
X672188Y1248885D03*
X677980Y1262074D03*
X672773Y1404136D03*
X682160Y1548040D03*
X678621Y1571072D03*
X678619Y1579070D03*
X673420Y1650057D03*
X671610Y1673792D03*
X675120Y1716242D03*
X672270Y1721612D03*
X687120Y39632D03*
X692289Y40633D03*
X696800Y42108D03*
X696838Y47940D03*
X683440Y42832D03*
X687344Y46940D03*
X692389Y46439D03*
X690027Y70142D03*
X699475Y69982D03*
X688019Y109845D03*
X687034Y115896D03*
X692083Y128157D03*
X697615Y123697D03*
X698900Y135782D03*
X687238Y171071D03*
X690520Y399622D03*
X685220Y391652D03*
X694880Y412255D03*
X693300Y418362D03*
X685220Y495887D03*
X697972Y481734D03*
X695220Y495887D03*
X690220D03*
X695220Y508862D03*
X690330Y503530D03*
X695220Y516852D03*
X699040Y952592D03*
X698920Y959252D03*
X697533Y1252541D03*
X694100Y1261562D03*
X699186Y1246192D03*
X692233Y1252480D03*
X696810Y1300162D03*
X692280Y1302532D03*
X692100Y1567190D03*
X686220Y1640667D03*
X697595Y1666862D03*
X701838Y42202D03*
Y47940D03*
X712340Y128093D03*
X707008Y125804D03*
X715600Y363900D03*
X705700Y361400D03*
X711200Y396500D03*
X713220Y388362D03*
X707330Y406232D03*
X712781Y420381D03*
X702940Y486652D03*
X701757Y521324D03*
X711220Y516852D03*
X705220Y530362D03*
X710417Y773685D03*
X701087Y988721D03*
X708090Y1262074D03*
X703790Y1249622D03*
X709748Y1252004D03*
X708126Y1403331D03*
X712222Y1570703D03*
X711102Y1575683D03*
X712582Y1584843D03*
X715775Y1599024D03*
X706103Y1617107D03*
X708857Y1613462D03*
X710570Y1629890D03*
X708830Y1623115D03*
X708999Y1646762D03*
X703719Y1646768D03*
X700460Y1660918D03*
X709678Y1658485D03*
X704759Y1677001D03*
X724620Y40062D03*
X728720Y43562D03*
X719820Y45862D03*
X729933Y108388D03*
X722500Y365500D03*
X727000D03*
X731400D03*
X725220Y380787D03*
X722500Y374100D03*
X727000D03*
X731400Y375000D03*
X728220Y388362D03*
X725280Y406242D03*
X721873Y421132D03*
X723220Y508882D03*
X717220D03*
X729220D03*
X729212Y531700D03*
X720240Y598292D03*
X729885Y952415D03*
Y959265D03*
X723975Y984675D03*
X723037Y1045285D03*
X731467Y1045015D03*
X723850Y1235892D03*
X723700Y1258727D03*
X722792Y1248688D03*
X728977Y1574453D03*
X717402Y1574433D03*
X723942Y1574123D03*
X729052Y1602518D03*
X726092Y1598483D03*
X720987Y1599568D03*
X718758Y1673800D03*
X745900Y40362D03*
X733314Y40862D03*
X740100Y41162D03*
X746100Y46262D03*
X736620Y45262D03*
X742960Y76142D03*
X733879Y83664D03*
X737929Y83714D03*
X736720Y101662D03*
X745035Y94632D03*
X735770Y94988D03*
X739823Y91052D03*
X741308Y108742D03*
X740220Y145362D03*
X732720Y231362D03*
X745685Y269322D03*
X741800Y363200D03*
X735800Y365500D03*
X732700Y351500D03*
X740200Y375100D03*
X735800Y375000D03*
X733220Y388362D03*
X733590Y406242D03*
X742450Y431472D03*
X738670Y417482D03*
X743980Y443482D03*
X742360Y436662D03*
X740510Y465258D03*
X741420Y494162D03*
X745700Y492062D03*
X747600Y506592D03*
X735220Y508862D03*
X745220Y522362D03*
X735173Y521362D03*
X740909Y754975D03*
X736425Y770072D03*
X738638Y1253541D03*
X737580Y1262074D03*
X740840Y1655590D03*
X750700Y106642D03*
X754800Y97082D03*
X757340Y92562D03*
X762590Y274028D03*
X758412Y298790D03*
X758390Y307272D03*
X749650Y398532D03*
X748380Y429052D03*
X757365Y459862D03*
X752500Y495762D03*
X757238Y483862D03*
X751220Y522362D03*
X755940Y516862D03*
X756650Y526072D03*
X761710Y517651D03*
X762570Y756052D03*
X751997Y952481D03*
Y959331D03*
X751505Y987865D03*
X751957Y1041755D03*
X759237Y1253019D03*
X753000Y1261352D03*
X759149Y1247626D03*
X753656Y1250281D03*
X748630Y1251792D03*
X751927Y1301285D03*
X757720Y1375462D03*
Y1384062D03*
X758020Y1397862D03*
X758420Y1406862D03*
X758120Y1414762D03*
X749612Y1579023D03*
X749652Y1586407D03*
X749612Y1594683D03*
X758360Y1589661D03*
X750504Y1612521D03*
X758830Y1674823D03*
X751620Y1674312D03*
X763994Y1674691D03*
X774059Y68912D03*
X764850Y249792D03*
X766320Y264892D03*
X768490Y354942D03*
X774490D03*
X773245Y398212D03*
Y403212D03*
Y408212D03*
X771050Y416940D03*
X766195Y428212D03*
X772365Y454862D03*
Y459862D03*
X765810Y506342D03*
X769745Y502600D03*
X775378Y502502D03*
X766125Y770072D03*
X767080Y1262074D03*
X767053Y1251480D03*
X776922Y1590444D03*
X766811Y1661726D03*
X766603Y1721797D03*
X790120Y135412D03*
X795520Y393462D03*
X781320Y398212D03*
X787320Y444862D03*
Y439862D03*
Y454862D03*
Y449862D03*
Y459862D03*
X787360Y469862D03*
X796315Y469290D03*
X783340Y474802D03*
X782690Y488862D03*
X785800Y482762D03*
X783600Y502462D03*
X783450Y522462D03*
X791969Y618384D03*
X794658Y770104D03*
X789385Y952415D03*
Y959265D03*
X789877Y987865D03*
X783130Y1259372D03*
X794157Y1248685D03*
X788890Y1248688D03*
X796880Y1262074D03*
X796280Y1254402D03*
X797052Y1611893D03*
X801840Y276587D03*
X802070Y284092D03*
X805775Y297007D03*
X805570Y307622D03*
X802220Y393727D03*
X800352Y408389D03*
X803120Y428762D03*
X797720Y428412D03*
X798370Y439932D03*
X802790Y433832D03*
X801750Y444330D03*
X802810Y454862D03*
Y464862D03*
Y449862D03*
Y459862D03*
X802865Y474862D03*
X810815D03*
X812510Y486422D03*
X801567Y512942D03*
X810850Y770272D03*
X812440Y1258727D03*
X801935Y1252215D03*
X811521Y1248688D03*
X806323Y1343076D03*
X812130Y1343022D03*
X812652Y1577793D03*
X801652Y1584539D03*
X814570Y145952D03*
X814531Y139851D03*
X820900Y147112D03*
X825003Y389012D03*
X819220Y412264D03*
X821720Y428437D03*
X816810Y464862D03*
X816400Y472900D03*
X821720Y511082D03*
Y527082D03*
X815650Y516807D03*
X826497Y739255D03*
X826930Y752352D03*
X825425Y770072D03*
X819085Y952415D03*
Y959265D03*
X819577Y987865D03*
X826750Y1262074D03*
X824268Y1256206D03*
X825256Y1249197D03*
X836779Y68008D03*
X839898Y87248D03*
X841584Y94181D03*
X845220Y135862D03*
Y129362D03*
X837160Y218212D03*
Y213207D03*
X844526Y204968D03*
X838820Y206872D03*
X844250Y301629D03*
X844100Y309306D03*
X838784Y392880D03*
X838220Y459562D03*
X838645Y492862D03*
X832590Y512888D03*
X829745Y498082D03*
X834327Y769285D03*
X840851Y1229802D03*
X845240Y1242372D03*
X842630Y1256912D03*
X841747Y1246745D03*
X832090Y1326862D03*
X839052Y1611893D03*
X850015Y87341D03*
X847472Y94754D03*
X860050Y215310D03*
X847580Y232222D03*
X861865Y273730D03*
X856243Y286447D03*
X859920Y308852D03*
X859740Y399081D03*
X856842Y410760D03*
X846490Y422131D03*
X857560Y417762D03*
X850610Y444352D03*
X857620Y492862D03*
X848620Y509752D03*
X853070Y515447D03*
X860345Y522162D03*
X848685Y952415D03*
Y959265D03*
X849177Y987865D03*
X851867Y1256798D03*
X875169Y185113D03*
X873200Y194262D03*
X877971Y196652D03*
X867528Y231788D03*
X867700Y268262D03*
X863747Y280870D03*
X867237Y273325D03*
X868552Y285537D03*
X868113Y409372D03*
X862320Y431462D03*
X863415Y445829D03*
X868110Y499142D03*
X866820Y736562D03*
X883909Y281862D03*
X879587Y270004D03*
X883870Y272652D03*
X887338Y296760D03*
X893440Y336232D03*
X890820Y389362D03*
X887810Y582442D03*
X885310Y736442D03*
X884619Y916477D03*
X892317Y915872D03*
X888652Y1597793D03*
Y1609793D03*
X896540Y341132D03*
X900490Y482752D03*
X899049Y501792D03*
X896652Y1605793D03*
X922726Y176302D03*
X922100Y181791D03*
X917386Y184114D03*
X923836Y193563D03*
X927034Y445594D03*
X914300Y486862D03*
X911361Y508201D03*
X920070Y966320D03*
X917980Y974952D03*
X914838Y985989D03*
X926120Y1671500D03*
X914500Y1671400D03*
X940424Y184190D03*
X936424D03*
X940410Y188852D03*
X931580Y472092D03*
X937000Y489179D03*
X935052Y812630D03*
X927790Y966450D03*
X939740Y987762D03*
X933700Y1671500D03*
X957020Y264862D03*
X947100Y374462D03*
X946300Y392562D03*
X950660Y399472D03*
X949920Y404602D03*
X945100Y534464D03*
X957220Y582862D03*
X949560Y981392D03*
X946100Y1671800D03*
X962570Y282812D03*
X962882Y314512D03*
X963854Y320113D03*
X974026Y398056D03*
X975670Y392063D03*
X971600Y408602D03*
X963720Y439862D03*
X969351Y512416D03*
X965904Y1554364D03*
X960904D03*
X962086Y1603984D03*
X990501Y152397D03*
X986369Y155358D03*
X985499Y168753D03*
X990115Y173039D03*
X987259Y276094D03*
X978000Y362462D03*
X988723Y369650D03*
X986400Y383123D03*
X983770Y373962D03*
X979766Y377507D03*
X977949Y384205D03*
X980856Y392502D03*
X983629Y397628D03*
X991369Y408252D03*
X979240Y425212D03*
X989635Y426655D03*
X980720Y512362D03*
X992306Y1295049D03*
X984270Y1554364D03*
X995180Y153689D03*
X1001101Y165510D03*
X996415Y172579D03*
X1002920Y174799D03*
X1008120Y198293D03*
X1000610Y211039D03*
X1005640Y210969D03*
X994743Y289843D03*
X993901Y376544D03*
X1006201Y370004D03*
X999440Y371782D03*
X996922Y367764D03*
X1005123Y414662D03*
X997617Y412383D03*
X997225Y419162D03*
X1005720Y498862D03*
X1005520Y510932D03*
X1008560Y589682D03*
X1007444Y766798D03*
X1001970Y1251522D03*
X1002070Y1256942D03*
X1006897Y1262435D03*
X1007636Y1554364D03*
X993698Y1604000D03*
X1011320Y202169D03*
X1017360Y199109D03*
X1019355Y218423D03*
X1010005Y208424D03*
X1010470Y224169D03*
X1022957Y249528D03*
X1024720Y259662D03*
X1017547Y255928D03*
X1014500Y266862D03*
X1021118Y294290D03*
X1015520Y302862D03*
X1009800Y343800D03*
X1009883Y367955D03*
X1010420Y416062D03*
X1019300Y405662D03*
X1024200Y510362D03*
X1020392Y521826D03*
X1016360Y594682D03*
X1019000Y601042D03*
X1021654Y606302D03*
X1023203Y989083D03*
X1023012Y1245659D03*
X1015170Y1249722D03*
X1022835Y1252034D03*
X1032547Y247928D03*
Y255928D03*
X1037618Y261200D03*
X1025862Y291727D03*
X1032260Y294532D03*
X1036278Y307393D03*
X1026250Y381582D03*
X1039340Y372642D03*
X1025004Y374662D03*
X1031153Y390152D03*
X1039370Y413842D03*
Y418842D03*
X1038294Y506504D03*
X1032155Y509737D03*
X1025530Y519627D03*
X1033040Y519852D03*
X1038130Y518417D03*
X1040720Y591862D03*
X1029630Y601252D03*
X1037144Y766798D03*
X1032063Y950820D03*
X1032527Y959265D03*
X1030830Y1261302D03*
X1030270Y1256042D03*
X1031002Y1554364D03*
X1025298Y1604000D03*
X1044978Y267275D03*
Y275275D03*
X1043720Y363462D03*
X1047010Y1259222D03*
X1057047Y1256865D03*
X1055531Y1248688D03*
X1044930Y1263492D03*
X1054368Y1554364D03*
X1056898Y1604000D03*
X1059978Y267275D03*
Y283275D03*
Y275275D03*
X1072310Y364422D03*
X1062120Y477462D03*
X1058220Y585862D03*
X1061867Y774038D03*
X1062123Y950460D03*
X1062227Y959265D03*
X1061837Y994357D03*
X1061330Y1262074D03*
X1059410Y1252272D03*
X1059086Y1579240D03*
X1085300Y282162D03*
X1077270Y374131D03*
X1076598Y477087D03*
X1081930Y477132D03*
X1076739Y506461D03*
X1077751Y522235D03*
X1084376Y774754D03*
X1084239Y952481D03*
X1084703Y960926D03*
X1079367Y984535D03*
X1084140Y1245202D03*
X1076520Y1259072D03*
X1086613Y1256826D03*
X1074010Y1510650D03*
X1077734Y1554364D03*
X1105580Y132822D03*
X1100630Y130376D03*
X1105553Y356475D03*
X1095199Y768537D03*
X1097749Y779005D03*
X1093172Y1011260D03*
X1104601Y1244631D03*
X1091000Y1262074D03*
X1106200Y1250162D03*
X1103530Y1263602D03*
X1105480Y1517982D03*
X1101600Y1554364D03*
X1104750Y1549346D03*
X1103960Y1576300D03*
Y1583300D03*
Y1590300D03*
X1092436Y1603944D03*
X1118486Y208942D03*
X1111918Y234718D03*
X1120190Y255652D03*
X1121523Y950460D03*
X1121627Y959265D03*
X1121237Y994357D03*
X1114448Y1245353D03*
X1120920Y1246282D03*
X1120800Y1262074D03*
X1106740Y1267902D03*
X1110725Y1518046D03*
X1115802Y1615010D03*
X1117182Y1625460D03*
X1114150Y1715726D03*
X1132547Y64864D03*
X1129997Y69864D03*
X1128485Y198159D03*
X1124360Y259712D03*
X1125409Y305797D03*
X1124120Y643762D03*
X1136720Y641362D03*
X1125194Y768709D03*
X1131721Y1439984D03*
X1127377Y1628485D03*
X1147700Y362731D03*
X1140465Y379592D03*
X1147700Y368041D03*
X1140912Y602207D03*
X1152241Y766798D03*
X1151223Y950460D03*
X1151327Y959265D03*
X1140727Y985255D03*
X1144577Y1244341D03*
X1139796Y1248338D03*
X1144792Y1249984D03*
X1150400Y1262074D03*
X1148563Y1257097D03*
X1152397Y1301095D03*
X1153465Y1550301D03*
X1140750Y1604330D03*
X1139392Y1620851D03*
X1159460Y194090D03*
X1159753Y361281D03*
X1156790Y373231D03*
X1157980Y588892D03*
X1158020Y593812D03*
X1158030Y598952D03*
X1158047Y609052D03*
X1158054Y603965D03*
X1159078Y763401D03*
X1158997Y1301095D03*
X1165597D03*
X1170670Y1439635D03*
X1163308Y1524187D03*
X1155433D03*
X1169213Y1550301D03*
X1161339D03*
X1169460Y1606630D03*
Y1616630D03*
Y1611630D03*
X1164830Y1628830D03*
Y1645632D03*
X1169325Y1642600D03*
X1158325D03*
X1162383Y1652505D03*
X1161613Y1669112D03*
X1187413Y143132D03*
X1181420Y157962D03*
X1181700Y186962D03*
X1173314Y176452D03*
X1181470Y208802D03*
X1181500Y222162D03*
X1172795Y222174D03*
X1186653Y302242D03*
X1174120Y355362D03*
X1180923Y950460D03*
X1181027Y959265D03*
X1180637Y994357D03*
X1179080Y1260672D03*
X1174331Y1248688D03*
X1177222Y1255567D03*
X1179180Y1265872D03*
X1172197Y1301095D03*
X1184200Y1599900D03*
X1185030Y1624660D03*
X1186830Y1645632D03*
X1175830D03*
X1180325Y1642600D03*
X1173383Y1652505D03*
X1184383D03*
X1183613Y1669112D03*
X1172613D03*
X1193532Y132644D03*
X1196930Y126690D03*
X1194800Y143112D03*
X1197414Y161592D03*
X1191020Y170862D03*
X1194840Y240672D03*
X1192877Y595012D03*
X1201977Y593252D03*
X1197280Y610352D03*
X1192890Y600292D03*
X1192887Y605652D03*
X1202495Y961858D03*
X1201627Y955185D03*
X1201403Y989083D03*
X1195097Y1251575D03*
X1193590Y1267912D03*
X1195470Y1262802D03*
X1194842Y1373682D03*
X1194442Y1380612D03*
X1203832Y1409772D03*
Y1419772D03*
X1187830Y1522188D03*
X1198546Y1524688D03*
X1187720Y1536362D03*
X1198485Y1534313D03*
X1187720Y1553692D03*
Y1544292D03*
X1198436Y1551192D03*
Y1561062D03*
X1187720Y1563182D03*
X1201600Y1633790D03*
X1197400Y1645942D03*
X1190895Y1642910D03*
X1194183Y1669422D03*
X1197240Y1691422D03*
X1190735Y1688390D03*
X1194793Y1698295D03*
X1201505Y1688435D03*
X1194023Y1714902D03*
X1215763Y114363D03*
X1206114Y132962D03*
X1206694Y139512D03*
X1213420Y144962D03*
X1214415Y153962D03*
X1214054Y186092D03*
X1208518Y174162D03*
X1213720Y195362D03*
X1215720Y204862D03*
X1219060Y213312D03*
X1206660Y224742D03*
X1213540Y224792D03*
X1207220Y247148D03*
X1210900Y265300D03*
X1205165Y380962D03*
X1218870Y418082D03*
X1214000Y599262D03*
X1208980Y598462D03*
X1212407Y773625D03*
X1209457Y787702D03*
X1204161Y1244598D03*
X1209790Y1259423D03*
X1204305Y1254514D03*
X1208750Y1266546D03*
X1210457Y1658415D03*
X1205820Y1652910D03*
X1213980Y1676500D03*
X1217210Y1684520D03*
X1218810Y1691732D03*
X1208010Y1691467D03*
X1212305Y1688700D03*
X1216363Y1698605D03*
X1205563Y1698340D03*
X1215593Y1715212D03*
X1204793Y1714947D03*
X1225100Y91500D03*
X1223500Y111162D03*
X1229500Y125100D03*
X1225574Y188662D03*
X1225320Y200162D03*
X1233780Y214572D03*
X1232000Y248332D03*
X1230720Y380362D03*
X1224300Y380400D03*
X1224439Y956561D03*
X1231327Y955185D03*
X1224031Y988295D03*
X1232107Y1057940D03*
X1228500Y1242102D03*
X1235234Y1256802D03*
X1224007Y1251715D03*
X1244200Y112862D03*
X1249362Y111600D03*
X1237664Y141202D03*
X1249430Y147620D03*
X1241100Y145842D03*
X1246272Y164889D03*
X1243100Y160181D03*
X1249720Y177662D03*
X1242470Y173612D03*
X1243184Y182422D03*
X1248868Y213414D03*
X1246853Y208229D03*
X1245593Y237462D03*
X1240500Y244332D03*
X1252040Y306480D03*
X1246079Y876083D03*
X1251727Y907485D03*
X1244237Y928847D03*
X1250230Y933374D03*
X1244383Y939465D03*
X1247301Y1022801D03*
X1247044Y1065220D03*
X1248000Y1089723D03*
X1239435Y1248688D03*
X1246654Y1660152D03*
X1267014Y112012D03*
X1266926Y118057D03*
X1254520Y115562D03*
X1253161Y128848D03*
X1256093Y149462D03*
X1265010Y162222D03*
X1261899Y174648D03*
X1263830Y195682D03*
X1252720Y193362D03*
X1267315Y220701D03*
X1252930Y205462D03*
X1259703Y209808D03*
X1253440Y230552D03*
X1253860Y235622D03*
X1253950Y246692D03*
X1266715Y244692D03*
X1254370Y241302D03*
X1265065Y249982D03*
X1258250Y292986D03*
X1263150Y294726D03*
X1267150Y305998D03*
X1256220Y434362D03*
X1261220Y454362D03*
X1253220Y451362D03*
X1267220D03*
X1255920Y511362D03*
X1261607Y853715D03*
X1265003Y860128D03*
X1254788Y873600D03*
X1262954Y873559D03*
X1258891Y881517D03*
X1264570Y891259D03*
X1256097Y914995D03*
X1267447Y912265D03*
X1252880Y924465D03*
X1260887Y935665D03*
X1254166Y942501D03*
X1253087Y978815D03*
X1260502Y1015250D03*
X1264362Y1048399D03*
X1267471Y1060464D03*
X1253916Y1051209D03*
X1253863Y1071764D03*
X1265784Y1076853D03*
X1260341Y1067280D03*
X1259335Y1074313D03*
X1265387Y1083345D03*
X1253557Y1086495D03*
X1257586Y1334649D03*
X1259433Y1660486D03*
X1275820Y87962D03*
X1269420Y96012D03*
X1271284Y108971D03*
X1278949Y123567D03*
X1282764Y135398D03*
X1269228Y147097D03*
X1277820Y140682D03*
X1281093Y144516D03*
X1277490Y165946D03*
X1271954Y159143D03*
X1271593Y165962D03*
X1276952Y174834D03*
X1278093Y184462D03*
X1278183Y201262D03*
X1272893Y191262D03*
X1271315Y220701D03*
X1284383Y215762D03*
X1284746Y207271D03*
X1277355Y216851D03*
X1273093Y213962D03*
X1280134Y235206D03*
X1277749Y230871D03*
X1277661Y225685D03*
X1278783Y221386D03*
X1282654Y226309D03*
X1276800Y276562D03*
X1269960Y294536D03*
X1272530Y429362D03*
X1284220D03*
X1280270Y434362D03*
X1272220D03*
X1278380Y463362D03*
X1276220Y477362D03*
X1283220D03*
X1277266Y868490D03*
X1278043Y862242D03*
X1271410Y866886D03*
X1270912Y877372D03*
X1270249Y885331D03*
X1271402Y904801D03*
X1278764Y1015609D03*
X1277461Y1041864D03*
X1284922Y1038464D03*
X1277419Y1062985D03*
X1283822Y1055804D03*
X1275830Y1056275D03*
X1271087Y1093050D03*
X1270528Y1100231D03*
X1275528D03*
X1272550Y1347922D03*
X1269012Y1371693D03*
X1274548Y1660486D03*
X1293454Y81232D03*
X1298640Y93062D03*
X1292880Y93162D03*
X1292899Y98519D03*
X1297884Y120072D03*
X1294751Y133852D03*
X1288093Y125962D03*
X1291478Y137745D03*
X1286150Y131092D03*
X1291311Y152073D03*
X1300481Y151020D03*
X1286513Y161483D03*
X1290734Y199122D03*
X1285899Y196392D03*
X1291194Y188899D03*
X1288904Y204002D03*
X1289739Y218499D03*
X1291983Y208562D03*
X1285393Y222262D03*
X1292554Y230101D03*
X1301235Y228210D03*
X1285710Y249182D03*
X1290293Y247562D03*
X1288637Y240448D03*
X1292630Y240462D03*
X1298032Y267219D03*
X1295540Y440902D03*
X1301310Y440862D03*
X1291220Y463362D03*
X1294440Y477267D03*
X1300220Y477362D03*
X1299327Y765475D03*
X1297298Y790982D03*
X1285316Y865291D03*
X1295535Y871113D03*
X1298830Y864461D03*
X1292792Y928724D03*
X1288257Y921605D03*
X1296637Y970755D03*
X1300851Y1043664D03*
X1296478Y1064139D03*
X1298540Y1056104D03*
X1291775Y1055990D03*
X1288529Y1069460D03*
X1288000Y1362151D03*
X1296930Y1660520D03*
X1311260Y83032D03*
X1314406Y97756D03*
X1308274Y104162D03*
X1310000Y113552D03*
X1302080Y117032D03*
X1302509Y134795D03*
X1308825Y136721D03*
X1315353Y146030D03*
X1310880Y143431D03*
X1315020Y139762D03*
X1305115Y142712D03*
X1309049Y182865D03*
X1309918Y201187D03*
X1314970Y219772D03*
X1306190Y210502D03*
X1309189Y206274D03*
X1316842Y238692D03*
X1317300Y250162D03*
X1316754Y268442D03*
X1317100Y553900D03*
X1303576Y659671D03*
X1305187Y735630D03*
X1304707Y769984D03*
X1307627Y764735D03*
X1314227Y770855D03*
X1301927Y759935D03*
X1305117Y797125D03*
X1311407Y868055D03*
X1307717Y888265D03*
X1311798Y1054354D03*
X1305878Y1062943D03*
X1317150Y1062622D03*
X1316092Y1053513D03*
X1307032Y1058856D03*
X1311780Y1058894D03*
X1311952Y1321945D03*
X1304066Y1323578D03*
X1309194Y1655255D03*
X1313583Y1660466D03*
X1322248Y68487D03*
X1322415Y75480D03*
X1322906Y94212D03*
X1319968Y98266D03*
X1322906Y109733D03*
X1321747Y136899D03*
X1326826Y138922D03*
X1332002Y142289D03*
X1326974Y144338D03*
X1320880Y143430D03*
X1332654Y154452D03*
X1332268Y159982D03*
X1329620Y227682D03*
X1323912Y245111D03*
X1323694Y266442D03*
X1320387Y258901D03*
X1325769Y259001D03*
X1328745Y732336D03*
X1323345Y769844D03*
X1332947Y767085D03*
X1320032Y775725D03*
X1320786Y1339353D03*
X1318151Y1655269D03*
X1333709Y1655241D03*
X1329331Y1660390D03*
X1341718Y130781D03*
X1348079Y129474D03*
X1336819Y150298D03*
X1339481Y154705D03*
X1343034Y141698D03*
X1337547Y170397D03*
X1337637Y162994D03*
X1337697Y728652D03*
X1338495Y774984D03*
X1345079Y1660508D03*
X1366369Y83820D03*
X1364844Y133782D03*
X1363266Y155703D03*
X1357514Y150092D03*
X1351165Y150861D03*
X1353894Y144872D03*
X1362564Y161142D03*
X1363170Y200872D03*
X1355250Y211002D03*
X1356220Y581862D03*
X1361727Y680665D03*
X1351554Y1325594D03*
X1364860Y1455172D03*
X1375619Y236261D03*
X1374054Y223752D03*
X1378684Y229122D03*
X1381094Y224412D03*
X1370207Y682245D03*
X1369297Y807025D03*
X1375897Y813625D03*
X1382497Y807025D03*
X1370577Y1421899D03*
X1382157Y1408975D03*
X1377075Y1425014D03*
X1386684Y145017D03*
X1386404Y149008D03*
X1394182Y171470D03*
X1398182D03*
X1389097Y813625D03*
X1384638Y1325516D03*
X1396311Y1385712D03*
X1398680Y1380582D03*
X1387074Y1384272D03*
X1390513Y1395452D03*
X1387066Y1401734D03*
X1387291Y1408163D03*
X1392400Y1419825D03*
X1390170Y1423942D03*
X1388557Y1431645D03*
X1395443Y1434700D03*
X1383429Y1427652D03*
X1389220Y1446708D03*
X1391655Y1570037D03*
X1391055Y1565037D03*
X1393000Y1590300D03*
X1401971Y924341D03*
X1401655Y1384676D03*
X1415171Y1383692D03*
X1412608Y1391687D03*
X1414362Y1402191D03*
X1414786Y1426890D03*
X1413440Y1436774D03*
X1409680Y1430613D03*
X1401371Y1434592D03*
X1403350Y1516435D03*
X1400695Y1570037D03*
X1400715Y1565037D03*
X1401300Y1619917D03*
X1400000Y1626362D03*
X1410500Y1638862D03*
X1431430Y251265D03*
X1430097Y726635D03*
X1419697Y792165D03*
X1429697D03*
X1418030Y1325927D03*
X1418990Y1387452D03*
X1415620Y1396652D03*
X1419055Y1392497D03*
X1418870Y1406742D03*
X1423256Y1403728D03*
X1424255Y1396612D03*
X1421371Y1411719D03*
X1421864Y1419730D03*
X1426020Y1521535D03*
X1427120Y1537355D03*
X1427320Y1548575D03*
X1416800Y1564862D03*
X1425620Y1556662D03*
X1428403Y1581378D03*
X1416060Y1574922D03*
X1436335Y309407D03*
X1436050Y321352D03*
X1432487Y712485D03*
X1440150Y730182D03*
X1438457Y737565D03*
X1439697Y792165D03*
X1441357Y845635D03*
X1444874Y925533D03*
X1436470Y925622D03*
X1432125Y924530D03*
X1446807Y1293335D03*
Y1301335D03*
X1444997Y1392885D03*
X1435462Y1396409D03*
X1443112Y1417929D03*
X1445020Y1412672D03*
X1443676Y1432624D03*
X1439742Y1436924D03*
X1434720Y1454862D03*
X1440440Y1454892D03*
X1436330Y1521152D03*
X1436570Y1536972D03*
X1436720Y1548192D03*
X1437140Y1576012D03*
X1446700Y1598400D03*
X1438320Y1668292D03*
X1438220Y1673955D03*
X1446715Y1679957D03*
X1462561Y205982D03*
X1459900Y370823D03*
X1463600Y374462D03*
X1449777Y371039D03*
X1449697Y792165D03*
X1459697D03*
X1454557Y845635D03*
X1450997Y925673D03*
X1448586Y1325395D03*
X1461062Y1413246D03*
X1448620Y1556162D03*
X1448920Y1675062D03*
X1464200Y67802D03*
X1473090Y204502D03*
X1476858Y225448D03*
X1466958Y244948D03*
X1474660Y252878D03*
X1473820Y265962D03*
X1466660Y273878D03*
X1468400Y283709D03*
X1472261Y300182D03*
X1470073Y316202D03*
X1470841Y721493D03*
X1474000Y739362D03*
X1480250Y757753D03*
X1473717Y744674D03*
X1467587Y770665D03*
X1479870Y763842D03*
X1480320Y1338759D03*
X1466448Y1421499D03*
X1470487Y1462965D03*
X1478320Y1522962D03*
X1478061Y1633864D03*
X1493120Y240412D03*
X1490029Y309277D03*
X1494784Y374188D03*
X1486040Y368392D03*
X1493384Y411313D03*
X1482650Y411190D03*
X1495527Y406215D03*
X1489310Y426822D03*
X1494968Y732603D03*
X1489387Y757925D03*
X1491828Y766875D03*
X1486997Y1392015D03*
Y1402015D03*
X1493967Y1418445D03*
X1481918Y1425579D03*
X1482830Y1525162D03*
X1493700Y1665900D03*
X1512420Y239116D03*
X1498984Y282797D03*
X1497817Y292997D03*
Y300997D03*
Y308997D03*
X1505922Y304583D03*
X1505297Y671325D03*
X1508067Y664655D03*
X1496813Y757699D03*
X1510557Y747202D03*
X1502745Y759915D03*
X1512483Y1043233D03*
X1512587Y1323205D03*
Y1333205D03*
X1511357Y1361195D03*
X1510027Y1425825D03*
X1522920Y113030D03*
X1518575Y138662D03*
X1526675Y140117D03*
X1526083Y146225D03*
X1514520Y231116D03*
X1525977Y293444D03*
Y301444D03*
X1517669Y291516D03*
X1518017Y757455D03*
X1526000Y745162D03*
X1523197Y759045D03*
X1518967Y891005D03*
X1520528Y917924D03*
X1527257Y917665D03*
X1522907Y986792D03*
X1523614Y1011464D03*
X1515770Y1028159D03*
X1521528Y1031364D03*
X1526427Y1019785D03*
X1522746Y1048368D03*
X1526746D03*
X1520737Y1061993D03*
X1525787Y1323205D03*
Y1333205D03*
X1516137Y1432135D03*
X1544010Y27552D03*
X1535320Y113062D03*
X1529500Y122122D03*
X1529233Y153162D03*
X1535450Y155262D03*
X1542401Y141561D03*
X1545447Y156035D03*
X1537262Y197834D03*
X1533247Y284324D03*
X1533977Y293444D03*
Y301444D03*
X1540989Y616587D03*
X1541211Y646178D03*
X1530185Y757790D03*
X1531403Y765791D03*
X1540426Y855555D03*
X1540800Y889012D03*
X1531827Y913665D03*
X1535622Y905170D03*
X1544993Y936489D03*
X1543042Y951465D03*
X1535580Y948056D03*
X1536837Y965965D03*
X1530847Y978075D03*
X1532107Y971957D03*
X1538393Y1016271D03*
X1545047Y1030225D03*
X1540227Y1027095D03*
X1543727Y1021175D03*
X1535797Y1037875D03*
X1530467Y1045234D03*
X1536273Y1046561D03*
X1544337Y1042125D03*
X1543667Y1049835D03*
X1532288Y1052545D03*
X1531011Y1660548D03*
X1554239Y138263D03*
X1552960Y124359D03*
X1559387Y589340D03*
X1550487Y681565D03*
X1550320Y696562D03*
X1550917Y704332D03*
X1550390Y709885D03*
X1555937Y1042715D03*
X1563714Y572792D03*
X1564690Y663302D03*
X1562871Y735716D03*
X1567737Y1036815D03*
X1576740Y1080262D03*
X1579632Y787410D03*
X1579816Y793954D03*
X1588459Y1068895D03*
X1603530Y202402D03*
X1604240Y227892D03*
X1608307Y772125D03*
X1609239Y959331D03*
X1602650Y1242752D03*
X1608000Y1261662D03*
X1609403Y1247684D03*
X1623881Y117627D03*
X1623107Y769805D03*
X1616927Y952415D03*
X1623744Y996980D03*
X1620727Y1256225D03*
X1624600Y1262074D03*
X1619454Y1249290D03*
X1624040Y1247202D03*
X1623930Y1252242D03*
X1614116Y1411169D03*
X1636393Y181778D03*
X1633111Y206693D03*
X1642135Y414202D03*
X1638713Y722692D03*
X1639689Y1259345D03*
X1639467Y1250175D03*
X1630643Y1440290D03*
X1636200Y1436862D03*
X1647110Y434177D03*
X1654110D03*
X1658275Y527195D03*
X1649291Y556057D03*
X1645530Y549160D03*
X1645300Y612202D03*
X1653319Y642311D03*
X1648722Y645613D03*
Y679613D03*
X1649455Y711844D03*
X1652807Y769805D03*
X1646627Y952415D03*
Y959265D03*
X1651404Y992838D03*
X1648368Y1245574D03*
X1644714Y1249914D03*
X1649573Y1252942D03*
X1654600Y1262742D03*
X1668100Y180852D03*
X1666690Y193290D03*
X1674432Y216981D03*
X1668426Y222432D03*
X1660861Y227548D03*
X1661110Y434177D03*
X1667376Y515531D03*
X1665790Y523417D03*
X1666840Y544332D03*
X1662467Y530301D03*
X1668917Y549992D03*
X1663502Y555115D03*
X1660660Y602273D03*
X1669489Y1259545D03*
X1661300Y1252085D03*
X1669731Y1248688D03*
X1664867Y1303505D03*
X1671870Y1438296D03*
X1665940Y1512862D03*
X1666123Y1524862D03*
Y1537862D03*
Y1553557D03*
X1666198Y1565557D03*
X1671660Y1569412D03*
X1666198Y1585321D03*
X1690208Y421855D03*
X1689121Y488288D03*
X1681817Y495290D03*
X1686564Y497580D03*
X1675664Y513802D03*
X1690999Y513107D03*
X1683702Y514687D03*
X1676600Y523902D03*
X1687166Y529824D03*
X1684810Y523602D03*
X1688768Y518107D03*
X1685766Y535011D03*
X1685358Y539743D03*
X1679941Y552222D03*
X1678860Y556752D03*
X1683369Y562698D03*
X1683087Y712055D03*
X1686041Y763095D03*
X1676427Y952415D03*
Y959265D03*
X1675642Y989103D03*
X1682942Y1258909D03*
X1679522Y1249489D03*
X1683578Y1253780D03*
X1683500Y1264312D03*
X1678067Y1303505D03*
X1680720Y1487062D03*
X1678340Y1500862D03*
X1677930Y1520362D03*
X1678340Y1541362D03*
X1678230Y1590542D03*
X1703026Y188993D03*
X1699740Y207090D03*
X1693987Y230174D03*
X1703487Y232174D03*
X1698220Y369652D03*
X1702959Y404243D03*
X1707780Y410738D03*
X1697161Y406602D03*
X1692429Y403985D03*
X1701124Y423802D03*
X1694050Y416643D03*
X1695455Y422287D03*
X1707544Y431745D03*
X1707568Y420370D03*
X1697648Y463724D03*
X1693720Y455862D03*
X1702127Y468719D03*
X1697210Y500802D03*
X1694158Y504875D03*
X1707200Y498962D03*
X1699553Y513107D03*
X1707552Y506731D03*
X1707716Y513562D03*
X1702930Y526102D03*
X1701726Y518107D03*
X1699107Y555783D03*
X1703306Y550064D03*
X1692883Y703943D03*
X1701320Y705678D03*
X1693087Y712055D03*
X1696402Y709533D03*
X1706027Y952415D03*
Y959265D03*
X1705242Y989103D03*
X1696061Y1014019D03*
X1705076Y1242032D03*
X1699089Y1258842D03*
X1699431Y1248688D03*
X1699030Y1263912D03*
X1702817Y1374325D03*
X1702417Y1364595D03*
X1691988Y1517803D03*
Y1538803D03*
Y1558262D03*
X1705723Y1583821D03*
X1715210Y18282D03*
X1709589Y26062D03*
X1720895Y68062D03*
X1709000Y87362D03*
X1712720Y111862D03*
X1714180Y154790D03*
X1711599Y197329D03*
X1721220Y458362D03*
X1713977Y457137D03*
X1708977Y458542D03*
X1713158Y478243D03*
X1718786Y467517D03*
X1713977Y470804D03*
X1708977D03*
X1711720Y497964D03*
X1709356Y541144D03*
X1716480Y691410D03*
X1714897Y706095D03*
X1709828Y719283D03*
X1712207Y769805D03*
X1719277Y1013205D03*
X1710363Y1249132D03*
X1713930Y1262074D03*
X1718149Y1496270D03*
X1717149Y1505895D03*
X1717988Y1520951D03*
X1711988D03*
X1717149Y1513945D03*
X1717988Y1530445D03*
X1711988D03*
X1729080Y118132D03*
X1739720Y120892D03*
X1728999Y112895D03*
X1733920Y151362D03*
X1728320Y169862D03*
X1737470Y177147D03*
X1725344Y359334D03*
X1729810Y390620D03*
X1737660D03*
X1734290Y423820D03*
X1739316Y480939D03*
X1728139Y952481D03*
Y959331D03*
X1728924Y987935D03*
X1728477Y1242955D03*
X1728689Y1258845D03*
X1739237Y1256935D03*
X1736715Y1249405D03*
X1727674Y1513945D03*
X1729310Y1520951D03*
X1735310D03*
X1729310Y1530445D03*
X1735310D03*
X1726988Y1554631D03*
Y1547131D03*
X1748720Y97362D03*
X1745010Y122952D03*
X1750820Y119972D03*
X1747591Y171733D03*
X1751068Y262123D03*
X1754245Y269724D03*
X1746484Y279682D03*
X1756204Y301695D03*
X1756933Y372452D03*
X1744380Y382892D03*
X1744510Y377452D03*
X1747080Y435870D03*
X1746720Y464862D03*
X1740886Y493960D03*
X1743440Y721802D03*
X1745541Y763095D03*
X1743710Y1262074D03*
X1742337Y1252300D03*
X1747677Y1507388D03*
X1747304Y1524976D03*
X1741988Y1554631D03*
Y1547131D03*
X1768026Y24165D03*
X1769669Y15244D03*
X1761998Y15187D03*
X1765260Y18262D03*
X1757320Y15872D03*
X1767185Y48817D03*
X1771774Y53682D03*
X1767170Y83607D03*
X1767990Y76797D03*
X1760478Y90027D03*
X1768483Y166260D03*
X1765820Y182282D03*
X1767300Y174587D03*
X1760104Y301648D03*
X1770520Y364148D03*
X1765670Y458012D03*
X1767300Y465893D03*
X1768317Y686375D03*
X1770017Y701175D03*
Y721175D03*
Y711175D03*
X1757839Y952481D03*
Y959331D03*
X1764742Y989103D03*
X1758189Y1258875D03*
X1769037Y1256835D03*
X1759070Y1249412D03*
X1770299Y1249182D03*
X1764163Y1246974D03*
X1758352Y1317368D03*
Y1322168D03*
X1771988Y1554631D03*
Y1547131D03*
X1756988Y1554631D03*
Y1547131D03*
X1775556Y21471D03*
X1775830Y26522D03*
X1779411Y50692D03*
X1774328Y62987D03*
X1775580Y73330D03*
X1787790Y85132D03*
X1781485Y88192D03*
X1785142Y76032D03*
X1773611Y88293D03*
X1780320Y153162D03*
X1774950Y167392D03*
X1779500Y171692D03*
X1782600Y175932D03*
X1777354Y295489D03*
X1782420Y443987D03*
X1773870Y438222D03*
X1781720Y592742D03*
X1773559Y763642D03*
X1787539Y952481D03*
Y959331D03*
X1788219Y1259312D03*
X1773390Y1262074D03*
X1788531Y1248688D03*
X1773480Y1253692D03*
X1788360Y1264522D03*
X1784680Y1553922D03*
X1786988Y1547131D03*
X1797324Y161465D03*
X1799250Y297932D03*
X1803129Y362293D03*
X1802929Y385293D03*
X1792450Y410615D03*
X1792507Y403932D03*
X1792220Y425432D03*
X1792335Y418775D03*
X1804841Y763095D03*
X1794442Y989103D03*
X1802670Y1239522D03*
X1803100Y1262074D03*
X1803357Y1251204D03*
X1795484Y1496401D03*
X1800450Y1505230D03*
X1792645Y1511423D03*
X1795561Y1524729D03*
X1806920Y150862D03*
X1808910Y143902D03*
X1813335Y155435D03*
X1810835Y163986D03*
X1819939Y177243D03*
X1813325Y177257D03*
X1813740Y281712D03*
X1820307Y373829D03*
X1820144Y398052D03*
X1819374Y410432D03*
X1818874Y423932D03*
X1810792Y417432D03*
X1818816Y468872D03*
X1818290Y1232452D03*
X1815474Y1246472D03*
X1814537Y1322105D03*
X1807150Y1505675D03*
X1818004Y1510021D03*
X1818410Y1525815D03*
X1828204Y328654D03*
X1829189Y363731D03*
X1824827Y952415D03*
Y959265D03*
X1824042Y989103D03*
X1829920Y1258322D03*
X1829940Y1263662D03*
X1828510Y1525915D03*
X1841257Y151402D03*
X1838910Y185772D03*
X1844157Y182210D03*
G54D105*
X1297819Y250945D03*
X1297799Y258931D03*
X1293697Y254829D03*
X1293949Y262857D03*
X1289847Y258755D03*
X1301921Y255047D03*
G54D124*
G01X419611Y1079791D02*
X420227Y1078724D01*
X420144Y1078417D01*
G02X418874Y1078514I-534J1374D01*
G01X418816Y1078548D01*
G03X416648Y1078514I-1054J-1961D01*
G02X415174I-737J1277D01*
G01X415116Y1078548D01*
G03X412948Y1078514I-1054J-1961D01*
G02X411474I-737J1277D01*
G01X411416Y1078548D01*
G03X409248Y1078514I-1054J-1961D01*
G02X407774I-737J1277D01*
G01X407739Y1078534D01*
G02X407036Y1079791I772J1257D01*
G01Y1079852D01*
G03X405925Y1081718I-2225J-61D01*
G03X403757Y1081752I-1114J-1927D01*
G01X403699Y1081718D01*
G02X402225I-737J1277D01*
G03X400057Y1081752I-1114J-1927D01*
G01X399999Y1081718D01*
G02X398525I-737J1277D01*
G03X396357Y1081752I-1114J-1927D01*
G01X396299Y1081718D01*
G02X394825I-737J1277D01*
G03X392657Y1081752I-1114J-1927D01*
G01X392599Y1081718D01*
G02X391125I-737J1277D01*
G03X388939Y1081742I-1114J-1927D01*
G01X388898Y1081718D01*
G02X387424I-737J1277D01*
G03X385240Y1081742I-1113J-1927D01*
G01X385199Y1081718D01*
G02X383725I-737J1277D01*
G03X381557Y1081752I-1114J-1927D01*
G01X381499Y1081718D01*
G02X380025I-737J1277D01*
G03X377857Y1081752I-1114J-1927D01*
G01X377799Y1081718D01*
G02X376325I-737J1277D01*
G03X374157Y1081752I-1114J-1927D01*
G01X374099Y1081718D01*
G02X372625I-737J1277D01*
G03X370457Y1081752I-1114J-1927D01*
G01X370399Y1081718D01*
G02X368925I-737J1277D01*
G03X366757Y1081752I-1114J-1927D01*
G01X366699Y1081718D01*
G02X365225I-737J1277D01*
G03X363039Y1081742I-1114J-1927D01*
G01X362998Y1081718D01*
G02X361524I-737J1277D01*
G01X361483Y1081742D01*
G03X359299Y1081718I-1071J-1951D01*
G02X357825I-737J1277D01*
G03X355639Y1081742I-1114J-1927D01*
G01X355598Y1081718D01*
G02X354124I-737J1277D01*
G03X351898I-1113J-1927D01*
G02X350424I-737J1277D01*
G03X348198I-1113J-1927D01*
G02X346724I-737J1277D01*
G03X344498I-1113J-1927D01*
G01X344497D01*
G02X343023I-737J1277D01*
G01X342965Y1081752D01*
G03X340797Y1081718I-1054J-1961D01*
G02X339323I-737J1277D01*
G03X337155Y1081752I-1114J-1927D01*
G01X337097Y1081718D01*
X337064Y1081699D01*
G02X335622Y1081718I-704J1296D01*
G01X332207Y1083692D01*
G01X402962Y1031727D02*
X400805Y1030728D01*
G03X399999Y1030450I309J-2205D01*
G02X398525I-737J1277D01*
G03X396299I-1113J-1927D01*
G02X394825I-737J1277D01*
G01X394767Y1030484D01*
G03X392599Y1030450I-1054J-1961D01*
G02X391125I-737J1277D01*
G01X391067Y1030484D01*
G03X388899Y1030450I-1054J-1961D01*
G02X387425I-737J1277D01*
G01X387384Y1030474D01*
G03X385200Y1030450I-1071J-1951D01*
G02X383726I-737J1277D01*
G01X383685Y1030474D01*
G03X381499Y1030450I-1072J-1951D01*
G02X380025I-737J1277D01*
G01X379967Y1030484D01*
G03X377799Y1030450I-1054J-1961D01*
G02X376325I-737J1277D01*
G01X376267Y1030484D01*
G03X374099Y1030450I-1054J-1961D01*
G02X372625I-737J1277D01*
G03X370399I-1113J-1927D01*
G02X368925I-737J1277D01*
G01X368867Y1030484D01*
G03X366699Y1030450I-1054J-1961D01*
G02X365225I-737J1277D01*
G01X365167Y1030484D01*
G03X362999Y1030450I-1054J-1961D01*
G02X361525I-737J1277D01*
G01X361484Y1030474D01*
G03X359300Y1030450I-1071J-1951D01*
G02X357826I-737J1277D01*
G03X355599I-1114J-1929D01*
G01X355249Y1030248D01*
G02X354475I-387J670D01*
G01X354126Y1030449D01*
G03X352007Y1030448I-1059J-1837D01*
G01X351906Y1030390D01*
G02X350432I-737J1277D01*
G03X348206I-1113J-1927D01*
G01X348191Y1030382D01*
G02X347439Y1030177I-765J1324D01*
G01X344526Y1030155D01*
X340736D01*
G01X430711Y1054157D02*
X429579Y1055289D01*
X428249D01*
X426934Y1056604D01*
Y1058706D01*
G03X426298Y1059274I-1772J-1344D01*
G01X426274Y1059288D01*
X426239Y1059308D01*
G02X425536Y1060565I772J1257D01*
G01Y1060652D01*
G03X424425Y1062493I-2225J-87D01*
G01X424390Y1062513D01*
G02X423687Y1063770I772J1257D01*
G03X422598Y1065683I-2225J0D01*
G01X422574Y1065697D01*
X422539Y1065717D01*
G02X421836Y1066974I772J1257D01*
G01Y1067035D01*
G03X420725Y1068901I-2225J-61D01*
G01X420690Y1068921D01*
G02X419987Y1070178I772J1257D01*
G01Y1070234D01*
G03X418874Y1072106I-2225J-56D01*
G01X418839Y1072126D01*
G02X418136Y1073383I772J1257D01*
G01Y1073444D01*
G03X417025Y1075310I-2225J-61D01*
G03X414857Y1075344I-1114J-1927D01*
G01X414799Y1075310D01*
G02X413325I-737J1277D01*
G03X411157Y1075344I-1114J-1927D01*
G01X411099Y1075310D01*
G02X409625I-737J1277D01*
G03X407439Y1075334I-1114J-1927D01*
G01X407398Y1075310D01*
G02X405924I-737J1277D01*
G02X405187Y1076553I737J1277D01*
G01Y1076587D01*
G03X404098Y1078500I-2225J0D01*
G01X404074Y1078514D01*
X404016Y1078548D01*
G03X401848Y1078514I-1054J-1961D01*
G02X400374I-737J1277D01*
G03X398148I-1113J-1927D01*
G02X396674I-737J1277D01*
G01X396616Y1078548D01*
G03X394448Y1078514I-1054J-1961D01*
G02X392974I-737J1277D01*
G01X392916Y1078548D01*
G03X390748Y1078514I-1054J-1961D01*
G02X389274I-737J1277D01*
G01X389216Y1078548D01*
G03X387048Y1078514I-1054J-1961D01*
G02X385574I-737J1277D01*
G01X385516Y1078548D01*
G03X383348Y1078514I-1054J-1961D01*
G02X381874I-737J1277D01*
G01X381816Y1078548D01*
G03X379648Y1078514I-1054J-1961D01*
G02X378174I-737J1277D01*
G01X378116Y1078548D01*
G03X375948Y1078514I-1054J-1961D01*
G02X374474I-737J1277D01*
G03X372248I-1113J-1927D01*
G02X370774I-737J1277D01*
G01X370716Y1078548D01*
G03X368548Y1078514I-1054J-1961D01*
G02X367074I-737J1277D01*
G01X367016Y1078548D01*
G03X364848Y1078514I-1054J-1961D01*
G02X363374I-737J1277D01*
G01X363333Y1078538D01*
G03X361149Y1078514I-1071J-1951D01*
G02X359675I-737J1277D01*
G01X359634Y1078538D01*
G03X357448Y1078514I-1072J-1951D01*
G02X355974I-737J1277D01*
G03X353748I-1113J-1927D01*
G02X352274I-737J1277D01*
G03X350048I-1113J-1927D01*
G02X348574I-737J1277D01*
G03X346348I-1113J-1927D01*
G02X344874I-737J1277D01*
G03X342648I-1113J-1927D01*
G02X341174I-737J1277D01*
G03X340062Y1078812I-1112J-1926D01*
G01X339985D01*
X339370Y1079427D01*
X338133D01*
X338119Y1079413D01*
X331214D01*
G01X328943Y943548D02*
X329030D01*
X329171Y943407D01*
X337578D01*
X344134Y936851D01*
G03X344442Y936619I1034J1053D01*
G03X345916I737J1277D01*
G02X348100Y936643I1113J-1928D01*
G01X348141Y936619D01*
G03X349615I737J1277D01*
G02X351783Y936653I1115J-1928D01*
G01X351841Y936619D01*
G03X353315I737J1277D01*
G02X355483Y936653I1115J-1928D01*
G01X355541Y936619D01*
G03X357015I737J1277D01*
G02X359201Y936643I1114J-1928D01*
G01X359242Y936619D01*
G03X360716I737J1277D01*
G01X360757Y936643D01*
G02X362941Y936619I1071J-1952D01*
G03X364415I737J1277D01*
G02X366583Y936653I1115J-1928D01*
G01X366641Y936619D01*
G03X368115I737J1277D01*
G02X370283Y936653I1115J-1928D01*
G01X370341Y936619D01*
G03X371815I737J1277D01*
G02X373983Y936653I1115J-1928D01*
G01X374041Y936619D01*
G03X375515I737J1277D01*
G02X377683Y936653I1115J-1928D01*
G01X377741Y936619D01*
G03X379215I737J1277D01*
G02X381383Y936653I1115J-1928D01*
G01X381441Y936619D01*
G03X382915I737J1277D01*
G02X385101Y936643I1114J-1928D01*
G01X385142Y936619D01*
G03X386616I737J1277D01*
G01X386657Y936643D01*
G02X388841Y936619I1071J-1952D01*
G03X390315I737J1277D01*
G02X392483Y936653I1115J-1928D01*
G01X392541Y936619D01*
G03X394015I737J1277D01*
G02X396183Y936653I1115J-1928D01*
G01X396241Y936619D01*
G02X397354Y934747I-1112J-1928D01*
G01Y934691D01*
G03Y934666I1473J-12D01*
G01X397353Y934665D01*
X397358Y934410D01*
G03X397818Y933587I999J18D01*
G01X398036Y933447D01*
X398089Y933417D01*
X398092Y933415D01*
X398135Y933390D01*
G03X399566Y933414I694J1301D01*
G01X399572Y933417D01*
X399757Y933526D01*
G03X400256Y934265I-535J899D01*
G01X400287Y934464D01*
X400060Y934691D01*
X398829D01*
G01X328943Y942528D02*
X328953Y942518D01*
X329030D01*
X329170Y942658D01*
X337265D01*
X337266Y942659D01*
X343607Y936318D01*
G03X344100Y935948I1570J1579D01*
G03X346292Y935968I1078J1948D01*
G02X347766I737J-1277D01*
G01X347824Y935934D01*
G03X349992Y935968I1053J1962D01*
G02X351466I737J-1277D01*
G01X351524Y935934D01*
G03X353692Y935968I1053J1962D01*
G02X355166I737J-1277D01*
G01X355224Y935934D01*
G03X357392Y935968I1053J1962D01*
G02X358866I737J-1277D01*
G03X361050Y935944I1113J1928D01*
G01X361091Y935968D01*
G02X362565I737J-1277D01*
G01X362606Y935944D01*
G03X364792Y935968I1072J1952D01*
G02X366266I737J-1277D01*
G01X366324Y935934D01*
G03X368492Y935968I1053J1962D01*
G02X369966I737J-1277D01*
G01X370024Y935934D01*
G03X372192Y935968I1053J1962D01*
G02X373666I737J-1277D01*
G01X373724Y935934D01*
G03X375892Y935968I1053J1962D01*
G02X377366I737J-1277D01*
G01X377424Y935934D01*
G03X379592Y935968I1053J1962D01*
G02X381066I737J-1277D01*
G01X381124Y935934D01*
G03X383292Y935968I1053J1962D01*
G02X384766I737J-1277D01*
G03X386950Y935944I1113J1928D01*
G01X386991Y935968D01*
G02X388465I737J-1277D01*
G01X388497Y935949D01*
X388506Y935944D01*
G03X390692Y935968I1072J1952D01*
G02X392166I737J-1277D01*
G01X392224Y935934D01*
G03X394392Y935968I1053J1962D01*
G02X396604Y934691I737J-1277D01*
G01Y934651D01*
X396609Y934396D01*
G03X397413Y932956I1748J31D01*
G01X397716Y932764D01*
G03X399900Y932740I1113J1927D01*
G01X399953Y932771D01*
X400139Y932881D01*
G03X400997Y934150I-917J1544D01*
G01X401028Y934350D01*
G03X401039Y934432I-2199J337D01*
G01X401298Y934691D01*
X402529D01*
G01X328893Y938354D02*
X328980D01*
X329121Y938213D01*
X339854D01*
X341852Y936215D01*
Y934745D01*
X341854Y934658D01*
G03X342591Y933415I1474J34D01*
G01X342602Y933408D01*
X342606Y933406D01*
X342615Y933401D01*
G02X343704Y931488I-1136J-1913D01*
G03X344407Y930231I1475J0D01*
G01X344442Y930211D01*
G03X345916I737J1277D01*
G02X348142I1113J-1928D01*
G03X349616I737J1277D01*
G02X351800Y930235I1113J-1928D01*
G01X351841Y930211D01*
G03X353315I737J1277D01*
G02X355483Y930245I1115J-1928D01*
G01X355541Y930211D01*
G03X357015I737J1277D01*
G02X359241I1113J-1928D01*
G03X360715I737J1277D01*
G02X362883Y930245I1115J-1928D01*
G01X362941Y930211D01*
G03X364415I737J1277D01*
G02X366583Y930245I1115J-1928D01*
G01X366641Y930211D01*
G03X368115I737J1277D01*
G02X370301Y930235I1114J-1928D01*
G01X370342Y930211D01*
G03X371816I737J1277D01*
G02X374000Y930235I1113J-1928D01*
G01X374041Y930211D01*
G03X375515I737J1277D01*
G02X377683Y930245I1115J-1928D01*
G01X377741Y930211D01*
G03X379215I737J1277D01*
G02X381383Y930245I1115J-1928D01*
G01X381441Y930211D01*
G03X382915I737J1277D01*
G02X385141I1113J-1928D01*
G03X386615I737J1277D01*
G02X388783Y930245I1115J-1928D01*
G01X388841Y930211D01*
G03X390315I737J1277D01*
G02X392483Y930245I1115J-1928D01*
G01X392541Y930211D01*
G03X394015I737J1277D01*
G02X396201Y930235I1114J-1928D01*
G01X396242Y930211D01*
G03X397716I737J1277D01*
G02X399873Y930249I1113J-1928D01*
G01X399941Y930210D01*
G03X401211Y930113I736J1277D01*
G01X401294Y930420D01*
X400678Y931488D01*
G01X328893Y937334D02*
X328903Y937324D01*
X328980D01*
X329120Y937464D01*
X339543D01*
X341103Y935904D01*
Y934692D01*
G03X342192Y932779I2225J0D01*
G01X342216Y932765D01*
X342222Y932762D01*
X342251Y932745D01*
G02X342954Y931488I-772J-1257D01*
G01Y931415D01*
G03X344066Y929560I2225J73D01*
G03X346292I1113J1928D01*
G02X347766I737J-1277D01*
G03X349992I1113J1928D01*
G02X351466I737J-1277D01*
G01X351524Y929526D01*
G03X353692Y929560I1053J1962D01*
G02X355166I737J-1277D01*
G01X355207Y929536D01*
G03X357391Y929560I1071J1952D01*
G02X358865I737J-1277D01*
G01X358906Y929536D01*
G03X361092Y929560I1072J1952D01*
G02X362566I737J-1277D01*
G01X362624Y929526D01*
G03X364792Y929560I1053J1962D01*
G02X366266I737J-1277D01*
G01X366324Y929526D01*
G03X368492Y929560I1053J1962D01*
G02X369966I737J-1277D01*
G03X372192I1113J1928D01*
G02X373666I737J-1277D01*
G01X373724Y929526D01*
G03X375892Y929560I1053J1962D01*
G02X377366I737J-1277D01*
G01X377424Y929526D01*
G03X379592Y929560I1053J1962D01*
G02X381066I737J-1277D01*
G01X381107Y929536D01*
G03X383291Y929560I1071J1952D01*
G02X384765I737J-1277D01*
G01X384806Y929536D01*
G03X386992Y929560I1072J1952D01*
G02X388466I737J-1277D01*
G01X388497Y929542D01*
X388524Y929526D01*
G03X390692Y929560I1053J1962D01*
G02X392166I737J-1277D01*
G01X392224Y929526D01*
G03X394392Y929560I1053J1962D01*
G02X395866I737J-1277D01*
G03X398092I1113J1928D01*
G02X399566I737J-1277D01*
G01X399624Y929526D01*
G03X401483Y929412I1053J1961D01*
G03X401562Y929444I-796J2079D01*
G01X401913Y929350D01*
X402529Y928283D01*
G01X424729Y921875D02*
X421635Y924969D01*
X414818D01*
X413048Y926739D01*
X410847D01*
X409900Y925792D01*
X403113D01*
X402252Y926653D01*
G03X399624Y927040I-1574J-1574D01*
G01X399566Y927006D01*
G02X398092I-737J1277D01*
G03X395924Y927040I-1114J-1927D01*
G01X395866Y927006D01*
G02X394392I-737J1277D01*
G03X392224Y927040I-1114J-1927D01*
G01X392166Y927006D01*
G02X390692I-737J1277D01*
G03X388524Y927040I-1114J-1927D01*
G01X388497Y927024D01*
X388466Y927006D01*
G02X386992I-737J1277D01*
G03X384806Y927030I-1114J-1927D01*
G01X384765Y927006D01*
G02X383291I-737J1277D01*
G01X383250Y927030D01*
G03X381066Y927006I-1071J-1951D01*
G02X379592I-737J1277D01*
G03X377424Y927040I-1114J-1927D01*
G01X377366Y927006D01*
G02X375892I-737J1277D01*
G03X373724Y927040I-1114J-1927D01*
G01X373666Y927006D01*
G02X372192I-737J1277D01*
G03X370024Y927040I-1114J-1927D01*
G01X369966Y927006D01*
G02X368492I-737J1277D01*
G03X366324Y927040I-1114J-1927D01*
G01X366266Y927006D01*
G02X364792I-737J1277D01*
G03X362624Y927040I-1114J-1927D01*
G01X362566Y927006D01*
G02X361092I-737J1277D01*
G03X358906Y927030I-1114J-1927D01*
G01X358865Y927006D01*
G02X357391I-737J1277D01*
G01X357350Y927030D01*
G03X355166Y927006I-1071J-1951D01*
G02X353692I-737J1277D01*
G03X351524Y927040I-1114J-1927D01*
G01X351466Y927006D01*
G02X349992I-737J1277D01*
G03X347824Y927040I-1114J-1927D01*
G01X347766Y927006D01*
G03X347305Y926652I1113J-1926D01*
G01X344359Y926807D01*
X344029D01*
G01X422878Y918670D02*
X424109D01*
X424335Y918896D01*
G03X422141Y919947I-1457J-226D01*
G01X422083Y919913D01*
G02X419915Y919947I-1053J1962D01*
G03X418441I-737J-1277D01*
G01X418383Y919913D01*
G02X416215Y919947I-1053J1962D01*
G03X414741I-737J-1277D01*
G01X414683Y919913D01*
G02X412515Y919947I-1053J1962D01*
G03X411041I-737J-1277D01*
G01X410983Y919913D01*
G02X408815Y919947I-1053J1962D01*
G03X407341I-737J-1277D01*
G01X407283Y919913D01*
G02X405115Y919947I-1053J1962D01*
G03X403641I-737J-1277D01*
G01X403583Y919913D01*
G02X401415Y919947I-1053J1962D01*
G03X399941I-737J-1277D01*
G02X397715I-1113J1928D01*
G03X396241I-737J-1277D01*
G01X396183Y919913D01*
G02X394015Y919947I-1053J1962D01*
G03X392541I-737J-1277D01*
G01X392483Y919913D01*
G02X390315Y919947I-1053J1962D01*
G03X388841I-737J-1277D01*
G01X388800Y919923D01*
G02X386616Y919947I-1071J1952D01*
G03X385142I-737J-1277D01*
G01X385101Y919923D01*
G02X382915Y919947I-1072J1952D01*
G03X381441I-737J-1277D01*
G01X381383Y919913D01*
G02X379215Y919947I-1053J1962D01*
G03X377741I-737J-1277D01*
G01X377683Y919913D01*
G02X375515Y919947I-1053J1962D01*
G03X374041I-737J-1277D01*
G02X371815I-1113J1928D01*
G03X370341I-737J-1277D01*
G01X370283Y919913D01*
G02X368115Y919947I-1053J1962D01*
G03X366641I-737J-1277D01*
G01X366583Y919913D01*
G02X364415Y919947I-1053J1962D01*
G03X362941I-737J-1277D01*
G01X362900Y919923D01*
G02X360716Y919947I-1071J1952D01*
G03X359242I-737J-1277D01*
G01X359201Y919923D01*
G02X357015Y919947I-1072J1952D01*
G03X355541I-737J-1277D01*
G01X355483Y919913D01*
G02X353315Y919947I-1053J1962D01*
G03X351841I-737J-1277D01*
G01X351783Y919913D01*
G02X349615Y919947I-1053J1962D01*
G03X348141I-737J-1277D01*
G01X348100Y919923D01*
G02X345916Y919947I-1071J1952D01*
G03X345179Y920147I-742J-1276D01*
G01X344469D01*
X344041Y919719D01*
X337729D01*
X333009Y924439D01*
X328819D01*
G01X330127Y916955D02*
X333181D01*
X334272Y915864D01*
Y914864D01*
X335146Y913990D01*
X335148Y913992D01*
X339629D01*
G03X340366Y914189I1J1474D01*
G02X342592I1113J-1927D01*
G03X344066I737J1277D01*
G02X346292I1113J-1927D01*
G03X347766I737J1277D01*
G01X347824Y914223D01*
G02X349992Y914189I1054J-1961D01*
G03X351466I737J1277D01*
G01X351524Y914223D01*
G02X353692Y914189I1054J-1961D01*
G03X355166I737J1277D01*
G01X355224Y914223D01*
G02X357392Y914189I1054J-1961D01*
G03X358866I737J1277D01*
G01X358907Y914213D01*
G02X361091Y914189I1071J-1951D01*
G03X362565I737J1277D01*
G01X362606Y914213D01*
G02X364792Y914189I1072J-1951D01*
G03X366266I737J1277D01*
G01X366324Y914223D01*
G02X368492Y914189I1054J-1961D01*
G03X369966I737J1277D01*
G02X372192I1113J-1927D01*
G03X373666I737J1277D01*
G01X373724Y914223D01*
G02X375892Y914189I1054J-1961D01*
G03X377366I737J1277D01*
G01X377424Y914223D01*
G02X379592Y914189I1054J-1961D01*
G03X381066I737J1277D01*
G01X381124Y914223D01*
G02X383292Y914189I1054J-1961D01*
G03X384766I737J1277D01*
G01X384807Y914213D01*
G02X386991Y914189I1071J-1951D01*
G03X388465I737J1277D01*
G01X388497Y914208D01*
X388506Y914213D01*
G02X390692Y914189I1072J-1951D01*
G03X392166I737J1277D01*
G01X392224Y914223D01*
G02X394392Y914189I1054J-1961D01*
G03X395866I737J1277D01*
G02X398092I1113J-1927D01*
G03X399566I737J1277D01*
G01X399624Y914223D01*
G02X401562Y914305I1054J-1961D01*
G01X401913Y914399D01*
X402291Y915053D01*
X402529Y915466D01*
G01X421029D02*
X419798D01*
X419539Y915725D01*
G03X418465Y917379I-2210J-259D01*
G01X418441Y917393D01*
X418383Y917427D01*
G03X416215Y917393I-1054J-1961D01*
G02X414741I-737J1277D01*
G01X414683Y917427D01*
G03X412515Y917393I-1054J-1961D01*
G02X411041I-737J1277D01*
G01X410983Y917427D01*
G03X408815Y917393I-1054J-1961D01*
G02X407341I-737J1277D01*
G01X407283Y917427D01*
G03X405115Y917393I-1054J-1961D01*
G02X403641I-737J1277D01*
G01X403583Y917427D01*
G03X401415Y917393I-1054J-1961D01*
G02X399941I-737J1277D01*
G01X399883Y917427D01*
G03X397715Y917393I-1054J-1961D01*
G02X396241I-737J1277D01*
G01X396183Y917427D01*
G03X394015Y917393I-1054J-1961D01*
G02X392541I-737J1277D01*
G01X392483Y917427D01*
G03X390315Y917393I-1054J-1961D01*
G02X388841I-737J1277D01*
G03X386657Y917417I-1113J-1927D01*
G01X386616Y917393D01*
G02X385142I-737J1277D01*
G01X385101Y917417D01*
G03X382915Y917393I-1072J-1951D01*
G02X381441I-737J1277D01*
G01X381383Y917427D01*
G03X379215Y917393I-1054J-1961D01*
G02X377741I-737J1277D01*
G01X377683Y917427D01*
G03X375515Y917393I-1054J-1961D01*
G02X374041I-737J1277D01*
G01X373983Y917427D01*
G03X371815Y917393I-1054J-1961D01*
G02X370341I-737J1277D01*
G01X370283Y917427D01*
G03X368115Y917393I-1054J-1961D01*
G02X366641I-737J1277D01*
G01X366583Y917427D01*
G03X364415Y917393I-1054J-1961D01*
G02X362941I-737J1277D01*
G03X360757Y917417I-1113J-1927D01*
G01X360716Y917393D01*
G02X359242I-737J1277D01*
G01X359201Y917417D01*
G03X357015Y917393I-1072J-1951D01*
G02X355541I-737J1277D01*
G01X355483Y917427D01*
G03X353315Y917393I-1054J-1961D01*
G02X351841I-737J1277D01*
G01X351783Y917427D01*
G03X349615Y917393I-1054J-1961D01*
G02X348141I-737J1277D01*
G01X348100Y917417D01*
G03X345916Y917393I-1071J-1951D01*
G02X344442I-737J1277D01*
G03X341191Y918264I-3251J-5633D01*
G01X336538D01*
X334937Y919865D01*
X331767D01*
X331268Y920364D01*
G01X426578Y918670D02*
X425347D01*
X425090Y918927D01*
G03X423992Y920598I-2212J-257D01*
G03X421824Y920632I-1115J-1928D01*
G01X421766Y920598D01*
G02X420292I-737J1277D01*
G03X418124Y920632I-1115J-1928D01*
G01X418066Y920598D01*
G02X416592I-737J1277D01*
G03X414424Y920632I-1115J-1928D01*
G01X414366Y920598D01*
G02X412892I-737J1277D01*
G03X410724Y920632I-1115J-1928D01*
G01X410666Y920598D01*
G02X409192I-737J1277D01*
G03X407024Y920632I-1115J-1928D01*
G01X406966Y920598D01*
G02X405492I-737J1277D01*
G03X403324Y920632I-1115J-1928D01*
G01X403266Y920598D01*
G02X401792I-737J1277D01*
G03X399606Y920622I-1114J-1928D01*
G01X399565Y920598D01*
G02X398091I-737J1277D01*
G03X395907Y920622I-1113J-1928D01*
G01X395866Y920598D01*
G02X394392I-737J1277D01*
G03X392224Y920632I-1115J-1928D01*
G01X392166Y920598D01*
G02X390692I-737J1277D01*
G03X388524Y920632I-1115J-1928D01*
G01X388497Y920616D01*
X388466Y920598D01*
G02X386992I-737J1277D01*
G03X384766I-1113J-1928D01*
G02X383292I-737J1277D01*
G03X381124Y920632I-1115J-1928D01*
G01X381066Y920598D01*
G02X379592I-737J1277D01*
G03X377424Y920632I-1115J-1928D01*
G01X377366Y920598D01*
G02X375892I-737J1277D01*
G03X373706Y920622I-1114J-1928D01*
G01X373665Y920598D01*
G02X372191I-737J1277D01*
G03X370007Y920622I-1113J-1928D01*
G01X369966Y920598D01*
G02X368492I-737J1277D01*
G03X366324Y920632I-1115J-1928D01*
G01X366266Y920598D01*
G02X364792I-737J1277D01*
G03X362624Y920632I-1115J-1928D01*
G01X362566Y920598D01*
G02X361092I-737J1277D01*
G03X358866I-1113J-1928D01*
G02X357392I-737J1277D01*
G03X355224Y920632I-1115J-1928D01*
G01X355166Y920598D01*
G02X353692I-737J1277D01*
G03X351524Y920632I-1115J-1928D01*
G01X351466Y920598D01*
G02X349992I-737J1277D01*
G03X347824Y920632I-1115J-1928D01*
G01X347766Y920598D01*
G02X346292I-737J1277D01*
G03X345179Y920896I-1113J-1928D01*
G01X339050D01*
X333647Y926299D01*
X326374D01*
G01X421029Y921875D02*
X419798D01*
X418047Y923626D01*
X415725D01*
G02X414743Y923803I-245J1454D01*
G03X412575Y923837I-1115J-1928D01*
G01X412517Y923803D01*
G02X411043I-737J1277D01*
G03X408875Y923837I-1115J-1928D01*
G01X408817Y923803D01*
G02X407343I-737J1277D01*
G03X405175Y923837I-1115J-1928D01*
G01X405117Y923803D01*
G02X403643I-737J1277D01*
G03X401475Y923837I-1115J-1928D01*
G01X401434Y923813D01*
X401415Y923802D01*
G02X399941I-737J1277D01*
G03X397715I-1113J-1927D01*
G02X396241I-737J1277D01*
G01X396183Y923836D01*
G03X394015Y923802I-1054J-1961D01*
G02X392541I-737J1277D01*
G01X392483Y923836D01*
G03X390315Y923802I-1054J-1961D01*
G02X388841I-737J1277D01*
G01X388783Y923836D01*
G03X386615Y923802I-1054J-1961D01*
G02X385141I-737J1277D01*
G01X385100Y923826D01*
G03X382916Y923802I-1071J-1951D01*
G02X381442I-737J1277D01*
G01X381401Y923826D01*
G03X379215Y923802I-1072J-1951D01*
G02X377741I-737J1277D01*
G01X377683Y923836D01*
G03X375515Y923802I-1054J-1961D01*
G02X374041I-737J1277D01*
G03X371815I-1113J-1927D01*
G02X370341I-737J1277D01*
G01X370283Y923836D01*
G03X368115Y923802I-1054J-1961D01*
G02X366641I-737J1277D01*
G01X366583Y923836D01*
G03X364415Y923802I-1054J-1961D01*
G02X362941I-737J1277D01*
G01X362883Y923836D01*
G03X360715Y923802I-1054J-1961D01*
G02X359241I-737J1277D01*
G01X359200Y923826D01*
G03X357016Y923802I-1071J-1951D01*
G02X355542I-737J1277D01*
G01X355501Y923826D01*
G03X353315Y923802I-1072J-1951D01*
G02X351841I-737J1277D01*
G01X351783Y923836D01*
G03X349615Y923802I-1054J-1961D01*
G02X348141I-737J1277D01*
G03X347029Y924100I-1112J-1926D01*
G01X346238D01*
X345975Y923837D01*
X345917Y923803D01*
G02X344443I-737J1277D01*
G03X342275Y923837I-1115J-1928D01*
G01X342217Y923803D01*
G02X340743I-737J1277D01*
G02X340436Y924037I732J1278D01*
G01X338772Y925701D01*
G01X406662Y1050952D02*
X404074Y1049025D01*
X404073D01*
G02X401848I-1112J1926D01*
G03X400374I-737J-1276D01*
G01X400316Y1048991D01*
G02X398148Y1049025I-1054J1961D01*
G03X396674I-737J-1276D01*
G01X396616Y1048991D01*
G02X394448Y1049025I-1054J1961D01*
G03X392974I-737J-1277D01*
G01X392916Y1048991D01*
G02X390748Y1049025I-1054J1961D01*
G03X389274I-737J-1277D01*
G01X389216Y1048991D01*
G02X387048Y1049025I-1054J1961D01*
G01X387024Y1049039D01*
G02X385936Y1050952I1138J1913D01*
G03X385233Y1052209I-1475J0D01*
G01X385198Y1052229D01*
G03X383724I-737J-1277D01*
G01X383683Y1052205D01*
G02X381499Y1052229I-1071J1952D01*
G03X380025I-737J-1277D01*
G02X377857Y1052195I-1115J1928D01*
G01X377799Y1052229D01*
G03X376325I-737J-1277D01*
G02X374157Y1052195I-1115J1928D01*
G01X374099Y1052229D01*
G03X372625I-737J-1277D01*
G02X370457Y1052195I-1115J1928D01*
G01X370399Y1052229D01*
G03X368925I-737J-1277D01*
G02X366757Y1052195I-1115J1928D01*
G01X366699Y1052229D01*
G03X365225I-737J-1277D01*
G02X363057Y1052195I-1115J1928D01*
G01X362999Y1052229D01*
G03X361525I-737J-1277D01*
G02X359339Y1052205I-1114J1928D01*
G01X359298Y1052229D01*
G03X357824I-737J-1277D01*
G01X357766Y1052195D01*
G02X355598Y1052229I-1053J1962D01*
G03X354124I-737J-1277D01*
G02X351898I-1113J1928D01*
G03X350424I-737J-1277D01*
G02X348198I-1113J1928D01*
G03X346724I-737J-1277D01*
G02X344498I-1113J1928D01*
G03X343761Y1052429I-742J-1276D01*
G01X339114D01*
G01X421462Y1076587D02*
X420846Y1077654D01*
X420495Y1077748D01*
G02X418557Y1077830I-884J2043D01*
G01X418499Y1077864D01*
G03X417025I-737J-1277D01*
G02X414857Y1077830I-1114J1927D01*
G01X414799Y1077864D01*
G03X413325I-737J-1277D01*
G02X411157Y1077830I-1114J1927D01*
G01X411099Y1077864D01*
G03X409625I-737J-1277D01*
G02X407439Y1077840I-1114J1927D01*
G01X407398Y1077864D01*
G02X406286Y1079752I1113J1927D01*
G01Y1079791D01*
G03X405583Y1081048I-1475J0D01*
G01X405548Y1081068D01*
G03X404074I-737J-1277D01*
G01X404016Y1081034D01*
G02X401848Y1081068I-1054J1961D01*
G03X400374I-737J-1277D01*
G01X400316Y1081034D01*
G02X398148Y1081068I-1054J1961D01*
G03X396674I-737J-1277D01*
G01X396616Y1081034D01*
G02X394448Y1081068I-1054J1961D01*
G03X392974I-737J-1277D01*
G01X392916Y1081034D01*
G02X390748Y1081068I-1054J1961D01*
G03X389274I-737J-1277D01*
G02X387048I-1113J1927D01*
G03X385574I-737J-1277D01*
G01X385516Y1081034D01*
G02X383348Y1081068I-1054J1961D01*
G03X381874I-737J-1277D01*
G01X381816Y1081034D01*
G02X379648Y1081068I-1054J1961D01*
G03X378174I-737J-1277D01*
G01X378116Y1081034D01*
G02X375948Y1081068I-1054J1961D01*
G03X374474I-737J-1277D01*
G01X374416Y1081034D01*
G02X372248Y1081068I-1054J1961D01*
G03X370774I-737J-1277D01*
G01X370716Y1081034D01*
G02X368548Y1081068I-1054J1961D01*
G03X367074I-737J-1277D01*
G01X367016Y1081034D01*
G02X364848Y1081068I-1054J1961D01*
G03X363374I-737J-1277D01*
G02X361190Y1081044I-1113J1927D01*
G01X361149Y1081068D01*
G03X359675I-737J-1277D01*
G01X359634Y1081044D01*
G02X357448Y1081068I-1072J1951D01*
G03X355974I-737J-1277D01*
G02X353748I-1113J1927D01*
G03X352274I-737J-1277D01*
G02X350048I-1113J1927D01*
G03X348574I-737J-1277D01*
G02X346348I-1113J1927D01*
G03X344874I-737J-1277D01*
G02X342706Y1081034I-1114J1927D01*
G01X342648Y1081068D01*
G03X341174I-737J-1277D01*
G02X338946I-1114J1927D01*
G03X337472I-737J-1277D01*
G01X337414Y1081034D01*
G02X336349Y1080766I-1065J1982D01*
G01X334607D01*
G01X400678Y912262D02*
X401294Y913329D01*
X401211Y913636D01*
G03X399941Y913539I-534J-1374D01*
G01X399900Y913515D01*
G02X397716Y913539I-1071J1951D01*
G03X396242I-737J-1277D01*
G01X396201Y913515D01*
G02X394015Y913539I-1072J1951D01*
G03X392541I-737J-1277D01*
G01X392483Y913505D01*
G02X390315Y913539I-1054J1961D01*
G03X388841I-737J-1277D01*
G02X386615I-1113J1927D01*
G03X385141I-737J-1277D01*
G01X385083Y913505D01*
G02X382915Y913539I-1054J1961D01*
G03X381441I-737J-1277D01*
G01X381383Y913505D01*
G02X379215Y913539I-1054J1961D01*
G03X377741I-737J-1277D01*
G01X377683Y913505D01*
G02X375515Y913539I-1054J1961D01*
G03X374041I-737J-1277D01*
G01X374000Y913515D01*
G02X371816Y913539I-1071J1951D01*
G03X370342I-737J-1277D01*
G01X370301Y913515D01*
G02X368115Y913539I-1072J1951D01*
G03X366641I-737J-1277D01*
G01X366583Y913505D01*
G02X364415Y913539I-1054J1961D01*
G03X362941I-737J-1277D01*
G02X360715I-1113J1927D01*
G03X359241I-737J-1277D01*
G01X359183Y913505D01*
G02X357015Y913539I-1054J1961D01*
G03X355541I-737J-1277D01*
G01X355483Y913505D01*
G02X353315Y913539I-1054J1961D01*
G03X351841I-737J-1277D01*
G01X351783Y913505D01*
G02X349615Y913539I-1054J1961D01*
G03X348141I-737J-1277D01*
G01X348100Y913515D01*
G02X345916Y913539I-1071J1951D01*
G03X344442I-737J-1277D01*
G02X342216I-1113J1927D01*
G03X340742I-737J-1277D01*
G02X339629Y913241I-1112J1927D01*
G01X334407D01*
G01X413629Y915466D02*
X413013Y914399D01*
X412662Y914305D01*
G03X410724Y914223I-884J-2043D01*
G01X410666Y914189D01*
G02X409192I-737J1277D01*
G03X407024Y914223I-1114J-1927D01*
G01X406966Y914189D01*
G02X405492I-737J1277D01*
G03X403324Y914223I-1114J-1927D01*
G01X403266Y914189D01*
X403242Y914175D01*
G03X402153Y912262I1136J-1913D01*
G02X401450Y911005I-1475J0D01*
G01X401415Y910985D01*
G02X399941I-737J1277D01*
G01X399900Y911009D01*
G03X397716Y910985I-1071J-1952D01*
G02X396242I-737J1277D01*
G01X396201Y911009D01*
G03X394015Y910985I-1072J-1952D01*
G02X392541I-737J1277D01*
G01X392483Y911019D01*
G03X390315Y910985I-1053J-1962D01*
G02X388841I-737J1277D01*
G01X388783Y911019D01*
G03X386615Y910985I-1053J-1962D01*
G02X385141I-737J1277D01*
G03X382915I-1113J-1928D01*
G02X381441I-737J1277D01*
G01X381383Y911019D01*
G03X379215Y910985I-1053J-1962D01*
G02X377741I-737J1277D01*
G01X377683Y911019D01*
G03X375515Y910985I-1053J-1962D01*
G02X374041I-737J1277D01*
G01X374000Y911009D01*
G03X371816Y910985I-1071J-1952D01*
G02X370342I-737J1277D01*
G01X370301Y911009D01*
G03X368115Y910985I-1072J-1952D01*
G02X366641I-737J1277D01*
G01X366583Y911019D01*
G03X364415Y910985I-1053J-1962D01*
G02X362941I-737J1277D01*
G01X362883Y911019D01*
G03X360715Y910985I-1053J-1962D01*
G02X359241I-737J1277D01*
G03X357015I-1113J-1928D01*
G02X355541I-737J1277D01*
G01X355483Y911019D01*
G03X353315Y910985I-1053J-1962D01*
G02X351841I-737J1277D01*
G01X351783Y911019D01*
G03X349615Y910985I-1053J-1962D01*
G02X348141I-737J1277D01*
G01X348100Y911009D01*
G03X345916Y910985I-1071J-1952D01*
G02X345179Y910785I-742J1276D01*
G01X332925D01*
X330175Y913535D01*
G01X417329Y921875D02*
X415718Y922866D01*
G02X414366Y923152I-238J2214D01*
G03X412892I-737J-1277D01*
G01X412834Y923118D01*
G02X410666Y923152I-1053J1962D01*
G03X409192I-737J-1277D01*
G01X409134Y923118D01*
G02X406966Y923152I-1053J1962D01*
G03X405492I-737J-1277D01*
G01X405434Y923118D01*
G02X403266Y923152I-1053J1962D01*
G03X401792I-737J-1277D01*
G02X399606Y923128I-1114J1927D01*
G01X399565Y923152D01*
G03X398091I-737J-1277D01*
G02X395907Y923128I-1113J1927D01*
G01X395866Y923152D01*
G03X394392I-737J-1277D01*
G02X392224Y923118I-1114J1927D01*
G01X392166Y923152D01*
G03X390692I-737J-1277D01*
G02X388524Y923118I-1114J1927D01*
G01X388497Y923134D01*
X388466Y923152D01*
G03X386992I-737J-1277D01*
G02X384824Y923118I-1114J1927D01*
G01X384766Y923152D01*
G03X383292I-737J-1277D01*
G02X381066I-1113J1927D01*
G03X379592I-737J-1277D01*
G02X377424Y923118I-1114J1927D01*
G01X377366Y923152D01*
G03X375892I-737J-1277D01*
G02X373706Y923128I-1114J1927D01*
G01X373665Y923152D01*
G03X372191I-737J-1277D01*
G02X370007Y923128I-1113J1927D01*
G01X369966Y923152D01*
G03X368492I-737J-1277D01*
G02X366324Y923118I-1114J1927D01*
G01X366266Y923152D01*
G03X364792I-737J-1277D01*
G02X362624Y923118I-1114J1927D01*
G01X362566Y923152D01*
G03X361092I-737J-1277D01*
G02X358924Y923118I-1114J1927D01*
G01X358866Y923152D01*
G03X357392I-737J-1277D01*
G02X355166I-1113J1927D01*
G03X353692I-737J-1277D01*
G02X351524Y923118I-1114J1927D01*
G01X351466Y923152D01*
G03X349992I-737J-1277D01*
G02X347824Y923118I-1114J1927D01*
G01X347766Y923152D01*
X347767Y923153D01*
G03X347029Y923351I-738J-1276D01*
G01X346549D01*
X346437Y923239D01*
X346292Y923152D01*
X346234Y923118D01*
G02X344066Y923152I-1053J1962D01*
G03X342592I-737J-1277D01*
G01X342551Y923128D01*
G02X340367Y923152I-1071J1952D01*
G02X339905Y923506I1110J1927D01*
G01X338935D01*
X337331Y925110D01*
G01X411872Y925264D02*
X410636D01*
X410394Y925022D01*
X402823D01*
X401722Y926123D01*
G03X401415Y926356I-1038J-1049D01*
G03X399941I-737J-1277D01*
G01X399883Y926322D01*
G02X397715Y926356I-1054J1961D01*
G03X396241I-737J-1277D01*
G01X396183Y926322D01*
G02X394015Y926356I-1054J1961D01*
G03X392541I-737J-1277D01*
G01X392483Y926322D01*
G02X390315Y926356I-1054J1961D01*
G03X388841I-737J-1277D01*
G01X388783Y926322D01*
G02X386615Y926356I-1054J1961D01*
G03X385141I-737J-1277D01*
G02X382957Y926332I-1113J1927D01*
G01X382916Y926356D01*
G03X381442I-737J-1277D01*
G01X381401Y926332D01*
G02X379215Y926356I-1072J1951D01*
G03X377741I-737J-1277D01*
G01X377683Y926322D01*
G02X375515Y926356I-1054J1961D01*
G03X374041I-737J-1277D01*
G01X373983Y926322D01*
G02X371815Y926356I-1054J1961D01*
G03X370341I-737J-1277D01*
G01X370283Y926322D01*
G02X368115Y926356I-1054J1961D01*
G03X366641I-737J-1277D01*
G01X366583Y926322D01*
G02X364415Y926356I-1054J1961D01*
G03X362941I-737J-1277D01*
G01X362883Y926322D01*
G02X360715Y926356I-1054J1961D01*
G03X359241I-737J-1277D01*
G02X357057Y926332I-1113J1927D01*
G01X357016Y926356D01*
G03X355542I-737J-1277D01*
G01X355501Y926332D01*
G02X353315Y926356I-1072J1951D01*
G03X351841I-737J-1277D01*
G01X351783Y926322D01*
G02X349615Y926356I-1054J1961D01*
G03X347835Y926122I-738J-1277D01*
G01X347427Y925714D01*
X343296D01*
G01X410362Y1057361D02*
X407567Y1055748D01*
G03X406661Y1054157I944J-1591D01*
G01Y1054104D01*
G02X405736Y1052554I-1850J53D01*
G02X403886I-925J1603D01*
G01X403833Y1052585D01*
G03X402036Y1052554I-871J-1633D01*
G03X401112Y1050990I926J-1602D01*
G01Y1050952D01*
G02X400562Y1050001I-1099J1D01*
G01X399999Y1049675D01*
G02X398525I-737J1277D01*
G03X396357Y1049709I-1114J-1927D01*
G01X396299Y1049675D01*
G02X394825I-737J1277D01*
G03X392657Y1049709I-1114J-1927D01*
G01X392599Y1049675D01*
G02X391125I-737J1277D01*
G03X388957Y1049709I-1114J-1927D01*
G01X388899Y1049675D01*
G02X387425I-737J1277D01*
G01Y1049676D01*
X387369Y1049708D01*
G02X386687Y1050952I794J1244D01*
G01Y1050982D01*
G03X385574Y1052880I-2226J-30D01*
G03X383390Y1052904I-1113J-1928D01*
G01X383349Y1052880D01*
G02X381875I-737J1277D01*
G01X381834Y1052904D01*
G03X379648Y1052880I-1072J-1952D01*
G02X378174I-737J1277D01*
G01X378116Y1052914D01*
G03X375948Y1052880I-1053J-1962D01*
G02X374474I-737J1277D01*
G01X374416Y1052914D01*
G03X372248Y1052880I-1053J-1962D01*
G02X370774I-737J1277D01*
G01X370716Y1052914D01*
G03X368548Y1052880I-1053J-1962D01*
G02X367074I-737J1277D01*
G01X367016Y1052914D01*
G03X364848Y1052880I-1053J-1962D01*
G02X363374I-737J1277D01*
G01X363316Y1052914D01*
G03X361148Y1052880I-1053J-1962D01*
G02X359674I-737J1277D01*
G03X357490Y1052904I-1113J-1928D01*
G01X357449Y1052880D01*
G02X355975I-737J1277D01*
G03X353789Y1052904I-1114J-1928D01*
G01X353748Y1052880D01*
G02X352274I-737J1277D01*
G03X350048I-1113J-1928D01*
G02X348574I-737J1277D01*
G03X346348I-1113J-1928D01*
G02X344874I-737J1277D01*
G03X343761Y1053178I-1113J-1928D01*
G01X340655D01*
X340052Y1053781D01*
G01X427011Y1054157D02*
X425457D01*
X423619Y1055995D01*
Y1058319D01*
X424852Y1059552D01*
Y1060027D01*
G02X424786Y1060565I2160J538D01*
G03X424083Y1061822I-1475J0D01*
G01X424048Y1061842D01*
G02X422937Y1063683I1114J1928D01*
G01Y1063770D01*
G03X422234Y1065027I-1475J0D01*
G01X422199Y1065047D01*
X422175Y1065061D01*
G02X421086Y1066974I1136J1913D01*
G03X420383Y1068231I-1475J0D01*
G01X420348Y1068251D01*
G02X419237Y1070117I1114J1927D01*
G01Y1070178D01*
G03X418534Y1071435I-1475J0D01*
G01X418499Y1071455D01*
G02X417386Y1073327I1112J1928D01*
G01Y1073383D01*
G03X416683Y1074640I-1475J0D01*
G01X416648Y1074660D01*
G03X415174I-737J-1277D01*
G01X415116Y1074626D01*
G02X412948Y1074660I-1054J1961D01*
G03X411474I-737J-1277D01*
G01X411416Y1074626D01*
G02X409248Y1074660I-1054J1961D01*
G03X407774I-737J-1277D01*
G02X405548I-1113J1927D01*
G02X404436Y1076548I1113J1927D01*
G01Y1076621D01*
G03X403699Y1077864I-1474J-34D01*
G03X402225I-737J-1277D01*
G02X400039Y1077840I-1114J1927D01*
G01X399998Y1077864D01*
G03X398524I-737J-1277D01*
G02X396340Y1077840I-1113J1927D01*
G01X396299Y1077864D01*
G03X394825I-737J-1277D01*
G02X392657Y1077830I-1114J1927D01*
G01X392599Y1077864D01*
G03X391125I-737J-1277D01*
G02X388957Y1077830I-1114J1927D01*
G01X388899Y1077864D01*
G03X387425I-737J-1277D01*
G02X385257Y1077830I-1114J1927D01*
G01X385199Y1077864D01*
G03X383725I-737J-1277D01*
G02X381557Y1077830I-1114J1927D01*
G01X381499Y1077864D01*
G03X380025I-737J-1277D01*
G02X377857Y1077830I-1114J1927D01*
G01X377799Y1077864D01*
G03X376325I-737J-1277D01*
G02X374139Y1077840I-1114J1927D01*
G01X374098Y1077864D01*
G03X372624I-737J-1277D01*
G02X370440Y1077840I-1113J1927D01*
G01X370399Y1077864D01*
G03X368925I-737J-1277D01*
G02X366757Y1077830I-1114J1927D01*
G01X366699Y1077864D01*
G03X365225I-737J-1277D01*
G02X363057Y1077830I-1114J1927D01*
G01X362999Y1077864D01*
G03X361525I-737J-1277D01*
G02X359299I-1113J1927D01*
G03X357825I-737J-1277D01*
G02X355639Y1077840I-1114J1927D01*
G01X355598Y1077864D01*
G03X354124I-737J-1277D01*
G02X351898I-1113J1927D01*
G03X350424I-737J-1277D01*
G02X348198I-1113J1927D01*
G03X346724I-737J-1277D01*
G02X344498I-1113J1927D01*
G03X343024I-737J-1277D01*
G02X340840Y1077840I-1113J1927D01*
G01X340799Y1077864D01*
G03X340062Y1078061I-736J-1277D01*
G01X335627D01*
X335081Y1077515D01*
X331174D01*
G01X408511Y1073383D02*
X407280D01*
X407023Y1073126D01*
G02X403757Y1071421I-2212J257D01*
G01X403699Y1071455D01*
G03X402225I-737J-1277D01*
G02X400057Y1071421I-1115J1928D01*
G01X399999Y1071455D01*
G03X398525I-737J-1277D01*
G02X396357Y1071421I-1115J1928D01*
G01X396299Y1071455D01*
G03X394825I-737J-1277D01*
G02X392657Y1071421I-1115J1928D01*
G01X392599Y1071455D01*
G03X391125I-737J-1277D01*
G02X388957Y1071421I-1115J1928D01*
G01X388899Y1071455D01*
G03X387425I-737J-1277D01*
G02X385239Y1071431I-1114J1928D01*
G01X385198Y1071455D01*
G03X383724I-737J-1277D01*
G01X383683Y1071431D01*
G02X381499Y1071455I-1071J1952D01*
G03X380025I-737J-1277D01*
G02X377857Y1071421I-1115J1928D01*
G01X377799Y1071455D01*
G03X376325I-737J-1277D01*
G02X374157Y1071421I-1115J1928D01*
G01X374099Y1071455D01*
G03X372625I-737J-1277D01*
G02X370457Y1071421I-1115J1928D01*
G01X370399Y1071455D01*
G03X368925I-737J-1277D01*
G02X366757Y1071421I-1115J1928D01*
G01X366699Y1071455D01*
G03X365225I-737J-1277D01*
G02X363057Y1071421I-1115J1928D01*
G01X362999Y1071455D01*
G03X361525I-737J-1277D01*
G02X359339Y1071431I-1114J1928D01*
G01X359298Y1071455D01*
G03X357824I-737J-1277D01*
G01X357766Y1071421D01*
G02X355598Y1071455I-1053J1962D01*
G03X354124I-737J-1277D01*
G02X351940Y1071431I-1113J1928D01*
G01X351899Y1071455D01*
G03X350425I-737J-1277D01*
G01X350384Y1071431D01*
G02X348198Y1071455I-1072J1952D01*
G03X347074Y1071759I-1124J-1928D01*
G01X344759D01*
G01X404811Y1073383D02*
X406042D01*
X406268Y1073157D01*
G02X404074Y1072106I-1457J226D01*
G01X404016Y1072140D01*
G03X401848Y1072106I-1053J-1962D01*
G02X400374I-737J1277D01*
G01X400316Y1072140D01*
G03X398148Y1072106I-1053J-1962D01*
G02X396674I-737J1277D01*
G01X396616Y1072140D01*
G03X394448Y1072106I-1053J-1962D01*
G02X392974I-737J1277D01*
G01X392916Y1072140D01*
G03X390748Y1072106I-1053J-1962D01*
G02X389274I-737J1277D01*
G01X389216Y1072140D01*
G03X387048Y1072106I-1053J-1962D01*
G02X385574I-737J1277D01*
G03X383390Y1072130I-1113J-1928D01*
G01X383349Y1072106D01*
G02X381875I-737J1277D01*
G01X381834Y1072130D01*
G03X379648Y1072106I-1072J-1952D01*
G02X378174I-737J1277D01*
G01X378116Y1072140D01*
G03X375948Y1072106I-1053J-1962D01*
G02X374474I-737J1277D01*
G01X374416Y1072140D01*
G03X372248Y1072106I-1053J-1962D01*
G02X370774I-737J1277D01*
G01X370716Y1072140D01*
G03X368548Y1072106I-1053J-1962D01*
G02X367074I-737J1277D01*
G01X367016Y1072140D01*
G03X364848Y1072106I-1053J-1962D01*
G02X363374I-737J1277D01*
G01X363316Y1072140D01*
G03X361148Y1072106I-1053J-1962D01*
G02X359674I-737J1277D01*
G03X357490Y1072130I-1113J-1928D01*
G01X357449Y1072106D01*
G02X355975I-737J1277D01*
G03X353789Y1072130I-1114J-1928D01*
G01X353748Y1072106D01*
G02X352274I-737J1277D01*
G01X352233Y1072130D01*
G03X350049Y1072106I-1071J-1952D01*
G02X348575I-737J1277D01*
G03X345764Y1072860I-2811J-4862D01*
G01X344830D01*
G01X402962Y1076587D02*
G03X401504Y1076192I-1J-2886D01*
G01X399998Y1075310D01*
G02X398524I-737J1277D01*
G03X396340Y1075334I-1113J-1927D01*
G01X396299Y1075310D01*
G02X394825I-737J1277D01*
G03X392657Y1075344I-1114J-1927D01*
G01X392599Y1075310D01*
G02X391125I-737J1277D01*
G03X388957Y1075344I-1114J-1927D01*
G01X388899Y1075310D01*
G02X387425I-737J1277D01*
G03X385257Y1075344I-1114J-1927D01*
G01X385199Y1075310D01*
G02X383725I-737J1277D01*
G03X381499I-1113J-1927D01*
G02X380025I-737J1277D01*
G03X377857Y1075344I-1114J-1927D01*
G01X377799Y1075310D01*
G02X376325I-737J1277D01*
G03X374139Y1075334I-1114J-1927D01*
G01X374098Y1075310D01*
G02X372624I-737J1277D01*
G03X370440Y1075334I-1113J-1927D01*
G01X370399Y1075310D01*
G02X368925I-737J1277D01*
G03X366757Y1075344I-1114J-1927D01*
G01X366699Y1075310D01*
G02X365225I-737J1277D01*
G03X363057Y1075344I-1114J-1927D01*
G01X362999Y1075310D01*
G02X361525I-737J1277D01*
G03X359357Y1075344I-1114J-1927D01*
G01X359299Y1075310D01*
G02X357825I-737J1277D01*
G01X357784Y1075334D01*
G03X355598Y1075310I-1072J-1951D01*
G02X354124I-737J1277D01*
G03X351898I-1113J-1927D01*
G02X350424I-737J1277D01*
G01X350366Y1075344D01*
G03X348198Y1075310I-1054J-1961D01*
G02X345743Y1074648I-2455J4222D01*
G01X345742D01*
X345731Y1074659D01*
X343941D01*
G01X399262Y1121447D02*
X402036Y1119845D01*
G03X403833Y1119814I926J1602D01*
G01X403886Y1119845D01*
X403887D01*
G03X404436Y1120796I-549J951D01*
G01Y1121448D01*
G02X404477Y1121875I2224J2D01*
G02X405548Y1123374I2182J-427D01*
G01X405583Y1123394D01*
G03X406286Y1124651I-772J1257D01*
G01Y1124707D01*
G02X407399Y1126579I2225J-56D01*
G03X408136Y1127822I-737J1277D01*
G01Y1127895D01*
G02X409248Y1129783I2225J-39D01*
G01X409283Y1129803D01*
G03Y1132317I-772J1257D01*
G01X409252Y1132335D01*
X409248Y1132337D01*
G02X408137Y1134203I1114J1927D01*
G01Y1134264D01*
G03X405925Y1135541I-1475J0D01*
G02X402587Y1137396I-1113J1928D01*
G01Y1138247D01*
G02X403711Y1139553I2225J-778D01*
G03X404436Y1140335I-749J1421D01*
G01Y1141664D01*
X402898Y1143202D01*
X395834D01*
X395459Y1142827D01*
G01X406661Y1121447D02*
X405499D01*
X405215Y1121731D01*
G02X405924Y1122724I1447J-283D01*
G03X407036Y1124612I-1113J1927D01*
G01Y1124651D01*
G02X407739Y1125908I1475J0D01*
G01X407774Y1125928D01*
G03X408887Y1127800I-1112J1928D01*
G01Y1127890D01*
G02X409624Y1129133I1474J-34D01*
G01X409661Y1129155D01*
X409672Y1129161D01*
G03X410737Y1131060I-1161J1899D01*
G03X409649Y1132973I-2226J0D01*
G01X409625Y1132987D01*
X409590Y1133007D01*
G02X408887Y1134264I772J1257D01*
G01Y1134337D01*
G03X405549Y1136192I-2225J-73D01*
G02X403337Y1137469I-737J1277D01*
G01Y1138104D01*
G02X404062Y1138889I1475J-635D01*
G03X405186Y1140195I-1101J2084D01*
G01Y1141975D01*
X403209Y1143952D01*
X395834D01*
X395459Y1144327D01*
G01X402529Y909057D02*
X401913Y907990D01*
X401562Y907896D01*
G03X399624Y907814I-884J-2043D01*
G01X399566Y907780D01*
G02X398092I-737J1277D01*
G03X395924Y907814I-1114J-1927D01*
G01X395866Y907780D01*
G02X394392I-737J1277D01*
G03X392224Y907814I-1114J-1927D01*
G01X392166Y907780D01*
G02X390692I-737J1277D01*
G03X388524Y907814I-1114J-1927D01*
G01X388497Y907798D01*
X388466Y907780D01*
G02X386992I-737J1277D01*
G03X384806Y907804I-1114J-1927D01*
G01X384765Y907780D01*
G02X383291I-737J1277D01*
G01X383250Y907804D01*
G03X381066Y907780I-1071J-1951D01*
G02X379592I-737J1277D01*
G03X377424Y907814I-1114J-1927D01*
G01X377366Y907780D01*
G02X375892I-737J1277D01*
G03X373724Y907814I-1114J-1927D01*
G01X373666Y907780D01*
G02X372192I-737J1277D01*
G03X370024Y907814I-1114J-1927D01*
G01X369966Y907780D01*
G02X368492I-737J1277D01*
G03X366324Y907814I-1114J-1927D01*
G01X366266Y907780D01*
G02X364792I-737J1277D01*
G03X362624Y907814I-1114J-1927D01*
G01X362566Y907780D01*
G02X361092I-737J1277D01*
G03X358906Y907804I-1114J-1927D01*
G01X358865Y907780D01*
G02X357391I-737J1277D01*
G01X357350Y907804D01*
G03X355166Y907780I-1071J-1951D01*
G02X353692I-737J1277D01*
G03X351524Y907814I-1114J-1927D01*
G01X351466Y907780D01*
G02X349992I-737J1277D01*
G03X347824Y907814I-1114J-1927D01*
G01X347766Y907780D01*
G02X347029Y907581I-740J1276D01*
G01X346255D01*
X345372Y908464D01*
X331546D01*
X328995Y911015D01*
G01X415478Y912262D02*
X414862Y911195D01*
X414512Y911102D01*
G03X412515Y910985I-882J-2045D01*
G02X411041I-737J1277D01*
G01X410983Y911019D01*
G03X408815Y910985I-1053J-1962D01*
G03X407704Y909144I1114J-1928D01*
G01Y909057D01*
G02X407001Y907800I-1475J0D01*
G01X406966Y907780D01*
X406942Y907766D01*
G03X405853Y905853I1136J-1913D01*
G02X405150Y904596I-1475J0D01*
G01X405115Y904576D01*
G03X404004Y902710I1114J-1927D01*
G01Y902649D01*
G02X403301Y901392I-1475J0D01*
G01X403266Y901372D01*
G02X401792I-737J1277D01*
G03X399606Y901396I-1114J-1927D01*
G01X399565Y901372D01*
G02X398091I-737J1277D01*
G03X395907Y901396I-1113J-1927D01*
G01X395866Y901372D01*
G02X394392I-737J1277D01*
G03X392224Y901406I-1114J-1927D01*
G01X392166Y901372D01*
G02X390692I-737J1277D01*
G03X388524Y901406I-1114J-1927D01*
G01X388497Y901390D01*
X388466Y901372D01*
G02X386992I-737J1277D01*
G03X384766I-1113J-1927D01*
G02X383292I-737J1277D01*
G03X381124Y901406I-1114J-1927D01*
G01X381066Y901372D01*
G02X379592I-737J1277D01*
G03X377424Y901406I-1114J-1927D01*
G01X377366Y901372D01*
G02X375892I-737J1277D01*
G03X373706Y901396I-1114J-1927D01*
G01X373665Y901372D01*
G02X372191I-737J1277D01*
G03X370007Y901396I-1113J-1927D01*
G01X369966Y901372D01*
G02X368492I-737J1277D01*
G03X366324Y901406I-1114J-1927D01*
G01X366266Y901372D01*
G02X364792I-737J1277D01*
G03X362624Y901406I-1114J-1927D01*
G01X362566Y901372D01*
G02X361092I-737J1277D01*
G03X358866I-1113J-1927D01*
G02X357392I-737J1277D01*
G03X355224Y901406I-1114J-1927D01*
G01X355166Y901372D01*
G02X353692I-737J1277D01*
G03X351524Y901406I-1114J-1927D01*
G01X351466Y901372D01*
G02X349992I-737J1277D01*
G03X347824Y901406I-1114J-1927D01*
G01X347766Y901372D01*
G02X346292I-737J1277D01*
G02X345986Y901606I735J1278D01*
G01X345533Y902059D01*
X342288D01*
X340993Y900764D01*
X331278D01*
X330467Y901575D01*
G01X413629Y909057D02*
X414245Y910124D01*
X414162Y910431D01*
G03X412892Y910334I-534J-1374D01*
G02X410724Y910300I-1115J1928D01*
G01X410666Y910334D01*
G03X409192I-737J-1277D01*
G01X409157Y910314D01*
G03X408454Y909057I772J-1257D01*
G02X407365Y907144I-2225J0D01*
G01X407341Y907130D01*
X407306Y907110D01*
G03X406603Y905853I772J-1257D01*
G01Y905792D01*
G02X405492Y903926I-2225J61D01*
G01X405457Y903906D01*
G03X404754Y902649I772J-1257D01*
G02X403665Y900736I-2225J0D01*
G01X403641Y900722D01*
X403583Y900688D01*
G02X401415Y900722I-1054J1961D01*
G03X399941I-737J-1277D01*
G02X397715I-1113J1927D01*
G03X396241I-737J-1277D01*
G01X396183Y900688D01*
G02X394015Y900722I-1054J1961D01*
G03X392541I-737J-1277D01*
G01X392483Y900688D01*
G02X390315Y900722I-1054J1961D01*
G03X388841I-737J-1277D01*
G01X388800Y900698D01*
G02X386616Y900722I-1071J1951D01*
G03X385142I-737J-1277D01*
G01X385101Y900698D01*
G02X382915Y900722I-1072J1951D01*
G03X381441I-737J-1277D01*
G01X381383Y900688D01*
G02X379215Y900722I-1054J1961D01*
G03X377741I-737J-1277D01*
G01X377683Y900688D01*
G02X375515Y900722I-1054J1961D01*
G03X374041I-737J-1277D01*
G02X371815I-1113J1927D01*
G03X370341I-737J-1277D01*
G01X370283Y900688D01*
G02X368115Y900722I-1054J1961D01*
G03X366641I-737J-1277D01*
G01X366583Y900688D01*
G02X364415Y900722I-1054J1961D01*
G03X362941I-737J-1277D01*
G01X362900Y900698D01*
G02X360716Y900722I-1071J1951D01*
G03X359242I-737J-1277D01*
G01X359201Y900698D01*
G02X357015Y900722I-1072J1951D01*
G03X355541I-737J-1277D01*
G01X355483Y900688D01*
G02X353315Y900722I-1054J1961D01*
G03X351841I-737J-1277D01*
G01X351783Y900688D01*
G02X349615Y900722I-1054J1961D01*
G03X348141I-737J-1277D01*
G01X348100Y900698D01*
G02X345916Y900722I-1071J1951D01*
G03X345179Y900919I-736J-1277D01*
G01X342687D01*
X341487Y899719D01*
X330292D01*
G01X400678Y899445D02*
X401294Y898378D01*
X401211Y898071D01*
G02X399941Y898168I-534J1374D01*
G01X399883Y898202D01*
G03X397715Y898168I-1053J-1962D01*
G02X396241I-737J1277D01*
G01X396183Y898202D01*
G03X394015Y898168I-1053J-1962D01*
G02X392541I-737J1277D01*
G03X390315I-1113J-1928D01*
G02X388841I-737J1277D01*
G01X388800Y898192D01*
G03X386616Y898168I-1071J-1952D01*
G02X385142I-737J1277D01*
G01X385101Y898192D01*
G03X382915Y898168I-1072J-1952D01*
G02X381441I-737J1277D01*
G01X381383Y898202D01*
G03X379215Y898168I-1053J-1962D01*
G02X377741I-737J1277D01*
G01X377683Y898202D01*
G03X375515Y898168I-1053J-1962D01*
G02X374041I-737J1277D01*
G01X373983Y898202D01*
G03X371815Y898168I-1053J-1962D01*
G02X370341I-737J1277D01*
G01X370283Y898202D01*
G03X368115Y898168I-1053J-1962D01*
G02X366641I-737J1277D01*
G01X366583Y898202D01*
G03X364415Y898168I-1053J-1962D01*
G02X362941I-737J1277D01*
G03X360757Y898192I-1113J-1928D01*
G01X360716Y898168D01*
G02X359242I-737J1277D01*
G01X359201Y898192D01*
G03X357015Y898168I-1072J-1952D01*
G02X355541I-737J1277D01*
G01X355483Y898202D01*
G03X353315Y898168I-1053J-1962D01*
G02X351841I-737J1277D01*
G01X351783Y898202D01*
G03X349615Y898168I-1053J-1962D01*
G02X348141I-737J1277D01*
G01X348100Y898192D01*
G03X345916Y898168I-1071J-1952D01*
G02X344442I-737J1277D01*
G01X344393Y898195D01*
X344384Y898200D01*
X343925Y898467D01*
X328202D01*
G01X406229Y909057D02*
X406342Y909253D01*
X406845Y910124D01*
X406762Y910431D01*
G03X405492Y910334I-534J-1374D01*
G01X405457Y910314D01*
G03X404754Y909057I772J-1257D01*
G02X403665Y907144I-2225J0D01*
G01X403641Y907130D01*
X403606Y907110D01*
G03X402903Y905853I772J-1257D01*
G01Y905792D01*
G02X401792Y903926I-2225J61D01*
G02X399606Y903902I-1114J1927D01*
G01X399565Y903926D01*
G03X398091I-737J-1277D01*
G02X395907Y903902I-1113J1927D01*
G01X395866Y903926D01*
G03X394392I-737J-1277D01*
G02X392224Y903892I-1114J1927D01*
G01X392166Y903926D01*
G03X390692I-737J-1277D01*
G02X388524Y903892I-1114J1927D01*
G01X388497Y903908D01*
X388466Y903926D01*
G03X386992I-737J-1277D01*
G02X384824Y903892I-1114J1927D01*
G01X384766Y903926D01*
G03X383292I-737J-1277D01*
G02X381066I-1113J1927D01*
G03X379592I-737J-1277D01*
G02X377424Y903892I-1114J1927D01*
G01X377366Y903926D01*
G03X375892I-737J-1277D01*
G02X373706Y903902I-1114J1927D01*
G01X373665Y903926D01*
G03X372191I-737J-1277D01*
G02X370007Y903902I-1113J1927D01*
G01X369966Y903926D01*
G03X368492I-737J-1277D01*
G02X366324Y903892I-1114J1927D01*
G01X366266Y903926D01*
G03X364792I-737J-1277D01*
G02X362624Y903892I-1114J1927D01*
G01X362566Y903926D01*
G03X361092I-737J-1277D01*
G02X358924Y903892I-1114J1927D01*
G01X358866Y903926D01*
G03X357392I-737J-1277D01*
G02X355166I-1113J1927D01*
G03X353692I-737J-1277D01*
G02X351524Y903892I-1114J1927D01*
G01X351466Y903926D01*
G03X349992I-737J-1277D01*
G02X347824Y903892I-1114J1927D01*
G01X347766Y903926D01*
G03X347029Y904125I-740J-1276D01*
G01X346125D01*
X345119Y903119D01*
X338517D01*
X337372Y904264D01*
X330177D01*
G01X412211Y1054157D02*
X412827Y1055224D01*
X412744Y1055531D01*
G03X411474Y1055434I-534J-1374D01*
G01X411439Y1055414D01*
G03X410736Y1054157I772J-1257D01*
G01Y1054084D01*
G02X409624Y1052229I-2225J73D01*
G03X408887Y1050986I737J-1277D01*
G01Y1050952D01*
G02X407798Y1049039I-2225J0D01*
G01X407774Y1049025D01*
X407739Y1049005D01*
G03X407036Y1047748I772J-1257D01*
G01Y1047687D01*
G02X405925Y1045821I-2225J61D01*
G01X405890Y1045801D01*
G03X405187Y1044544I772J-1257D01*
G02X404098Y1042631I-2225J0D01*
G01X404074Y1042617D01*
X404016Y1042583D01*
G02X401848Y1042617I-1054J1961D01*
G03X400374I-737J-1277D01*
G01X400316Y1042583D01*
G02X398148Y1042617I-1054J1961D01*
G03X396674I-737J-1277D01*
G01X396616Y1042583D01*
G02X394448Y1042617I-1054J1961D01*
G03X392974I-737J-1277D01*
G01X392916Y1042583D01*
G02X390748Y1042617I-1054J1961D01*
G03X389274I-737J-1277D01*
G02X387090Y1042593I-1113J1927D01*
G01X387049Y1042617D01*
G03X385575I-737J-1277D01*
G01X385534Y1042593D01*
G02X383348Y1042617I-1072J1951D01*
G03X381874I-737J-1277D01*
G01X381816Y1042583D01*
G02X379648Y1042617I-1054J1961D01*
G03X378174I-737J-1277D01*
G01X378116Y1042583D01*
G02X375948Y1042617I-1054J1961D01*
G03X374474I-737J-1277D01*
G01X374416Y1042583D01*
G02X372248Y1042617I-1054J1961D01*
G03X370774I-737J-1277D01*
G01X370716Y1042583D01*
G02X368548Y1042617I-1054J1961D01*
G03X367074I-737J-1277D01*
G01X367016Y1042583D01*
G02X364848Y1042617I-1054J1961D01*
G03X363374I-737J-1277D01*
G02X361190Y1042593I-1113J1927D01*
G01X361149Y1042617D01*
G03X359675I-737J-1277D01*
G01X359634Y1042593D01*
G02X357448Y1042617I-1072J1951D01*
G03X355974I-737J-1277D01*
G02X353748I-1113J1927D01*
G03X352274I-737J-1277D01*
G02X350048I-1113J1927D01*
G03X348574I-737J-1277D01*
G02X346348I-1113J1927D01*
G03X344874I-737J-1277D01*
G02X342648I-1113J1927D01*
G03X341911Y1042814I-736J-1277D01*
G01X339296D01*
X338775Y1043335D01*
G01X414062Y1057361D02*
X413446Y1056294D01*
X413095Y1056200D01*
G03X411157Y1056118I-884J-2043D01*
G01X411099Y1056084D01*
X411075Y1056070D01*
G03X409986Y1054157I1136J-1913D01*
G02X409283Y1052900I-1475J0D01*
G01X409248Y1052880D01*
G03X408136Y1051025I1113J-1928D01*
G01Y1050918D01*
G02X407399Y1049675I-1474J34D01*
G01X407375Y1049661D01*
G03X406286Y1047748I1136J-1913D01*
G02X405583Y1046491I-1475J0D01*
G01X405548Y1046471D01*
G03X404437Y1044605I1114J-1927D01*
G01Y1044544D01*
G02X402225Y1043267I-1475J0D01*
G03X400057Y1043301I-1114J-1927D01*
G01X399999Y1043267D01*
G02X398525I-737J1277D01*
G03X396357Y1043301I-1114J-1927D01*
G01X396299Y1043267D01*
G02X394825I-737J1277D01*
G03X392657Y1043301I-1114J-1927D01*
G01X392599Y1043267D01*
G02X391125I-737J1277D01*
G03X388939Y1043291I-1114J-1927D01*
G01X388898Y1043267D01*
G02X387424I-737J1277D01*
G01X387383Y1043291D01*
G03X385199Y1043267I-1071J-1951D01*
G02X383725I-737J1277D01*
G03X381557Y1043301I-1114J-1927D01*
G01X381499Y1043267D01*
G02X380025I-737J1277D01*
G03X377857Y1043301I-1114J-1927D01*
G01X377799Y1043267D01*
G02X376325I-737J1277D01*
G03X374157Y1043301I-1114J-1927D01*
G01X374099Y1043267D01*
G02X372625I-737J1277D01*
G03X370457Y1043301I-1114J-1927D01*
G01X370399Y1043267D01*
G02X368925I-737J1277D01*
G03X366757Y1043301I-1114J-1927D01*
G01X366699Y1043267D01*
G02X365225I-737J1277D01*
G03X363039Y1043291I-1114J-1927D01*
G01X362998Y1043267D01*
G02X361524I-737J1277D01*
G01X361483Y1043291D01*
G03X359299Y1043267I-1071J-1951D01*
G02X357825I-737J1277D01*
G03X355639Y1043291I-1114J-1927D01*
G01X355598Y1043267D01*
G02X354124I-737J1277D01*
G03X351898I-1113J-1927D01*
G02X350424I-737J1277D01*
G03X348198I-1113J-1927D01*
G02X346724I-737J1277D01*
G03X344498I-1113J-1927D01*
G02X343024I-737J1277D01*
G02X342718Y1043501I735J1278D01*
G01X341555Y1044664D01*
G01X414062Y1044544D02*
X412831D01*
X412572Y1044803D01*
G03X411498Y1046457I-2210J-259D01*
G01X411474Y1046472D01*
X411416Y1046506D01*
G03X409248Y1046472I-1053J-1962D01*
G03X408137Y1044547I1112J-1925D01*
G01Y1044544D01*
G02X407434Y1043287I-1475J0D01*
G01X407399Y1043267D01*
X407375Y1043253D01*
G03X406286Y1041340I1136J-1913D01*
G01Y1040586D01*
X405564Y1039864D01*
X404811D01*
G02X404074Y1040063I3J1475D01*
G01X404016Y1040097D01*
G03X401848Y1040063I-1054J-1961D01*
G02X400374I-737J1277D01*
G03X398148I-1113J-1927D01*
G02X396674I-737J1277D01*
G01X396616Y1040097D01*
G03X394448Y1040063I-1054J-1961D01*
G02X392974I-737J1277D01*
G01X392916Y1040097D01*
G03X390748Y1040063I-1054J-1961D01*
G02X389274I-737J1277D01*
G01X389233Y1040087D01*
G03X387049Y1040063I-1071J-1951D01*
G02X385575I-737J1277D01*
G01X385534Y1040087D01*
G03X383348Y1040063I-1072J-1951D01*
G02X381874I-737J1277D01*
G01X381816Y1040097D01*
G03X379648Y1040063I-1054J-1961D01*
G02X378174I-737J1277D01*
G01X378116Y1040097D01*
G03X375948Y1040063I-1054J-1961D01*
G02X374474I-737J1277D01*
G03X372248I-1113J-1927D01*
G02X370774I-737J1277D01*
G01X370716Y1040097D01*
G03X368548Y1040063I-1054J-1961D01*
G02X367074I-737J1277D01*
G01X367016Y1040097D01*
G03X364848Y1040063I-1054J-1961D01*
G02X363374I-737J1277D01*
G01X363333Y1040087D01*
G03X361149Y1040063I-1071J-1951D01*
G02X359675I-737J1277D01*
G01X359634Y1040087D01*
G03X357448Y1040063I-1072J-1951D01*
G02X355974I-737J1277D01*
G03X353748I-1113J-1927D01*
G02X352274I-737J1277D01*
G03X350048I-1113J-1927D01*
G02X348574I-737J1277D01*
G03X346348I-1113J-1927D01*
G02X345611Y1039864I-740J1276D01*
G01X340927D01*
X340578Y1039515D01*
X339847D01*
G01X402962Y1070178D02*
X404193D01*
X404419Y1069952D01*
G02X403734Y1068921I-1458J225D01*
G01X403699Y1068901D01*
G02X402225I-737J1277D01*
G03X399999I-1113J-1927D01*
G02X398525I-737J1277D01*
G03X396299I-1113J-1927D01*
G02X394825I-737J1277D01*
G03X392657Y1068935I-1114J-1927D01*
G01X392599Y1068901D01*
G02X391125I-737J1277D01*
G03X388957Y1068935I-1114J-1927D01*
G01X388899Y1068901D01*
G02X387425I-737J1277D01*
G03X385239Y1068925I-1114J-1927D01*
G01X385198Y1068901D01*
G02X383724I-737J1277D01*
G03X381540Y1068925I-1113J-1927D01*
G01X381499Y1068901D01*
G02X380025I-737J1277D01*
G03X377857Y1068935I-1114J-1927D01*
G01X377799Y1068901D01*
G02X376325I-737J1277D01*
G03X374157Y1068935I-1114J-1927D01*
G01X374099Y1068901D01*
G02X372625I-737J1277D01*
G03X370399I-1113J-1927D01*
G02X368925I-737J1277D01*
G03X366757Y1068935I-1114J-1927D01*
G01X366699Y1068901D01*
G02X365225I-737J1277D01*
G03X363057Y1068935I-1114J-1927D01*
G01X362999Y1068901D01*
G02X361525I-737J1277D01*
G03X359339Y1068925I-1114J-1927D01*
G01X359298Y1068901D01*
G02X357824I-737J1277D01*
G03X355598I-1113J-1927D01*
G02X354124I-737J1277D01*
G03X351940Y1068925I-1113J-1927D01*
G01X351899Y1068901D01*
G02X350425I-737J1277D01*
G03X348239Y1068925I-1114J-1927D01*
G01X348198Y1068901D01*
G02X346724I-737J1277D01*
G03X344498I-1113J-1927D01*
G02X343761Y1068702I-740J1276D01*
G01X343100D01*
X342978Y1068824D01*
X341819D01*
G01X406662Y1070178D02*
X405431D01*
X405172Y1069919D01*
G02X404098Y1068265I-2210J259D01*
G01X404074Y1068251D01*
X404033Y1068227D01*
G02X401849Y1068251I-1071J1951D01*
G03X400375I-737J-1277D01*
G02X398149I-1113J1927D01*
G03X396675I-737J-1277D01*
G01X396634Y1068227D01*
G02X394448Y1068251I-1072J1951D01*
G03X392974I-737J-1277D01*
G01X392916Y1068217D01*
G02X390748Y1068251I-1054J1961D01*
G03X389274I-737J-1277D01*
G01X389216Y1068217D01*
G02X387048Y1068251I-1054J1961D01*
G03X385574I-737J-1277D01*
G02X383348I-1113J1927D01*
G03X381874I-737J-1277D01*
G01X381816Y1068217D01*
G02X379648Y1068251I-1054J1961D01*
G03X378174I-737J-1277D01*
G01X378116Y1068217D01*
G02X375948Y1068251I-1054J1961D01*
G03X374474I-737J-1277D01*
G01X374433Y1068227D01*
G02X372249Y1068251I-1071J1951D01*
G03X370775I-737J-1277D01*
G01X370734Y1068227D01*
G02X368548Y1068251I-1072J1951D01*
G03X367074I-737J-1277D01*
G01X367016Y1068217D01*
G02X364848Y1068251I-1054J1961D01*
G03X363374I-737J-1277D01*
G01X363316Y1068217D01*
G02X361148Y1068251I-1054J1961D01*
G03X359674I-737J-1277D01*
G02X357448I-1113J1927D01*
G03X355974I-737J-1277D01*
G02X353748I-1113J1927D01*
G03X352274I-737J-1277D01*
G01X352216Y1068217D01*
G02X350048Y1068251I-1054J1961D01*
G03X348574I-737J-1277D01*
G02X346348I-1113J1927D01*
G03X344874I-737J-1277D01*
G02X343761Y1067953I-1112J1927D01*
G01X343215D01*
X342617Y1067355D01*
X341555D01*
X341546Y1067364D01*
G01X417329Y909057D02*
X416713Y907990D01*
X416362Y907896D01*
G03X414424Y907814I-884J-2043D01*
G01X414366Y907780D01*
G02X412892I-737J1277D01*
G03X410724Y907814I-1114J-1927D01*
G01X410666Y907780D01*
X410642Y907766D01*
G03X409553Y905853I1136J-1913D01*
G02X408850Y904596I-1475J0D01*
G01X408815Y904576D01*
G03X407704Y902710I1114J-1927D01*
G01Y902649D01*
G02X407001Y901392I-1475J0D01*
G01X406966Y901372D01*
X406942Y901358D01*
G03X405853Y899445I1136J-1913D01*
G02X405150Y898188I-1475J0D01*
G01X405115Y898168D01*
G03X404004Y896327I1114J-1928D01*
G01Y896240D01*
G02X403301Y894983I-1475J0D01*
G01X403266Y894963D01*
X403242Y894949D01*
G03X402153Y893036I1136J-1913D01*
G02X401450Y891779I-1475J0D01*
G01X401415Y891759D01*
G02X399941I-737J1277D01*
G01X399900Y891783D01*
G03X397716Y891759I-1071J-1951D01*
G02X396242I-737J1277D01*
G03X394016I-1113J-1927D01*
G02X392542I-737J1277D01*
G03X390316I-1113J-1927D01*
G02X388842I-737J1277D01*
G01X388801Y891783D01*
G03X386615Y891759I-1072J-1951D01*
G02X385141I-737J1277D01*
G01X385083Y891793D01*
G03X382915Y891759I-1054J-1961D01*
G02X381441I-737J1277D01*
G01X381400Y891783D01*
G03X379216Y891759I-1071J-1951D01*
G02X377742I-737J1277D01*
G01X377701Y891783D01*
G03X375515Y891759I-1072J-1951D01*
G02X374041I-737J1277D01*
G01X373983Y891793D01*
G03X371815Y891759I-1054J-1961D01*
G02X370341I-737J1277D01*
G01X370300Y891783D01*
G03X368116Y891759I-1071J-1951D01*
G02X366642I-737J1277D01*
G03X364416I-1113J-1927D01*
G02X362942I-737J1277D01*
G03X360716I-1113J-1927D01*
G02X359242I-737J1277D01*
G03X357056Y891783I-1114J-1927D01*
G01X357015Y891759D01*
G02X355541I-737J1277D01*
G01X355483Y891793D01*
G03X353315Y891759I-1054J-1961D01*
G02X351841I-737J1277D01*
G01X351783Y891793D01*
G03X349615Y891759I-1054J-1961D01*
G02X348141I-737J1277D01*
G01X348100Y891783D01*
G03X345916Y891759I-1071J-1951D01*
G02X344442I-737J1277D01*
G03X342256Y891783I-1114J-1927D01*
G01X342215Y891759D01*
G02X340741I-737J1277D01*
G01X340700Y891783D01*
G03X338516Y891759I-1071J-1951D01*
G02X337042I-737J1277D01*
G03X334856Y891783I-1114J-1927D01*
G01X334815Y891759D01*
G02X334078Y891562I-736J1277D01*
G01X331603D01*
G01X402529Y896240D02*
X401913Y897307D01*
X401562Y897401D01*
G02X399624Y897483I-884J2044D01*
G01X399566Y897517D01*
G03X398092I-737J-1277D01*
G02X395924Y897483I-1115J1928D01*
G01X395866Y897517D01*
G03X394392I-737J-1277D01*
G02X392206Y897493I-1114J1928D01*
G01X392165Y897517D01*
G03X390691I-737J-1277D01*
G02X388507Y897493I-1113J1928D01*
G01X388497Y897499D01*
X388466Y897517D01*
G03X386992I-737J-1277D01*
G02X384766I-1113J1928D01*
G03X383292I-737J-1277D01*
G02X381124Y897483I-1115J1928D01*
G01X381066Y897517D01*
G03X379592I-737J-1277D01*
G02X377424Y897483I-1115J1928D01*
G01X377366Y897517D01*
G03X375892I-737J-1277D01*
G02X373724Y897483I-1115J1928D01*
G01X373666Y897517D01*
G03X372192I-737J-1277D01*
G02X370024Y897483I-1115J1928D01*
G01X369966Y897517D01*
G03X368492I-737J-1277D01*
G02X366324Y897483I-1115J1928D01*
G01X366266Y897517D01*
G03X364792I-737J-1277D01*
G02X362606Y897493I-1114J1928D01*
G01X362565Y897517D01*
G03X361091I-737J-1277D01*
G01X361050Y897493D01*
G02X358866Y897517I-1071J1952D01*
G03X357392I-737J-1277D01*
G02X355224Y897483I-1115J1928D01*
G01X355166Y897517D01*
G03X353692I-737J-1277D01*
G02X351524Y897483I-1115J1928D01*
G01X351466Y897517D01*
G03X349992I-737J-1277D01*
G02X347824Y897483I-1115J1928D01*
G01X347766Y897517D01*
G03X346292I-737J-1277D01*
G01X346251Y897493D01*
G02X344065Y897517I-1072J1952D01*
G03X343327Y897718I-744J-1275D01*
G01X330200D01*
X327946Y895464D01*
G01X432129Y921875D02*
G03X430667Y921478I0J-2890D01*
G01X429166Y920598D01*
G03X428053Y918726I1112J-1928D01*
G01Y918670D01*
G02X427350Y917413I-1475J0D01*
G01X427315Y917393D01*
G03X426204Y915527I1114J-1927D01*
G01Y915466D01*
G02X425501Y914209I-1475J0D01*
G01X425466Y914189D01*
X425442Y914175D01*
G02X424173Y913832I-1269J2175D01*
G01X422800D01*
G03X421417Y913259I0J-1956D01*
G01X421002Y912844D01*
G03X420714Y912149I695J-695D01*
G02X419729Y910524I-1833J0D01*
G03X418804Y909057I701J-1467D01*
G02X418101Y907800I-1475J0D01*
G01X418066Y907780D01*
X418018Y907752D01*
G03X416953Y905853I1161J-1899D01*
G02X416250Y904596I-1475J0D01*
G01X416215Y904576D01*
G02X414741I-737J1277D01*
G01X414683Y904610D01*
G03X412515Y904576I-1054J-1961D01*
G03X411404Y902710I1114J-1927D01*
G01Y902649D01*
G02X410701Y901392I-1475J0D01*
G01X410666Y901372D01*
X410642Y901358D01*
G03X409553Y899445I1136J-1913D01*
G02X408850Y898188I-1475J0D01*
G01X408815Y898168D01*
G03X407704Y896327I1114J-1928D01*
G01Y896240D01*
G02X407001Y894983I-1475J0D01*
G01X406966Y894963D01*
X406918Y894935D01*
G03X405853Y893036I1161J-1899D01*
G02X405150Y891779I-1475J0D01*
G01X405115Y891759D01*
G03X404004Y889893I1114J-1927D01*
G01Y889832D01*
G02X403301Y888575I-1475J0D01*
G01X403266Y888555D01*
G02X401792I-737J1277D01*
G03X399624Y888589I-1115J-1928D01*
G01X399566Y888555D01*
G02X398092I-737J1277D01*
G03X395924Y888589I-1115J-1928D01*
G01X395866Y888555D01*
G02X394392I-737J1277D01*
G03X392224Y888589I-1115J-1928D01*
G01X392166Y888555D01*
G02X390692I-737J1277D01*
G03X388524Y888589I-1115J-1928D01*
G01X388497Y888573D01*
X388466Y888555D01*
G02X386992I-737J1277D01*
G03X384824Y888589I-1115J-1928D01*
G01X384766Y888555D01*
G02X383292I-737J1277D01*
G03X381124Y888589I-1115J-1928D01*
G01X381066Y888555D01*
G02X379592I-737J1277D01*
G03X377424Y888589I-1115J-1928D01*
G01X377366Y888555D01*
G02X375892I-737J1277D01*
G03X373724Y888589I-1115J-1928D01*
G01X373666Y888555D01*
G02X372192I-737J1277D01*
G03X370024Y888589I-1115J-1928D01*
G01X369966Y888555D01*
G02X368492I-737J1277D01*
G03X366324Y888589I-1115J-1928D01*
G01X366266Y888555D01*
G02X364792I-737J1277D01*
G03X362624Y888589I-1115J-1928D01*
G01X362566Y888555D01*
G02X361092I-737J1277D01*
G03X358906Y888579I-1114J-1928D01*
G01X358865Y888555D01*
G02X357391I-737J1277D01*
G03X355207Y888579I-1113J-1928D01*
G01X355166Y888555D01*
G02X353692I-737J1277D01*
G03X351524Y888589I-1115J-1928D01*
G01X351466Y888555D01*
G03X350353Y886683I1112J-1928D01*
G01Y886593D01*
G02X349616Y885350I-1474J34D01*
G02X348142I-737J1277D01*
G03X345916I-1113J-1927D01*
G02X344442I-737J1277D01*
G03X342216I-1113J-1927D01*
G02X340742I-737J1277D01*
G03X338516I-1113J-1927D01*
G02X337042I-737J1277D01*
G03X334874Y885384I-1114J-1927D01*
G01X334816Y885350D01*
G02X334079Y885151I-740J1276D01*
G01X328733D01*
G01X421029Y909057D02*
X419024Y907616D01*
G02X418442Y907130I-1696J1440D01*
G01X418407Y907110D01*
G03X417704Y905853I772J-1257D01*
G02X416616Y903940I-2226J0D01*
G01X416592Y903926D01*
G02X414424Y903892I-1114J1927D01*
G01X414366Y903926D01*
G03X412892I-737J-1277D01*
G01X412857Y903906D01*
G03X412154Y902649I772J-1257D01*
G02X411065Y900736I-2225J0D01*
G01X411041Y900722D01*
X411006Y900702D01*
G03X410303Y899445I772J-1257D01*
G01Y899358D01*
G02X409192Y897517I-2225J87D01*
G01X409157Y897497D01*
G03X408454Y896240I772J-1257D01*
G01Y896201D01*
G02X407342Y894313I-2225J39D01*
G01X407307Y894293D01*
G03X406604Y893036I772J-1257D01*
G02X405516Y891123I-2226J0D01*
G01X405492Y891109D01*
X405457Y891089D01*
G03X404754Y889832I772J-1257D01*
G01Y889776D01*
G02X403641Y887904I-2225J56D01*
G01X403583Y887870D01*
G02X401415Y887904I-1053J1962D01*
G03X399941I-737J-1277D01*
G01X399883Y887870D01*
G02X397715Y887904I-1053J1962D01*
G03X396241I-737J-1277D01*
G01X396183Y887870D01*
G02X394015Y887904I-1053J1962D01*
G03X392541I-737J-1277D01*
G01X392483Y887870D01*
G02X390315Y887904I-1053J1962D01*
G03X388841I-737J-1277D01*
G01X388783Y887870D01*
G02X386615Y887904I-1053J1962D01*
G03X385141I-737J-1277D01*
G01X385083Y887870D01*
G02X382915Y887904I-1053J1962D01*
G03X381441I-737J-1277D01*
G01X381383Y887870D01*
G02X379215Y887904I-1053J1962D01*
G03X377741I-737J-1277D01*
G01X377683Y887870D01*
G02X375515Y887904I-1053J1962D01*
G03X374041I-737J-1277D01*
G01X373983Y887870D01*
G02X371815Y887904I-1053J1962D01*
G03X370341I-737J-1277D01*
G01X370283Y887870D01*
G02X368115Y887904I-1053J1962D01*
G03X366641I-737J-1277D01*
G01X366583Y887870D01*
G02X364415Y887904I-1053J1962D01*
G03X362941I-737J-1277D01*
G01X362883Y887870D01*
G02X360715Y887904I-1053J1962D01*
G03X359241I-737J-1277D01*
G02X357015I-1113J1928D01*
G03X355541I-737J-1277D01*
G01X355483Y887870D01*
G02X353315Y887904I-1053J1962D01*
G03X351841I-737J-1277D01*
G03X351104Y886661I737J-1277D01*
G01Y886588D01*
G02X349992Y884700I-2225J39D01*
G02X347766I-1113J1927D01*
G03X346292I-737J-1277D01*
G02X344066I-1113J1927D01*
G03X342592I-737J-1277D01*
G02X340366I-1113J1927D01*
G03X338892I-737J-1277D01*
G01X338851Y884676D01*
G02X336665Y884700I-1072J1951D01*
G03X335191I-737J-1277D01*
G02X333564Y884264I-1627J2818D01*
G01X331746D01*
G01X398829Y896240D02*
X399445Y895173D01*
X399362Y894866D01*
G02X398092Y894963I-534J1374D01*
G03X395924Y894997I-1114J-1927D01*
G01X395866Y894963D01*
G02X394392I-737J1277D01*
G03X392206Y894987I-1114J-1927D01*
G01X392165Y894963D01*
G02X390691I-737J1277D01*
G01X390650Y894987D01*
G03X388466Y894963I-1071J-1951D01*
G02X386992I-737J1277D01*
G03X384824Y894997I-1114J-1927D01*
G01X384766Y894963D01*
G02X383292I-737J1277D01*
G03X381124Y894997I-1114J-1927D01*
G01X381066Y894963D01*
G02X379592I-737J1277D01*
G03X377366I-1113J-1927D01*
G02X375892I-737J1277D01*
G03X373724Y894997I-1114J-1927D01*
G01X373666Y894963D01*
G02X372192I-737J1277D01*
G03X370024Y894997I-1114J-1927D01*
G01X369966Y894963D01*
G02X368492I-737J1277D01*
G03X366324Y894997I-1114J-1927D01*
G01X366266Y894963D01*
G02X364792I-737J1277D01*
G03X362606Y894987I-1114J-1927D01*
G01X362565Y894963D01*
G02X361091I-737J1277D01*
G01X361050Y894987D01*
G03X358866Y894963I-1071J-1951D01*
G02X357392I-737J1277D01*
G03X355224Y894997I-1114J-1927D01*
G01X355166Y894963D01*
G02X353692I-737J1277D01*
G03X351524Y894997I-1114J-1927D01*
G01X351466Y894963D01*
G02X349992I-737J1277D01*
G03X347824Y894997I-1114J-1927D01*
G01X347766Y894963D01*
G02X346292I-737J1277D01*
G01X346251Y894987D01*
G03X344065Y894963I-1072J-1951D01*
G02X342591I-737J1277D01*
G03X340407Y894987I-1113J-1927D01*
G01X340366Y894963D01*
G02X338892I-737J1277D01*
G01X338851Y894987D01*
G03X336665Y894963I-1072J-1951D01*
G02X335191I-737J1277D01*
G02X334885Y895197I735J1278D01*
G01X334763Y895319D01*
X329995D01*
X328524Y893848D01*
G01X400678Y893036D02*
X400062Y894103D01*
X399712Y894196D01*
G02X397715Y894313I-882J2044D01*
G03X396241I-737J-1277D01*
G01X396183Y894279D01*
G02X394015Y894313I-1054J1961D01*
G03X392541I-737J-1277D01*
G02X390357Y894289I-1113J1927D01*
G01X390316Y894313D01*
G03X388842I-737J-1277D01*
G01X388801Y894289D01*
G02X386615Y894313I-1072J1951D01*
G03X385141I-737J-1277D01*
G01X385083Y894279D01*
G02X382915Y894313I-1054J1961D01*
G03X381441I-737J-1277D01*
G01X381400Y894289D01*
G02X379216Y894313I-1071J1951D01*
G03X377742I-737J-1277D01*
G01X377701Y894289D01*
G02X375515Y894313I-1072J1951D01*
G03X374041I-737J-1277D01*
G01X373983Y894279D01*
G02X371815Y894313I-1054J1961D01*
G03X370341I-737J-1277D01*
G01X370283Y894279D01*
G02X368115Y894313I-1054J1961D01*
G03X366641I-737J-1277D01*
G01X366583Y894279D01*
G02X364415Y894313I-1054J1961D01*
G03X362941I-737J-1277D01*
G02X360757Y894289I-1113J1927D01*
G01X360716Y894313D01*
G03X359242I-737J-1277D01*
G01X359201Y894289D01*
G02X357015Y894313I-1072J1951D01*
G03X355541I-737J-1277D01*
G01X355483Y894279D01*
G02X353315Y894313I-1054J1961D01*
G03X351841I-737J-1277D01*
G01X351783Y894279D01*
G02X349615Y894313I-1054J1961D01*
G03X348141I-737J-1277D01*
G01X348100Y894289D01*
G02X345916Y894313I-1071J1951D01*
G03X344442I-737J-1277D01*
G02X342256Y894289I-1114J1927D01*
G01X342215Y894313D01*
G03X340741I-737J-1277D01*
G01X340700Y894289D01*
G02X338516Y894313I-1071J1951D01*
G03X337042I-737J-1277D01*
G02X334856Y894289I-1114J1927D01*
G01X334815Y894313D01*
G03X334078Y894510I-736J-1277D01*
G01X331348D01*
X329440Y892602D01*
G01X433979Y918670D02*
X434595Y919737D01*
X434512Y920044D01*
G03X433242Y919947I-534J-1374D01*
G01X433207Y919927D01*
G03X432504Y918670I772J-1257D01*
G02X431416Y916757I-2226J0D01*
G01X431392Y916743D01*
X431357Y916723D01*
G03X430654Y915466I772J-1257D01*
G02X429565Y913553I-2225J0D01*
G01X429541Y913539D01*
X429506Y913519D01*
G03X428803Y912262I772J-1257D01*
G01Y912175D01*
G02X427692Y910334I-2225J87D01*
G02X425464I-1114J1928D01*
G03X423990I-737J-1277D01*
G03X423253Y909091I737J-1277D01*
G01Y908996D01*
G02X422141Y907130I-2224J61D01*
G03X421404Y905887I737J-1277D01*
G01Y905814D01*
G02X420292Y903926I-2225J39D01*
G01X420257Y903906D01*
G03X419554Y902649I772J-1257D01*
G02X418465Y900736I-2225J0D01*
G01X418441Y900722D01*
X418383Y900688D01*
G02X416215Y900722I-1054J1961D01*
G03X414741I-737J-1277D01*
G01X414706Y900702D01*
G03X414003Y899445I772J-1257D01*
G01Y899358D01*
G02X412892Y897517I-2225J87D01*
G01X412857Y897497D01*
G03X412154Y896240I772J-1257D01*
G01Y896201D01*
G02X411042Y894313I-2225J39D01*
G01X411007Y894293D01*
G03X410304Y893036I772J-1257D01*
G01Y892997D01*
G02X409192Y891109I-2225J39D01*
G01X409157Y891089D01*
G03X408454Y889832I772J-1257D01*
G01Y889776D01*
G02X407341Y887904I-2225J56D01*
G01X407306Y887884D01*
G03X406603Y886627I772J-1257D01*
G01Y886566D01*
G02X405492Y884700I-2225J61D01*
G01X405457Y884680D01*
G03X404754Y883423I772J-1257D01*
G01Y883384D01*
G02X403642Y881496I-2225J39D01*
G01X403601Y881472D01*
G02X401415Y881496I-1072J1951D01*
G02X400304Y883362I1114J1927D01*
G01Y883423D01*
G03X399601Y884680I-1475J0D01*
G01X399566Y884700D01*
G03X398092I-737J-1277D01*
G01X398057Y884680D01*
G03X397354Y883423I772J-1257D01*
G01Y883384D01*
G02X396242Y881496I-2225J39D01*
G01X396201Y881472D01*
G02X394015Y881496I-1072J1951D01*
G02X392904Y883362I1114J1927D01*
G01Y883423D01*
G03X392201Y884680I-1475J0D01*
G01X392166Y884700D01*
G03X390692I-737J-1277D01*
G01X390657Y884680D01*
G03X389954Y883423I772J-1257D01*
G01Y883384D01*
G02X388842Y881496I-2225J39D01*
G01X388801Y881472D01*
G02X386615Y881496I-1072J1951D01*
G02X385504Y883362I1114J1927D01*
G01Y883423D01*
G03X384801Y884680I-1475J0D01*
G01X384766Y884700D01*
G03X383292I-737J-1277D01*
G01X383257Y884680D01*
G03X382554Y883423I772J-1257D01*
G01Y883384D01*
G02X381442Y881496I-2225J39D01*
G01X381401Y881472D01*
G02X379215Y881496I-1072J1951D01*
G02X378104Y883362I1114J1927D01*
G01Y883423D01*
G03X377401Y884680I-1475J0D01*
G01X377366Y884700D01*
G03X375892I-737J-1277D01*
G01X375857Y884680D01*
G03X375154Y883423I772J-1257D01*
G01Y883384D01*
G02X374042Y881496I-2225J39D01*
G01X374001Y881472D01*
G02X371815Y881496I-1072J1951D01*
G02X370704Y883362I1114J1927D01*
G01Y883423D01*
G03X370001Y884680I-1475J0D01*
G01X369966Y884700D01*
G03X368492I-737J-1277D01*
G01X368457Y884680D01*
G03X367754Y883423I772J-1257D01*
G01Y883384D01*
G02X366642Y881496I-2225J39D01*
G01X366601Y881472D01*
G02X364415Y881496I-1072J1951D01*
G02X363304Y883362I1114J1927D01*
G01Y883423D01*
G03X362601Y884680I-1475J0D01*
G01X362566Y884700D01*
G03X361092I-737J-1277D01*
G01X361057Y884680D01*
G03X360354Y883423I772J-1257D01*
G01Y883384D01*
G02X359242Y881496I-2225J39D01*
G01X359201Y881472D01*
G02X357015Y881496I-1072J1951D01*
G02X355904Y883362I1114J1927D01*
G01Y883423D01*
G03X355201Y884680I-1475J0D01*
G01X355166Y884700D01*
G03X353692I-737J-1277D01*
G01X353657Y884680D01*
G03X352954Y883423I772J-1257D01*
G01Y883384D01*
G02X351842Y881496I-2225J39D01*
G01X351801Y881472D01*
G02X349615Y881496I-1072J1951D01*
G03X348141I-737J-1277D01*
G01X348100Y881472D01*
G02X345916Y881496I-1071J1951D01*
G03X344442I-737J-1277D01*
G02X342216I-1113J1927D01*
G03X340742I-737J-1277D01*
G02X338516I-1113J1927D01*
G03X337042I-737J-1277D01*
G02X334874Y881462I-1114J1927D01*
G01X334816Y881496D01*
G03X334079Y881695I-740J-1276D01*
G01X333302D01*
X331318Y879711D01*
G01X435829Y921875D02*
X435213Y920808D01*
X434862Y920714D01*
G03X432866Y920598I-883J-2044D01*
G03X431753Y918700I1113J-1928D01*
G01Y918670D01*
G02X431050Y917413I-1475J0D01*
G01X431015Y917393D01*
G03X429904Y915527I1114J-1927D01*
G01Y915466D01*
G02X429201Y914209I-1475J0D01*
G01X429166Y914189D01*
X429142Y914175D01*
G03X428053Y912262I1136J-1913D01*
G02X427350Y911005I-1475J0D01*
G01X427315Y910985D01*
G02X425841I-737J1277D01*
G03X423673Y911019I-1115J-1928D01*
G01X423615Y910985D01*
G03X422503Y909144I1112J-1928D01*
G01Y909023D01*
G02X421766Y907780I-1474J34D01*
G01X421742Y907766D01*
G03X420653Y905853I1136J-1913D01*
G01Y905819D01*
G02X419916Y904576I-1474J34D01*
G03X418804Y902688I1113J-1927D01*
G01Y902649D01*
G02X418101Y901392I-1475J0D01*
G01X418066Y901372D01*
G02X416592I-737J1277D01*
G03X414424Y901406I-1114J-1927D01*
G01X414366Y901372D01*
X414342Y901358D01*
G03X413253Y899445I1136J-1913D01*
G02X412550Y898188I-1475J0D01*
G01X412515Y898168D01*
G03X411404Y896327I1114J-1928D01*
G01Y896240D01*
G02X410701Y894983I-1475J0D01*
G01X410666Y894963D01*
G03X409554Y893075I1113J-1927D01*
G01Y893036D01*
G02X408851Y891779I-1475J0D01*
G01X408816Y891759D01*
G03X407704Y889871I1113J-1927D01*
G01Y889832D01*
G02X407001Y888575I-1475J0D01*
G01X406966Y888555D01*
G03X405853Y886683I1112J-1928D01*
G01Y886627D01*
G02X405150Y885370I-1475J0D01*
G01X405115Y885350D01*
G03X404004Y883484I1114J-1927D01*
G01Y883423D01*
G02X403301Y882166I-1475J0D01*
G01X403266Y882146D01*
G02X401792I-737J1277D01*
G01X401757Y882166D01*
G02X401054Y883423I772J1257D01*
G03X399965Y885336I-2225J0D01*
G01X399941Y885350D01*
X399883Y885384D01*
G03X397715Y885350I-1054J-1961D01*
G03X396604Y883484I1114J-1927D01*
G01Y883423D01*
G02X395901Y882166I-1475J0D01*
G01X395866Y882146D01*
G02X394392I-737J1277D01*
G01X394357Y882166D01*
G02X393654Y883423I772J1257D01*
G03X392565Y885336I-2225J0D01*
G01X392541Y885350D01*
X392483Y885384D01*
G03X390315Y885350I-1054J-1961D01*
G03X389204Y883484I1114J-1927D01*
G01Y883423D01*
G02X388501Y882166I-1475J0D01*
G01X388497Y882164D01*
X388466Y882146D01*
G02X386992I-737J1277D01*
G01X386957Y882166D01*
G02X386254Y883423I772J1257D01*
G03X385165Y885336I-2225J0D01*
G01X385141Y885350D01*
X385083Y885384D01*
G03X382915Y885350I-1054J-1961D01*
G03X381804Y883484I1114J-1927D01*
G01Y883423D01*
G02X381101Y882166I-1475J0D01*
G01X381066Y882146D01*
G02X379592I-737J1277D01*
G01X379557Y882166D01*
G02X378854Y883423I772J1257D01*
G03X377765Y885336I-2225J0D01*
G01X377741Y885350D01*
X377683Y885384D01*
G03X375515Y885350I-1054J-1961D01*
G03X374404Y883484I1114J-1927D01*
G01Y883423D01*
G02X373701Y882166I-1475J0D01*
G01X373666Y882146D01*
G02X372192I-737J1277D01*
G01X372157Y882166D01*
G02X371454Y883423I772J1257D01*
G03X370365Y885336I-2225J0D01*
G01X370341Y885350D01*
X370283Y885384D01*
G03X368115Y885350I-1054J-1961D01*
G03X367004Y883484I1114J-1927D01*
G01Y883423D01*
G02X366301Y882166I-1475J0D01*
G01X366266Y882146D01*
G02X364792I-737J1277D01*
G01X364757Y882166D01*
G02X364054Y883423I772J1257D01*
G03X362965Y885336I-2225J0D01*
G01X362941Y885350D01*
X362883Y885384D01*
G03X360715Y885350I-1054J-1961D01*
G03X359604Y883484I1114J-1927D01*
G01Y883423D01*
G02X358901Y882166I-1475J0D01*
G01X358866Y882146D01*
G02X357392I-737J1277D01*
G01X357357Y882166D01*
G02X356654Y883423I772J1257D01*
G03X355565Y885336I-2225J0D01*
G01X355541Y885350D01*
X355483Y885384D01*
G03X353315Y885350I-1054J-1961D01*
G03X352204Y883484I1114J-1927D01*
G01Y883423D01*
G02X351501Y882166I-1475J0D01*
G01X351466Y882146D01*
G02X349992I-737J1277D01*
G03X347824Y882180I-1114J-1927D01*
G01X347766Y882146D01*
G02X346292I-737J1277D01*
G03X344066I-1113J-1927D01*
G02X342592I-737J1277D01*
G03X340366I-1113J-1927D01*
G02X338892I-737J1277D01*
G01X338851Y882170D01*
G03X336665Y882146I-1072J-1951D01*
G02X335191I-737J1277D01*
G03X334223Y882440I-1114J-1926D01*
G03X334080Y882444I-134J-2221D01*
G01X331753D01*
G01X408078Y912262D02*
X407462Y911195D01*
X407112Y911102D01*
G03X405115Y910985I-882J-2045D01*
G03X404004Y909144I1114J-1928D01*
G01Y909057D01*
G02X403301Y907800I-1475J0D01*
G01X403266Y907780D01*
X403242Y907766D01*
G03X402153Y905853I1136J-1913D01*
G02X401450Y904596I-1475J0D01*
G01X401415Y904576D01*
G02X399941I-737J1277D01*
G03X397715I-1113J-1927D01*
G02X396241I-737J1277D01*
G01X396183Y904610D01*
G03X394015Y904576I-1054J-1961D01*
G02X392541I-737J1277D01*
G01X392483Y904610D01*
G03X390315Y904576I-1054J-1961D01*
G02X388841I-737J1277D01*
G01X388783Y904610D01*
G03X386615Y904576I-1054J-1961D01*
G02X385141I-737J1277D01*
G01X385100Y904600D01*
G03X382916Y904576I-1071J-1951D01*
G02X381442I-737J1277D01*
G01X381401Y904600D01*
G03X379215Y904576I-1072J-1951D01*
G02X377741I-737J1277D01*
G01X377683Y904610D01*
G03X375515Y904576I-1054J-1961D01*
G02X374041I-737J1277D01*
G03X371815I-1113J-1927D01*
G02X370341I-737J1277D01*
G01X370283Y904610D01*
G03X368115Y904576I-1054J-1961D01*
G02X366641I-737J1277D01*
G01X366583Y904610D01*
G03X364415Y904576I-1054J-1961D01*
G02X362941I-737J1277D01*
G01X362883Y904610D01*
G03X360715Y904576I-1054J-1961D01*
G02X359241I-737J1277D01*
G01X359200Y904600D01*
G03X357016Y904576I-1071J-1951D01*
G02X355542I-737J1277D01*
G01X355501Y904600D01*
G03X353315Y904576I-1072J-1951D01*
G02X351841I-737J1277D01*
G01X351783Y904610D01*
G03X349615Y904576I-1054J-1961D01*
G02X348141I-737J1277D01*
G03X347029Y904874I-1112J-1926D01*
G01X345474D01*
X344626Y904026D01*
X339109D01*
X337571Y905564D01*
G01X330008Y907464D02*
X344672D01*
X345304Y906832D01*
X347030D01*
G03X347173Y906836I9J2225D01*
G03X348141Y907130I-146J2220D01*
G02X349615I737J-1277D01*
G03X351783Y907096I1114J1927D01*
G01X351841Y907130D01*
G02X353315I737J-1277D01*
G03X355501Y907106I1114J1927D01*
G01X355542Y907130D01*
G02X357016I737J-1277D01*
G01X357057Y907106D01*
G03X359241Y907130I1071J1951D01*
G02X360715I737J-1277D01*
G03X362883Y907096I1114J1927D01*
G01X362941Y907130D01*
G02X364415I737J-1277D01*
G03X366583Y907096I1114J1927D01*
G01X366641Y907130D01*
G02X368115I737J-1277D01*
G03X370283Y907096I1114J1927D01*
G01X370341Y907130D01*
G02X371815I737J-1277D01*
G03X373983Y907096I1114J1927D01*
G01X374041Y907130D01*
G02X375515I737J-1277D01*
G03X377683Y907096I1114J1927D01*
G01X377741Y907130D01*
G02X379215I737J-1277D01*
G03X381401Y907106I1114J1927D01*
G01X381442Y907130D01*
G02X382916I737J-1277D01*
G01X382957Y907106D01*
G03X385141Y907130I1071J1951D01*
G02X386615I737J-1277D01*
G03X388783Y907096I1114J1927D01*
G01X388841Y907130D01*
G02X390315I737J-1277D01*
G03X392483Y907096I1114J1927D01*
G01X392541Y907130D01*
G02X394015I737J-1277D01*
G03X396183Y907096I1114J1927D01*
G01X396241Y907130D01*
G02X397715I737J-1277D01*
G03X399883Y907096I1114J1927D01*
G01X399941Y907130D01*
G02X401211Y907227I736J-1277D01*
G01X401294Y906920D01*
X400678Y905853D01*
G01X411778Y912262D02*
X412394Y913329D01*
X412311Y913636D01*
G03X411041Y913539I-534J-1374D01*
G01X410983Y913505D01*
G02X408815Y913539I-1054J1961D01*
G03X407341I-737J-1277D01*
G01X407283Y913505D01*
G02X405115Y913539I-1054J1961D01*
G03X402903Y912262I-737J-1277D01*
G01Y912175D01*
G02X399624Y910300I-2225J87D01*
G01X399566Y910334D01*
G03X398092I-737J-1277D01*
G02X395866I-1113J1928D01*
G03X394392I-737J-1277D01*
G02X392224Y910300I-1115J1928D01*
G01X392166Y910334D01*
G03X390692I-737J-1277D01*
G02X388524Y910300I-1115J1928D01*
G01X388497Y910316D01*
X388466Y910334D01*
G03X386992I-737J-1277D01*
G02X384806Y910310I-1114J1928D01*
G01X384765Y910334D01*
G03X383291I-737J-1277D01*
G02X381107Y910310I-1113J1928D01*
G01X381066Y910334D01*
G03X379592I-737J-1277D01*
G02X377424Y910300I-1115J1928D01*
G01X377366Y910334D01*
G03X375892I-737J-1277D01*
G02X373724Y910300I-1115J1928D01*
G01X373666Y910334D01*
G03X372192I-737J-1277D01*
G02X369966I-1113J1928D01*
G03X368492I-737J-1277D01*
G02X366324Y910300I-1115J1928D01*
G01X366266Y910334D01*
G03X364792I-737J-1277D01*
G02X362624Y910300I-1115J1928D01*
G01X362566Y910334D01*
G03X361092I-737J-1277D01*
G02X358906Y910310I-1114J1928D01*
G01X358865Y910334D01*
G03X357391I-737J-1277D01*
G02X355207Y910310I-1113J1928D01*
G01X355166Y910334D01*
G03X353692I-737J-1277D01*
G02X351524Y910300I-1115J1928D01*
G01X351466Y910334D01*
G03X349992I-737J-1277D01*
G02X347824Y910300I-1115J1928D01*
G01X347766Y910334D01*
G03X346292I-737J-1277D01*
G02X345179Y910036I-1113J1928D01*
G01X331974D01*
X329585Y912425D01*
G01X427011Y1047749D02*
Y1047748D01*
X424537Y1045885D01*
X424424Y1045821D01*
X424425D01*
X424390Y1045801D01*
G03X423687Y1044544I772J-1257D01*
G01Y1044505D01*
G02X422575Y1042617I-2225J39D01*
G01X422574D01*
G02X420348I-1113J1927D01*
G03X418874I-737J-1277D01*
G01X418816Y1042583D01*
G02X416648Y1042617I-1054J1961D01*
G03X415174I-737J-1277D01*
G01X415116Y1042583D01*
G02X412948Y1042617I-1054J1961D01*
G03X410736Y1041339I-737J-1277D01*
G01Y1040075D01*
X410734Y1040073D01*
Y1039713D01*
X404573Y1033552D01*
Y1029481D01*
X402012Y1026920D01*
X398336D01*
G02X396486I-925J1603D01*
G01X396433Y1026951D01*
G03X394636Y1026920I-871J-1633D01*
G02X392786I-925J1603D01*
G01X392733Y1026951D01*
G03X390936Y1026920I-871J-1633D01*
G02X389086I-925J1603D01*
G03X387236I-925J-1602D01*
G02X385386I-925J1603D01*
G01X385333Y1026951D01*
G03X383536Y1026920I-871J-1633D01*
G02X381686I-925J1603D01*
G03X379889Y1026951I-926J-1602D01*
G01X379836Y1026920D01*
G02X377986I-925J1603D01*
G01X377933Y1026951D01*
G03X376136Y1026920I-871J-1633D01*
G02X374286I-925J1603D01*
G03X372489Y1026951I-926J-1602D01*
G01X372436Y1026920D01*
G02X370586I-925J1603D01*
G01X370533Y1026951D01*
G03X368736Y1026920I-871J-1633D01*
G02X366886I-925J1603D01*
G01X366833Y1026951D01*
G03X365036Y1026920I-871J-1633D01*
G02X363186I-925J1603D01*
G03X361336I-925J-1602D01*
G02X359486I-925J1603D01*
G01X359433Y1026951D01*
G03X357636Y1026920I-871J-1633D01*
G02X355786I-925J1603D01*
G01X355733Y1026951D01*
G03X353936Y1026920I-871J-1633D01*
G02X352086I-925J1603D01*
G01X352033Y1026951D01*
G03X350236Y1026920I-871J-1633D01*
G02X348386I-925J1603D01*
G03X346536I-925J-1602D01*
G02X344686I-925J1603D01*
G03X342836I-925J-1602D01*
G01X410362Y1044544D02*
X411593D01*
X411819Y1044770D01*
G03X411134Y1045801I-1458J-225D01*
G01X411099Y1045821D01*
G03X409625I-737J-1277D01*
G01X409624Y1045820D01*
G03X408887Y1044544I736J-1276D01*
G02X407798Y1042631I-2225J0D01*
G01X407785Y1042623D01*
X407774Y1042617D01*
X407739Y1042597D01*
G03X407036Y1041340I772J-1257D01*
G01Y1038768D01*
X402155Y1033887D01*
G02X401848Y1033654I-1038J1049D01*
G02X400374I-737J1277D01*
G01X400316Y1033688D01*
G03X398148Y1033654I-1054J-1961D01*
G02X396674I-737J1277D01*
G01X396616Y1033688D01*
G03X394448Y1033654I-1054J-1961D01*
G02X392974I-737J1277D01*
G01X392916Y1033688D01*
G03X390748Y1033654I-1054J-1961D01*
G02X389274I-737J1277D01*
G01X389216Y1033688D01*
G03X387048Y1033654I-1054J-1961D01*
G02X385574I-737J1277D01*
G03X383390Y1033678I-1113J-1927D01*
G01X383349Y1033654D01*
G02X381875I-737J1277D01*
G01X381834Y1033678D01*
G03X379648Y1033654I-1072J-1951D01*
G02X378174I-737J1277D01*
G01X378116Y1033688D01*
G03X375948Y1033654I-1054J-1961D01*
G02X374474I-737J1277D01*
G01X374416Y1033688D01*
G03X372248Y1033654I-1054J-1961D01*
G02X370774I-737J1277D01*
G01X370716Y1033688D01*
G03X368548Y1033654I-1054J-1961D01*
G02X367074I-737J1277D01*
G01X367016Y1033688D01*
G03X364848Y1033654I-1054J-1961D01*
G02X363374I-737J1277D01*
G01X363316Y1033688D01*
G03X361148Y1033654I-1054J-1961D01*
G02X359674I-737J1277D01*
G03X357490Y1033678I-1113J-1927D01*
G01X357449Y1033654D01*
G02X355975I-737J1277D01*
G03X353789Y1033678I-1114J-1927D01*
G01X353748Y1033654D01*
G02X352274I-737J1277D01*
G01X352216Y1033688D01*
G03X350048Y1033654I-1054J-1961D01*
G02X348574I-737J1277D01*
G03X347461Y1033952I-1112J-1927D01*
G01X347066D01*
X346475Y1034543D01*
G01X421462Y1044544D02*
X418614Y1043334D01*
X418499Y1043267D01*
G02X417025I-737J1277D01*
G03X414857Y1043301I-1114J-1927D01*
G01X414799Y1043267D01*
G02X413325I-737J1277D01*
G03X411157Y1043301I-1114J-1927D01*
G01X411099Y1043267D01*
Y1043266D01*
X410850Y1043123D01*
G03X409986Y1041627I863J-1496D01*
G01Y1041340D01*
G02X409283Y1040083I-1475J0D01*
G01X409248Y1040063D01*
Y1040029D01*
X407837Y1038618D01*
Y1038509D01*
X402685Y1033357D01*
G02X400057Y1032970I-1574J1574D01*
G01X399999Y1033004D01*
G03X398525I-737J-1277D01*
G02X396357Y1032970I-1114J1927D01*
G01X396299Y1033004D01*
G03X394825I-737J-1277D01*
G02X392657Y1032970I-1114J1927D01*
G01X392599Y1033004D01*
G03X391125I-737J-1277D01*
G02X388957Y1032970I-1114J1927D01*
G01X388899Y1033004D01*
G03X387425I-737J-1277D01*
G02X385239Y1032980I-1114J1927D01*
G01X385198Y1033004D01*
G03X383724I-737J-1277D01*
G01X383683Y1032980D01*
G02X381499Y1033004I-1071J1951D01*
G03X380025I-737J-1277D01*
G02X377857Y1032970I-1114J1927D01*
G01X377799Y1033004D01*
G03X376325I-737J-1277D01*
G02X374157Y1032970I-1114J1927D01*
G01X374099Y1033004D01*
G03X372625I-737J-1277D01*
G02X370457Y1032970I-1114J1927D01*
G01X370399Y1033004D01*
G03X368925I-737J-1277D01*
G02X366757Y1032970I-1114J1927D01*
G01X366699Y1033004D01*
G03X365225I-737J-1277D01*
G02X363057Y1032970I-1114J1927D01*
G01X362999Y1033004D01*
G03X361525I-737J-1277D01*
G02X359339Y1032980I-1114J1927D01*
G01X359298Y1033004D01*
G03X357824I-737J-1277D01*
G01X357766Y1032970D01*
G02X355598Y1033004I-1054J1961D01*
G03X354124I-737J-1277D01*
G02X351940Y1032980I-1113J1927D01*
G01X351899Y1033004D01*
G03X350425I-737J-1277D01*
G02X348239Y1032980I-1114J1927D01*
G03X347461Y1033203I-780J-1252D01*
G01X346572D01*
X346419Y1033356D01*
G01X399262Y1063770D02*
X399878Y1062703D01*
X399795Y1062396D01*
G02X398525Y1062493I-534J1374D01*
G01X398467Y1062527D01*
G03X396299Y1062493I-1054J-1961D01*
G02X394825I-737J1277D01*
G01X394784Y1062517D01*
G03X392600Y1062493I-1071J-1951D01*
G02X391126I-737J1277D01*
G03X388900I-1113J-1927D01*
G02X387426I-737J1277D01*
G01X387385Y1062517D01*
G03X385199Y1062493I-1072J-1951D01*
G02X383725I-737J1277D01*
G01X383667Y1062527D01*
G03X381499Y1062493I-1054J-1961D01*
G02X380025I-737J1277D01*
G03X377799I-1113J-1927D01*
G02X376325I-737J1277D01*
G01X376267Y1062527D01*
G03X374099Y1062493I-1054J-1961D01*
G02X372625I-737J1277D01*
G01X372567Y1062527D01*
G03X370399Y1062493I-1054J-1961D01*
G02X368925I-737J1277D01*
G01X368867Y1062527D01*
G03X366699Y1062493I-1054J-1961D01*
G02X365225I-737J1277D01*
G01X365184Y1062517D01*
G03X363000Y1062493I-1071J-1951D01*
G02X361526I-737J1277D01*
G01X361485Y1062517D01*
G03X359299Y1062493I-1072J-1951D01*
G02X357825I-737J1277D01*
G01X357767Y1062527D01*
G03X355599Y1062493I-1054J-1961D01*
G02X354125I-737J1277D01*
G03X351899I-1113J-1927D01*
G02X350425I-737J1277D01*
G01X350367Y1062527D01*
G03X348199Y1062493I-1054J-1961D01*
G02X346725I-737J1277D01*
G03X344499I-1113J-1927D01*
G02X343025I-737J1277D01*
G03X342537Y1062702I-1114J-1927D01*
G03X341576Y1062768I-629J-2135D01*
G01X339841Y1061033D01*
Y1059686D01*
X339062Y1058907D01*
X336579D01*
X334513Y1060973D01*
X332584D01*
X331661Y1061896D01*
G01X406662Y1063770D02*
X407278Y1062703D01*
X407183Y1062352D01*
G03X406286Y1060621I1328J-1786D01*
G01Y1060565D01*
G02X405583Y1059308I-1475J0D01*
G01X405548Y1059288D01*
G02X404074I-737J1277D01*
G03X401850I-1112J-1927D01*
G01X401817Y1059269D01*
G02X400375Y1059288I-704J1296D01*
G03X398189Y1059312I-1114J-1927D01*
G01X398148Y1059288D01*
G02X396674I-737J1277D01*
G01X396616Y1059322D01*
G03X394448Y1059288I-1054J-1961D01*
G02X392974I-737J1277D01*
G01X392916Y1059322D01*
G03X390748Y1059288I-1054J-1961D01*
G02X389274I-737J1277D01*
G01X389233Y1059312D01*
G03X387049Y1059288I-1071J-1951D01*
G02X385575I-737J1277D01*
G01X385534Y1059312D01*
G03X383348Y1059288I-1072J-1951D01*
G02X381874I-737J1277D01*
G01X381816Y1059322D01*
G03X379648Y1059288I-1054J-1961D01*
G02X378174I-737J1277D01*
G01X378116Y1059322D01*
G03X375948Y1059288I-1054J-1961D01*
G02X374474I-737J1277D01*
G03X372248I-1113J-1927D01*
G02X370774I-737J1277D01*
G01X370716Y1059322D01*
G03X368548Y1059288I-1054J-1961D01*
G02X367074I-737J1277D01*
G01X367016Y1059322D01*
G03X364848Y1059288I-1054J-1961D01*
G02X363374I-737J1277D01*
G01X363333Y1059312D01*
G03X361149Y1059288I-1071J-1951D01*
G02X359675I-737J1277D01*
G01X359634Y1059312D01*
G03X357448Y1059288I-1072J-1951D01*
G02X355974I-737J1277D01*
G03X353748I-1113J-1927D01*
G02X352274I-737J1277D01*
G03X350048I-1113J-1927D01*
G02X348574I-737J1277D01*
G03X346348I-1113J-1927D01*
G02X344874I-737J1277D01*
G03X342749Y1059343I-1113J-1927D01*
G01X341754Y1058758D01*
X339890Y1056894D01*
X336201D01*
X334597Y1058498D01*
X330570D01*
X330151Y1058917D01*
X329458D01*
G01X435829Y915466D02*
X435213Y914399D01*
X434862Y914305D01*
G03X432866Y914189I-883J-2043D01*
G01X432818Y914161D01*
G03X431753Y912262I1161J-1899D01*
G02X431050Y911005I-1475J0D01*
G01X431015Y910985D01*
G03X429903Y909144I1112J-1928D01*
G01Y909023D01*
G02X429166Y907780I-1474J34D01*
G02X427692I-737J1277D01*
G03X425464I-1114J-1927D01*
G03X424353Y905914I1114J-1927D01*
G01Y905853D01*
G02X423650Y904596I-1475J0D01*
G01X423615Y904576D01*
G03X422504Y902710I1114J-1927D01*
G01Y902649D01*
G02X421801Y901392I-1475J0D01*
G01X421766Y901372D01*
X421742Y901358D01*
G03X420653Y899445I1136J-1913D01*
G02X419950Y898188I-1475J0D01*
G01X419915Y898168D01*
G03X418804Y896327I1114J-1928D01*
G01Y896240D01*
G02X418101Y894983I-1475J0D01*
G01X418066Y894963D01*
X418018Y894935D01*
G03X416953Y893036I1161J-1899D01*
G02X416250Y891779I-1475J0D01*
G01X416215Y891759D01*
G03X415104Y889893I1114J-1927D01*
G01Y889832D01*
G02X414401Y888575I-1475J0D01*
G01X414366Y888555D01*
G03X413253Y886683I1112J-1928D01*
G01Y886627D01*
G02X412550Y885370I-1475J0D01*
G01X412515Y885350D01*
G03X411404Y883484I1114J-1927D01*
G01Y883423D01*
G02X410701Y882166I-1475J0D01*
G01X410666Y882146D01*
X410618Y882118D01*
G03X409553Y880219I1161J-1899D01*
G02X408850Y878962I-1475J0D01*
G01X408815Y878942D01*
G02X407341I-737J1277D01*
G01X407300Y878966D01*
G03X405116Y878942I-1071J-1952D01*
G02X403642I-737J1277D01*
G01X403601Y878966D01*
G03X401415Y878942I-1072J-1952D01*
G02X399941I-737J1277D01*
G01X399900Y878966D01*
G03X397716Y878942I-1071J-1952D01*
G02X396242I-737J1277D01*
G01X396201Y878966D01*
G03X394015Y878942I-1072J-1952D01*
G02X392541I-737J1277D01*
G01X392500Y878966D01*
G03X390316Y878942I-1071J-1952D01*
G02X388842I-737J1277D01*
G01X388801Y878966D01*
G03X386615Y878942I-1072J-1952D01*
G02X385141I-737J1277D01*
G01X385100Y878966D01*
G03X382916Y878942I-1071J-1952D01*
G02X381442I-737J1277D01*
G01X381401Y878966D01*
G03X379215Y878942I-1072J-1952D01*
G02X377741I-737J1277D01*
G01X377700Y878966D01*
G03X375516Y878942I-1071J-1952D01*
G02X374042I-737J1277D01*
G01X374001Y878966D01*
G03X371815Y878942I-1072J-1952D01*
G02X370341I-737J1277D01*
G01X370300Y878966D01*
G03X368116Y878942I-1071J-1952D01*
G02X366642I-737J1277D01*
G01X366601Y878966D01*
G03X364415Y878942I-1072J-1952D01*
G02X362941I-737J1277D01*
G01X362900Y878966D01*
G03X360716Y878942I-1071J-1952D01*
G02X359242I-737J1277D01*
G01X359201Y878966D01*
G03X357015Y878942I-1072J-1952D01*
G02X355541I-737J1277D01*
G01X355500Y878966D01*
G03X353316Y878942I-1071J-1952D01*
G02X351842I-737J1277D01*
G01X351801Y878966D01*
G03X349615Y878942I-1072J-1952D01*
G02X348175Y878923I-737J1277D01*
G01X348142Y878942D01*
X348084Y878976D01*
G03X345916Y878942I-1053J-1962D01*
G02X344442I-737J1277D01*
G03X342216I-1113J-1928D01*
G02X340742I-737J1277D01*
G03X338516I-1113J-1928D01*
G02X337042I-737J1277D01*
G01X336924Y879011D01*
G03X336025Y879243I-995J-1997D01*
G01X335698D01*
X334370Y877915D01*
Y876816D01*
G01X408078Y873810D02*
X405492Y875737D01*
G03X403324Y875771I-1114J-1927D01*
G01X403266Y875737D01*
X403265D01*
G02X401792I-737J1276D01*
G03X399624Y875771I-1114J-1927D01*
G01X399566Y875737D01*
G02X398092I-737J1277D01*
G03X395924Y875771I-1114J-1927D01*
G01X395866Y875737D01*
G02X394392I-737J1277D01*
G03X392224Y875771I-1114J-1927D01*
G01X392166Y875737D01*
G02X390692I-737J1277D01*
G03X388524Y875771I-1114J-1927D01*
G01X388497Y875755D01*
X388466Y875737D01*
G02X386992I-737J1277D01*
G03X384824Y875771I-1114J-1927D01*
G01X384766Y875737D01*
G02X383292I-737J1277D01*
G03X381124Y875771I-1114J-1927D01*
G01X381066Y875737D01*
G02X379592I-737J1277D01*
G03X377424Y875771I-1114J-1927D01*
G01X377366Y875737D01*
G02X375892I-737J1277D01*
G03X373724Y875771I-1114J-1927D01*
G01X373666Y875737D01*
G02X372192I-737J1277D01*
G03X370024Y875771I-1114J-1927D01*
G01X369966Y875737D01*
G02X368492I-737J1277D01*
G03X366324Y875771I-1114J-1927D01*
G01X366266Y875737D01*
G02X364792I-737J1277D01*
G03X362624Y875771I-1114J-1927D01*
G01X362566Y875737D01*
G02X361092I-737J1277D01*
G03X358924Y875771I-1114J-1927D01*
G01X358866Y875737D01*
G02X357392I-737J1277D01*
G03X355224Y875771I-1114J-1927D01*
G01X355166Y875737D01*
G02X353692I-737J1277D01*
G03X351524Y875771I-1114J-1927D01*
G01X351466Y875737D01*
X351442Y875723D01*
G03X350353Y873810I1136J-1913D01*
G01Y873776D01*
G02X349616Y872533I-1474J34D01*
G02X348142I-737J1277D01*
G03X345916I-1113J-1927D01*
G01X345917D01*
G02X345181Y872335I-738J1277D01*
G01X341182D01*
X339872Y871025D01*
X339366D01*
G01X333915Y873333D02*
X334441D01*
X337727Y876619D01*
Y877657D01*
X338083Y878013D01*
G03X338851Y878267I-304J2206D01*
G01X338892Y878291D01*
G02X340366I737J-1277D01*
G03X342592I1113J1928D01*
G02X344066I737J-1277D01*
G01X344107Y878267D01*
G03X346293Y878291I1072J1952D01*
G02X347733Y878310I737J-1277D01*
G01X347766Y878291D01*
X347824Y878257D01*
G03X349992Y878291I1053J1962D01*
G02X351466I737J-1277D01*
G03X353692I1113J1928D01*
G02X355166I737J-1277D01*
G01X355224Y878257D01*
G03X357392Y878291I1053J1962D01*
G02X358866I737J-1277D01*
G03X361092I1113J1928D01*
G02X362566I737J-1277D01*
G01X362624Y878257D01*
G03X364792Y878291I1053J1962D01*
G02X366266I737J-1277D01*
G03X368492I1113J1928D01*
G02X369966I737J-1277D01*
G01X370024Y878257D01*
G03X372192Y878291I1053J1962D01*
G02X373666I737J-1277D01*
G03X375892I1113J1928D01*
G02X377366I737J-1277D01*
G01X377424Y878257D01*
G03X379592Y878291I1053J1962D01*
G02X381066I737J-1277D01*
G03X383292I1113J1928D01*
G02X384766I737J-1277D01*
G01X384824Y878257D01*
G03X386992Y878291I1053J1962D01*
G02X388466I737J-1277D01*
G03X390692I1113J1928D01*
G02X392166I737J-1277D01*
G01X392224Y878257D01*
G03X394392Y878291I1053J1962D01*
G02X395866I737J-1277D01*
G03X398092I1113J1928D01*
G02X399566I737J-1277D01*
G01X399624Y878257D01*
G03X401792Y878291I1053J1962D01*
G02X403266I737J-1277D01*
G03X405492I1113J1928D01*
G02X406966I737J-1277D01*
G01X407024Y878257D01*
G03X409192Y878291I1053J1962D01*
G03X410304Y880163I-1114J1928D01*
G01Y880219D01*
G02X411007Y881476I1475J0D01*
G01X411042Y881496D01*
G03X412154Y883384I-1113J1927D01*
G01Y883423D01*
G02X412857Y884680I1475J0D01*
G01X412892Y884700D01*
G03X414003Y886566I-1114J1927D01*
G01Y886627D01*
G02X414706Y887884I1475J0D01*
G01X414741Y887904D01*
G03X415854Y889776I-1112J1928D01*
G01Y889832D01*
G02X416557Y891089I1475J0D01*
G01X416592Y891109D01*
X416616Y891123D01*
G03X417704Y893036I-1138J1913D01*
G02X418407Y894293I1475J0D01*
G01X418442Y894313D01*
G03X419554Y896201I-1113J1927D01*
G01Y896240D01*
G02X420257Y897497I1475J0D01*
G01X420292Y897517D01*
G03X421403Y899358I-1114J1928D01*
G01Y899445D01*
G02X422106Y900702I1475J0D01*
G01X422141Y900722D01*
X422165Y900736D01*
G03X423254Y902649I-1136J1913D01*
G02X423957Y903906I1475J0D01*
G01X423992Y903926D01*
G03X425103Y905792I-1114J1927D01*
G01Y905853D01*
G02X425806Y907110I1475J0D01*
G01X425841Y907130D01*
G02X427315I737J-1277D01*
G03X429483Y907096I1114J1927D01*
G01X429541Y907130D01*
G03X430653Y908996I-1112J1927D01*
G01Y909091D01*
G02X431390Y910334I1474J-34D01*
G01X431422Y910353D01*
G03X432504Y912262I-1143J1909D01*
G02X433207Y913519I1475J0D01*
G01X433242Y913539D01*
G02X434512Y913636I736J-1277D01*
G01X434595Y913329D01*
X433979Y912262D01*
G01X439529Y921875D02*
X440145Y920808D01*
X440050Y920457D01*
G03X439153Y918726I1328J-1786D01*
G01Y918670D01*
G02X438450Y917413I-1475J0D01*
G01X438415Y917393D01*
G03X437304Y915527I1114J-1927D01*
G01Y915466D01*
G02X436601Y914209I-1475J0D01*
G01X436566Y914189D01*
X436542Y914175D01*
G03X435453Y912262I1136J-1913D01*
G01Y912228D01*
G02X434716Y910985I-1474J34D01*
G03X433603Y909087I1113J-1928D01*
G01Y909057D01*
G02X432923Y907814I-1476J0D01*
G01X432864Y907780D01*
G03X431753Y905914I1114J-1927D01*
G01Y905853D01*
G02X431050Y904596I-1475J0D01*
G01X431015Y904576D01*
G02X429541I-737J1277D01*
G01X429483Y904610D01*
G03X427315Y904576I-1054J-1961D01*
G03X426204Y902710I1114J-1927D01*
G01Y902649D01*
G02X425501Y901392I-1475J0D01*
G01X425466Y901372D01*
X425442Y901358D01*
G03X424353Y899445I1136J-1913D01*
G02X423650Y898188I-1475J0D01*
G01X423615Y898168D01*
G03X422504Y896327I1114J-1928D01*
G01Y896179D01*
G03X423615Y894313I2225J61D01*
G01X423650Y894293D01*
G02Y891779I-772J-1257D01*
G01X423615Y891759D01*
G03X422504Y889893I1114J-1927D01*
G01Y889832D01*
G02X421801Y888575I-1475J0D01*
G01X421766Y888555D01*
G03X420653Y886683I1112J-1928D01*
G01Y886627D01*
G02X419950Y885370I-1475J0D01*
G01X419915Y885350D01*
G03X418804Y883484I1114J-1927D01*
G01Y883423D01*
G02X418101Y882166I-1475J0D01*
G01X418066Y882146D01*
X418018Y882118D01*
G03X416953Y880219I1161J-1899D01*
G02X416250Y878962I-1475J0D01*
G01X416215Y878942D01*
G03X415104Y877101I1114J-1928D01*
G01Y877014D01*
G02X414401Y875757I-1475J0D01*
G01X414366Y875737D01*
G02X412892I-737J1277D01*
G03X410724Y875771I-1114J-1927D01*
G01X410666Y875737D01*
X410642Y875723D01*
G03X409553Y873810I1136J-1913D01*
G02X408850Y872553I-1475J0D01*
G01X408815Y872533D01*
G02X407341I-737J1277D01*
G01X407283Y872567D01*
G03X405115Y872533I-1054J-1961D01*
G03X404004Y870667I1114J-1927D01*
G01Y870606D01*
G02X403301Y869349I-1475J0D01*
G01X403266Y869329D01*
G02X401792I-737J1277D01*
G01X401757Y869349D01*
G02X401054Y870606I772J1257D01*
G03X399965Y872519I-2225J0D01*
G01X399941Y872533D01*
X399883Y872567D01*
G03X397715Y872533I-1054J-1961D01*
G03X396604Y870667I1114J-1927D01*
G01Y870606D01*
G02X395901Y869349I-1475J0D01*
G01X395866Y869329D01*
G02X394392I-737J1277D01*
G01X394357Y869349D01*
G02X393654Y870606I772J1257D01*
G03X392565Y872519I-2225J0D01*
G01X392541Y872533D01*
X392483Y872567D01*
G03X390315Y872533I-1054J-1961D01*
G03X389204Y870667I1114J-1927D01*
G01Y870606D01*
G02X388501Y869349I-1475J0D01*
G01X388497Y869347D01*
X388466Y869329D01*
G02X386992I-737J1277D01*
G01X386957Y869349D01*
G02X386254Y870606I772J1257D01*
G03X385165Y872519I-2225J0D01*
G01X385141Y872533D01*
X385083Y872567D01*
G03X382915Y872533I-1054J-1961D01*
G03X381804Y870667I1114J-1927D01*
G01Y870606D01*
G02X381101Y869349I-1475J0D01*
G01X381066Y869329D01*
G02X379592I-737J1277D01*
G01X379557Y869349D01*
G02X378854Y870606I772J1257D01*
G03X377765Y872519I-2225J0D01*
G01X377741Y872533D01*
X377683Y872567D01*
G03X375515Y872533I-1054J-1961D01*
G03X374404Y870667I1114J-1927D01*
G01Y870606D01*
G02X373701Y869349I-1475J0D01*
G01X373666Y869329D01*
G02X372192I-737J1277D01*
G01X372157Y869349D01*
G02X371454Y870606I772J1257D01*
G03X370365Y872519I-2225J0D01*
G01X370341Y872533D01*
X370283Y872567D01*
G03X368115Y872533I-1054J-1961D01*
G03X367004Y870667I1114J-1927D01*
G01Y870606D01*
G02X366301Y869349I-1475J0D01*
G01X366266Y869329D01*
G02X364792I-737J1277D01*
G01X364757Y869349D01*
G02X364054Y870606I772J1257D01*
G03X362965Y872519I-2225J0D01*
G01X362941Y872533D01*
X362883Y872567D01*
G03X360715Y872533I-1054J-1961D01*
G03X359604Y870667I1114J-1927D01*
G01Y870606D01*
G02X358901Y869349I-1475J0D01*
G01X358866Y869329D01*
G02X357392I-737J1277D01*
G01X357357Y869349D01*
G02X356654Y870606I772J1257D01*
G03X355565Y872519I-2225J0D01*
G01X355541Y872533D01*
X355483Y872567D01*
G03X353315Y872533I-1054J-1961D01*
G03X352204Y870667I1114J-1927D01*
G01Y870606D01*
G02X351501Y869349I-1475J0D01*
G01X351466Y869329D01*
G02X349992I-737J1277D01*
G03X347766I-1113J-1928D01*
G03X347306Y868975I1116J-1926D01*
G01X346826Y868495D01*
X345187D01*
X344267Y867575D01*
G01X400678Y873810D02*
X401909D01*
X402135Y874036D01*
G03X401450Y875067I-1458J-225D01*
G01X401415Y875087D01*
G03X399941I-737J-1277D01*
G01X399883Y875053D01*
G02X397715Y875087I-1054J1961D01*
G03X396241I-737J-1277D01*
G01X396183Y875053D01*
G02X394015Y875087I-1054J1961D01*
G03X392541I-737J-1277D01*
G01X392483Y875053D01*
G02X390315Y875087I-1054J1961D01*
G03X388841I-737J-1277D01*
G01X388783Y875053D01*
G02X386615Y875087I-1054J1961D01*
G03X385141I-737J-1277D01*
G01X385083Y875053D01*
G02X382915Y875087I-1054J1961D01*
G03X381441I-737J-1277D01*
G01X381383Y875053D01*
G02X379215Y875087I-1054J1961D01*
G03X377741I-737J-1277D01*
G01X377683Y875053D01*
G02X375515Y875087I-1054J1961D01*
G03X374041I-737J-1277D01*
G01X373983Y875053D01*
G02X371815Y875087I-1054J1961D01*
G03X370341I-737J-1277D01*
G01X370283Y875053D01*
G02X368115Y875087I-1054J1961D01*
G03X366641I-737J-1277D01*
G01X366583Y875053D01*
G02X364415Y875087I-1054J1961D01*
G03X362941I-737J-1277D01*
G01X362883Y875053D01*
G02X360715Y875087I-1054J1961D01*
G03X359241I-737J-1277D01*
G01X359183Y875053D01*
G02X357015Y875087I-1054J1961D01*
G03X355541I-737J-1277D01*
G01X355483Y875053D01*
G02X353315Y875087I-1054J1961D01*
G03X351841I-737J-1277D01*
G03X351104Y873844I737J-1277D01*
G01Y873771D01*
G02X349992Y871883I-2225J39D01*
G02X347766I-1113J1927D01*
G03X346292I-737J-1277D01*
G02X345182Y871585I-1112J1927D01*
G01X341493D01*
X340426Y870518D01*
Y869964D01*
G01X441378Y918670D02*
X441246Y918899D01*
X440762Y919737D01*
X440746Y919741D01*
X440454Y919819D01*
G03X439903Y918670I924J-1150D01*
G01Y918609D01*
G02X438792Y916743I-2225J61D01*
G01X438757Y916723D01*
G03X438054Y915466I772J-1257D01*
G02X436965Y913553I-2225J0D01*
G01X436941Y913539D01*
G03X436204Y912296I737J-1277D01*
G01Y912189D01*
G02X435092Y910334I-2225J73D01*
G01X435033Y910300D01*
G03X434353Y909057I796J-1243D01*
G02X433265Y907144I-2226J0D01*
G01X433241Y907130D01*
X433206Y907110D01*
G03X432503Y905853I772J-1257D01*
G01Y905792D01*
G02X431392Y903926I-2225J61D01*
G02X429224Y903892I-1114J1927D01*
G01X429166Y903926D01*
G03X427692I-737J-1277D01*
G01X427657Y903906D01*
G03X426954Y902649I772J-1257D01*
G02X425865Y900736I-2225J0D01*
G01X425841Y900722D01*
X425806Y900702D01*
G03X425103Y899445I772J-1257D01*
G01Y899358D01*
G02X423992Y897517I-2225J87D01*
G01X423957Y897497D01*
G03X423936Y897484I766J-1261D01*
G03X423254Y896240I794J-1244D01*
G03X423957Y894983I1475J0D01*
G01X423992Y894963D01*
X424016Y894949D01*
G02Y891123I-1138J-1913D01*
G01X423992Y891109D01*
X423957Y891089D01*
G03X423254Y889832I772J-1257D01*
G01Y889776D01*
G02X422141Y887904I-2225J56D01*
G01X422106Y887884D01*
G03X421403Y886627I772J-1257D01*
G01Y886566D01*
G02X420292Y884700I-2225J61D01*
G01X420257Y884680D01*
G03X419554Y883423I772J-1257D01*
G01Y883384D01*
G02X418442Y881496I-2225J39D01*
G01X418407Y881476D01*
G03X417704Y880219I772J-1257D01*
G01Y880163D01*
G02X416592Y878291I-2226J56D01*
G01X416557Y878271D01*
G03X415854Y877014I772J-1257D01*
G02X414765Y875101I-2225J0D01*
G01X414741Y875087D01*
X414683Y875053D01*
G02X412515Y875087I-1054J1961D01*
G03X411041I-737J-1277D01*
G01X411006Y875067D01*
G03X410303Y873810I772J-1257D01*
G01Y873749D01*
G02X409192Y871883I-2225J61D01*
G02X407024Y871849I-1114J1927D01*
G01X406966Y871883D01*
G03X405492I-737J-1277D01*
G01X405457Y871863D01*
G03X404754Y870606I772J-1257D01*
G01Y870533D01*
G02X403642Y868678I-2225J73D01*
G01X403601Y868654D01*
G02X401415Y868678I-1072J1952D01*
G02X400304Y870519I1114J1928D01*
G01Y870606D01*
G03X399601Y871863I-1475J0D01*
G01X399566Y871883D01*
G03X398092I-737J-1277D01*
G01X398057Y871863D01*
G03X397354Y870606I772J-1257D01*
G01Y870533D01*
G02X396242Y868678I-2225J73D01*
G01X396201Y868654D01*
G02X394015Y868678I-1072J1952D01*
G02X392904Y870519I1114J1928D01*
G01Y870606D01*
G03X392201Y871863I-1475J0D01*
G01X392166Y871883D01*
G03X390692I-737J-1277D01*
G01X390657Y871863D01*
G03X389954Y870606I772J-1257D01*
G01Y870533D01*
G02X388842Y868678I-2225J73D01*
G01X388801Y868654D01*
G02X386615Y868678I-1072J1952D01*
G02X385504Y870519I1114J1928D01*
G01Y870606D01*
G03X384801Y871863I-1475J0D01*
G01X384766Y871883D01*
G03X383292I-737J-1277D01*
G01X383257Y871863D01*
G03X382554Y870606I772J-1257D01*
G01Y870533D01*
G02X381442Y868678I-2225J73D01*
G01X381401Y868654D01*
G02X379215Y868678I-1072J1952D01*
G02X378104Y870519I1114J1928D01*
G01Y870606D01*
G03X377401Y871863I-1475J0D01*
G01X377366Y871883D01*
G03X375892I-737J-1277D01*
G01X375857Y871863D01*
G03X375154Y870606I772J-1257D01*
G01Y870533D01*
G02X374042Y868678I-2225J73D01*
G01X374001Y868654D01*
G02X371815Y868678I-1072J1952D01*
G02X370704Y870519I1114J1928D01*
G01Y870606D01*
G03X370001Y871863I-1475J0D01*
G01X369966Y871883D01*
G03X368492I-737J-1277D01*
G01X368457Y871863D01*
G03X367754Y870606I772J-1257D01*
G01Y870533D01*
G02X366642Y868678I-2225J73D01*
G01X366601Y868654D01*
G02X364415Y868678I-1072J1952D01*
G02X363304Y870519I1114J1928D01*
G01Y870606D01*
G03X362601Y871863I-1475J0D01*
G01X362566Y871883D01*
G03X361092I-737J-1277D01*
G01X361057Y871863D01*
G03X360354Y870606I772J-1257D01*
G01Y870533D01*
G02X359242Y868678I-2225J73D01*
G01X359201Y868654D01*
G02X357015Y868678I-1072J1952D01*
G02X355904Y870519I1114J1928D01*
G01Y870606D01*
G03X355201Y871863I-1475J0D01*
G01X355166Y871883D01*
G03X353692I-737J-1277D01*
G01X353657Y871863D01*
G03X352954Y870606I772J-1257D01*
G01Y870533D01*
G02X351842Y868678I-2225J73D01*
G02X349616I-1113J1928D01*
G03X348142I-737J-1277D01*
G03X347836Y868444I735J-1278D01*
G01X346122Y866730D01*
G01X347029Y877014D02*
X345871D01*
X344344Y875487D01*
X339959D01*
G01X415478Y905853D02*
X416094Y906920D01*
X416011Y907227D01*
G03X414741Y907130I-534J-1374D01*
G01X414683Y907096D01*
G02X412515Y907130I-1054J1961D01*
G03X411041I-737J-1277D01*
G01X411006Y907110D01*
G03X410303Y905853I772J-1257D01*
G01Y905792D01*
G02X409192Y903926I-2225J61D01*
G01X409157Y903906D01*
G03X408454Y902649I772J-1257D01*
G02X407365Y900736I-2225J0D01*
G01X407341Y900722D01*
X407306Y900702D01*
G03X406603Y899445I772J-1257D01*
G01Y899358D01*
G02X405492Y897517I-2225J87D01*
G01X405457Y897497D01*
G03X404754Y896240I772J-1257D01*
G02X403665Y894327I-2225J0D01*
G01X403641Y894313D01*
X403606Y894293D01*
G03X402903Y893036I772J-1257D01*
G01Y892975D01*
G02X401792Y891109I-2225J61D01*
G02X399624Y891075I-1114J1927D01*
G01X399566Y891109D01*
G03X398092I-737J-1277D01*
G02X395866I-1113J1927D01*
G03X394392I-737J-1277D01*
G02X392166I-1113J1927D01*
G03X390692I-737J-1277D01*
G02X388466I-1113J1927D01*
G03X386992I-737J-1277D01*
G02X384824Y891075I-1114J1927D01*
G01X384766Y891109D01*
G03X383292I-737J-1277D01*
G02X381124Y891075I-1114J1927D01*
G01X381066Y891109D01*
G03X379592I-737J-1277D01*
G02X377366I-1113J1927D01*
G03X375892I-737J-1277D01*
G02X373724Y891075I-1114J1927D01*
G01X373666Y891109D01*
G03X372192I-737J-1277D01*
G02X370024Y891075I-1114J1927D01*
G01X369966Y891109D01*
G03X368492I-737J-1277D01*
G02X366266I-1113J1927D01*
G03X364792I-737J-1277D01*
G02X362566I-1113J1927D01*
G03X361092I-737J-1277D01*
G01X361051Y891085D01*
G02X358865Y891109I-1072J1951D01*
G03X357391I-737J-1277D01*
G02X355207Y891085I-1113J1927D01*
G01X355166Y891109D01*
G03X353692I-737J-1277D01*
G02X351524Y891075I-1114J1927D01*
G01X351466Y891109D01*
G03X349992I-737J-1277D01*
G02X349222Y890837I-1114J1927D01*
G01X348907Y890522D01*
Y889705D01*
G01X417329Y915466D02*
X418560D01*
X418786Y915692D01*
G03X418101Y916723I-1458J-225D01*
G01X418066Y916743D01*
G03X416592I-737J-1277D01*
G02X414424Y916709I-1114J1927D01*
G01X414366Y916743D01*
G03X412892I-737J-1277D01*
G02X410724Y916709I-1114J1927D01*
G01X410666Y916743D01*
G03X409192I-737J-1277D01*
G02X407024Y916709I-1114J1927D01*
G01X406966Y916743D01*
G03X405492I-737J-1277D01*
G02X403324Y916709I-1114J1927D01*
G01X403266Y916743D01*
G03X401792I-737J-1277D01*
G02X399624Y916709I-1114J1927D01*
G01X399566Y916743D01*
G03X398092I-737J-1277D01*
G02X395924Y916709I-1114J1927D01*
G01X395866Y916743D01*
G03X394392I-737J-1277D01*
G02X392224Y916709I-1114J1927D01*
G01X392166Y916743D01*
G03X390692I-737J-1277D01*
G02X388506Y916719I-1114J1927D01*
G01X388497Y916724D01*
X388465Y916743D01*
G03X386991I-737J-1277D01*
G01X386950Y916719D01*
G02X384766Y916743I-1071J1951D01*
G03X383292I-737J-1277D01*
G02X381124Y916709I-1114J1927D01*
G01X381066Y916743D01*
G03X379592I-737J-1277D01*
G02X377424Y916709I-1114J1927D01*
G01X377366Y916743D01*
G03X375892I-737J-1277D01*
G02X373724Y916709I-1114J1927D01*
G01X373666Y916743D01*
G03X372192I-737J-1277D01*
G02X370024Y916709I-1114J1927D01*
G01X369966Y916743D01*
G03X368492I-737J-1277D01*
G02X366324Y916709I-1114J1927D01*
G01X366266Y916743D01*
G03X364792I-737J-1277D01*
G02X362606Y916719I-1114J1927D01*
G01X362565Y916743D01*
G03X361091I-737J-1277D01*
G01X361050Y916719D01*
G02X358866Y916743I-1071J1951D01*
G03X357392I-737J-1277D01*
G02X355224Y916709I-1114J1927D01*
G01X355166Y916743D01*
G03X353692I-737J-1277D01*
G02X351524Y916709I-1114J1927D01*
G01X351466Y916743D01*
G03X349992I-737J-1277D01*
G02X347824Y916709I-1114J1927D01*
G01X347766Y916743D01*
G03X346292I-737J-1277D01*
G02X344066I-1113J1927D01*
G03X343329Y916942I-740J-1276D01*
G01X336394D01*
X334841Y918495D01*
G01X401111Y1015705D02*
G03X399711Y1015330I0J-2801D01*
G01X398148Y1014428D01*
G02X396674I-737J1277D01*
G01X396616Y1014462D01*
G03X394448Y1014428I-1054J-1961D01*
G02X392974I-737J1277D01*
G03X390790Y1014452I-1113J-1927D01*
G01X390749Y1014428D01*
G02X389275I-737J1277D01*
G01X389234Y1014452D01*
G03X387048Y1014428I-1072J-1951D01*
G02X385574I-737J1277D01*
G03X383390Y1014452I-1113J-1927D01*
G01X383349Y1014428D01*
G02X381875I-737J1277D01*
G01X381834Y1014452D01*
G03X379648Y1014428I-1072J-1951D01*
G02X378174I-737J1277D01*
G01X378116Y1014462D01*
G03X375948Y1014428I-1054J-1961D01*
G02X374474I-737J1277D01*
G01X374416Y1014462D01*
G03X372248Y1014428I-1054J-1961D01*
G02X370774I-737J1277D01*
G01X370716Y1014462D01*
G03X368548Y1014428I-1054J-1961D01*
G02X367074I-737J1277D01*
G03X364890Y1014452I-1113J-1927D01*
G01X364849Y1014428D01*
G02X363375I-737J1277D01*
G01X363334Y1014452D01*
G03X361148Y1014428I-1072J-1951D01*
G02X359674I-737J1277D01*
G03X357490Y1014452I-1113J-1927D01*
G01X357449Y1014428D01*
G02X355975I-737J1277D01*
G03X353789Y1014452I-1114J-1927D01*
G01X353748Y1014428D01*
X353452Y1014132D01*
X344025D01*
G01X402962Y1038136D02*
X400884Y1037146D01*
G03X399999Y1036859I229J-2214D01*
G02X398525I-737J1277D01*
G03X396299I-1113J-1927D01*
G02X394825I-737J1277D01*
G01X394767Y1036893D01*
G03X392599Y1036859I-1054J-1961D01*
G02X391125I-737J1277D01*
G01X391067Y1036893D01*
G03X388899Y1036859I-1054J-1961D01*
G02X387425I-737J1277D01*
G01X387384Y1036883D01*
G03X385200Y1036859I-1071J-1951D01*
G02X383676Y1036864I-758J1313D01*
G01X383561Y1036922D01*
G03X381499Y1036859I-973J-1946D01*
G02X380025I-737J1277D01*
G01X379967Y1036893D01*
G03X377799Y1036859I-1054J-1961D01*
G02X376325I-737J1277D01*
G01X376267Y1036893D01*
G03X374099Y1036859I-1054J-1961D01*
G02X372692Y1036822I-738J1277D01*
G03X372526Y1036884I-339J-655D01*
G03X370498I-1014J-4315D01*
G03X370333Y1036822I175J-716D01*
G02X368925Y1036859I-670J1313D01*
G01X368867Y1036893D01*
G03X366699Y1036859I-1054J-1961D01*
G02X365225I-737J1277D01*
G01X365167Y1036893D01*
G03X362999Y1036859I-1054J-1961D01*
G02X361525I-737J1277D01*
G01X361484Y1036883D01*
G03X359300Y1036859I-1071J-1951D01*
G02X357826I-737J1277D01*
G03X355460Y1036468I-945J-1637D01*
G02X353985Y1036420I-760J667D01*
G01X353713Y1036691D01*
G03X351946I-884J-884D01*
G01X351569Y1036314D01*
G02X350385I-592J592D01*
G01X350059Y1036640D01*
G03X348325I-867J-867D01*
G01X348070Y1036385D01*
X342709D01*
G01X401113Y1060565D02*
X400497Y1061633D01*
X400146Y1061727D01*
G02X398208Y1061809I-884J2043D01*
G01X398150Y1061843D01*
G03X396676I-737J-1277D01*
G02X394508Y1061809I-1114J1927D01*
G01X394450Y1061843D01*
G03X392976I-737J-1277D01*
G02X390750I-1113J1927D01*
G03X389276I-737J-1277D01*
G02X387050I-1113J1927D01*
G03X385576I-737J-1277D01*
G02X383408Y1061809I-1114J1927D01*
G01X383350Y1061843D01*
G03X381876I-737J-1277D01*
G02X379690Y1061819I-1114J1927D01*
G01X379649Y1061843D01*
G03X378175I-737J-1277D01*
G02X375991Y1061819I-1113J1927D01*
G01X375950Y1061843D01*
G03X374476I-737J-1277D01*
G02X372308Y1061809I-1114J1927D01*
G01X372250Y1061843D01*
G03X370776I-737J-1277D01*
G02X368608Y1061809I-1114J1927D01*
G01X368550Y1061843D01*
G03X367076I-737J-1277D01*
G02X364908Y1061809I-1114J1927D01*
G01X364850Y1061843D01*
G03X363376I-737J-1277D01*
G02X361150I-1113J1927D01*
G03X359676I-737J-1277D01*
G02X357508Y1061809I-1114J1927D01*
G01X357450Y1061843D01*
G03X355976I-737J-1277D01*
G02X353790Y1061819I-1114J1927D01*
G01X353749Y1061843D01*
G03X352275I-737J-1277D01*
G02X350091Y1061819I-1113J1927D01*
G01X350050Y1061843D01*
G03X348576I-737J-1277D01*
G02X346390Y1061819I-1114J1927D01*
G01X346349Y1061843D01*
G03X344875I-737J-1277D01*
G02X342649I-1113J1927D01*
G03X341911Y1062043I-742J-1276D01*
G01X340590Y1060722D01*
Y1059375D01*
X339373Y1058158D01*
X336268D01*
X334483Y1059943D01*
X331462D01*
G01X408511Y1060565D02*
X407895Y1061632D01*
X407587Y1061714D01*
G03X407036Y1060565I924J-1150D01*
G01Y1060504D01*
G02X405925Y1058638I-2225J61D01*
G02X403757Y1058604I-1114J1927D01*
G01X403699Y1058638D01*
G03X402225I-737J-1277D01*
G01X402167Y1058604D01*
G02X399999Y1058638I-1054J1961D01*
G03X398557Y1058657I-738J-1277D01*
G01X398524Y1058638D01*
G02X396340Y1058614I-1113J1927D01*
G01X396299Y1058638D01*
G03X394825I-737J-1277D01*
G02X392657Y1058604I-1114J1927D01*
G01X392599Y1058638D01*
G03X391125I-737J-1277D01*
G02X388957Y1058604I-1114J1927D01*
G01X388899Y1058638D01*
G03X387425I-737J-1277D01*
G02X385199I-1113J1927D01*
G03X383725I-737J-1277D01*
G02X381557Y1058604I-1114J1927D01*
G01X381499Y1058638D01*
G03X380025I-737J-1277D01*
G02X377857Y1058604I-1114J1927D01*
G01X377799Y1058638D01*
G03X376325I-737J-1277D01*
G02X374139Y1058614I-1114J1927D01*
G01X374098Y1058638D01*
G03X372624I-737J-1277D01*
G02X370440Y1058614I-1113J1927D01*
G01X370399Y1058638D01*
G03X368925I-737J-1277D01*
G02X366757Y1058604I-1114J1927D01*
G01X366699Y1058638D01*
G03X365225I-737J-1277D01*
G02X363057Y1058604I-1114J1927D01*
G01X362999Y1058638D01*
G03X361525I-737J-1277D01*
G02X359299I-1113J1927D01*
G03X357825I-737J-1277D01*
G02X355639Y1058614I-1114J1927D01*
G01X355598Y1058638D01*
G03X354124I-737J-1277D01*
G02X351898I-1113J1927D01*
G03X350424I-737J-1277D01*
G02X348198I-1113J1927D01*
G03X346724I-737J-1277D01*
G02X344498I-1113J1927D01*
G03X343122Y1058689I-736J-1277D01*
G01X343030Y1058637D01*
X342945Y1058588D01*
X342216Y1058160D01*
X340201Y1056145D01*
X335650D01*
X334768Y1057027D01*
X329668D01*
G01X410362Y1063770D02*
X409746Y1064837D01*
X409395Y1064931D01*
G02X407457Y1065013I-884J2043D01*
G01X407399Y1065047D01*
G03X405925I-737J-1277D01*
G02X403757Y1065013I-1114J1927D01*
G01X403699Y1065047D01*
G03X402225I-737J-1277D01*
G02X399999I-1113J1927D01*
G03X398525I-737J-1277D01*
G02X396299I-1113J1927D01*
G03X394825I-737J-1277D01*
G02X392657Y1065013I-1114J1927D01*
G01X392599Y1065047D01*
G03X391125I-737J-1277D01*
G02X388939Y1065023I-1114J1927D01*
G01X388898Y1065047D01*
G03X387424I-737J-1277D01*
G02X385240Y1065023I-1113J1927D01*
G01X385199Y1065047D01*
G03X383725I-737J-1277D01*
G02X381557Y1065013I-1114J1927D01*
G01X381499Y1065047D01*
G03X380025I-737J-1277D01*
G02X377857Y1065013I-1114J1927D01*
G01X377799Y1065047D01*
G03X376325I-737J-1277D01*
G02X374157Y1065013I-1114J1927D01*
G01X374099Y1065047D01*
G03X372625I-737J-1277D01*
G02X370399I-1113J1927D01*
G03X368925I-737J-1277D01*
G02X366757Y1065013I-1114J1927D01*
G01X366699Y1065047D01*
G03X365225I-737J-1277D01*
G02X363039Y1065023I-1114J1927D01*
G01X362998Y1065047D01*
G03X361524I-737J-1277D01*
G02X359340Y1065023I-1113J1927D01*
G01X359299Y1065047D01*
G03X357825I-737J-1277D01*
G02X355639Y1065023I-1114J1927D01*
G01X355598Y1065047D01*
G03X354124I-737J-1277D01*
G02X351898I-1113J1927D01*
G03X350424I-737J-1277D01*
G02X348198I-1113J1927D01*
G03X346724I-737J-1277D01*
G02X344498I-1113J1927D01*
G03X343024I-737J-1277D01*
G01X342151Y1064542D01*
G02X341975Y1064495I-176J304D01*
G01X339004D01*
G01X408511Y1066974D02*
X409127Y1065907D01*
X409044Y1065600D01*
G02X407774Y1065697I-534J1374D01*
G01X407716Y1065731D01*
G03X405548Y1065697I-1054J-1961D01*
G02X404074I-737J1277D01*
G01X404033Y1065721D01*
G03X401849Y1065697I-1071J-1951D01*
G02X400375I-737J1277D01*
G03X398149I-1113J-1927D01*
G02X396675I-737J1277D01*
G01X396634Y1065721D01*
G03X394448Y1065697I-1072J-1951D01*
G02X392974I-737J1277D01*
G01X392916Y1065731D01*
G03X390748Y1065697I-1054J-1961D01*
G02X389274I-737J1277D01*
G03X387048I-1113J-1927D01*
G02X385574I-737J1277D01*
G01X385516Y1065731D01*
G03X383348Y1065697I-1054J-1961D01*
G02X381874I-737J1277D01*
G01X381816Y1065731D01*
G03X379648Y1065697I-1054J-1961D01*
G02X378174I-737J1277D01*
G01X378116Y1065731D01*
G03X375948Y1065697I-1054J-1961D01*
G02X374474I-737J1277D01*
G01X374433Y1065721D01*
G03X372249Y1065697I-1071J-1951D01*
G02X370775I-737J1277D01*
G01X370734Y1065721D01*
G03X368548Y1065697I-1072J-1951D01*
G02X367074I-737J1277D01*
G01X367016Y1065731D01*
G03X364848Y1065697I-1054J-1961D01*
G02X363374I-737J1277D01*
G03X361148I-1113J-1927D01*
G02X359674I-737J1277D01*
G01X359616Y1065731D01*
G03X357448Y1065697I-1054J-1961D01*
G02X355974I-737J1277D01*
G03X353748I-1113J-1927D01*
G02X352274I-737J1277D01*
G03X350048I-1113J-1927D01*
G02X348574I-737J1277D01*
G03X346348I-1113J-1927D01*
G02X344874I-737J1277D01*
G03X342648I-1113J-1927D01*
G02X341910Y1065497I-742J1276D01*
G01X339004D01*
G01X334302Y1086451D02*
X335531Y1085222D01*
X340060D01*
G02X341174Y1084923I-1J-2227D01*
G03X342648I737J1277D01*
G01X342689Y1084947D01*
G02X344873Y1084923I1071J-1952D01*
G03X346347I737J1277D01*
G02X348533Y1084947I1114J-1928D01*
G01X348574Y1084923D01*
G03X350048I737J1277D01*
G02X352274I1113J-1928D01*
G03X353748I737J1277D01*
G02X355974I1113J-1928D01*
G03X357448I737J1277D01*
G02X359616Y1084957I1115J-1928D01*
G01X359674Y1084923D01*
G03X361148I737J1277D01*
G02X363374I1113J-1928D01*
G03X364848I737J1277D01*
G02X367016Y1084957I1115J-1928D01*
G01X367074Y1084923D01*
G03X368548I737J1277D01*
G02X370734Y1084947I1114J-1928D01*
G01X370775Y1084923D01*
G03X372249I737J1277D01*
G02X374433Y1084947I1113J-1928D01*
G01X374474Y1084923D01*
G03X375948I737J1277D01*
G02X378116Y1084957I1115J-1928D01*
G01X378174Y1084923D01*
G03X379648I737J1277D01*
G02X381816Y1084957I1115J-1928D01*
G01X381874Y1084923D01*
G03X383348I737J1277D01*
G02X385516Y1084957I1115J-1928D01*
G01X385574Y1084923D01*
G03X387048I737J1277D01*
G02X389274I1113J-1928D01*
G03X390748I737J1277D01*
G02X392916Y1084957I1115J-1928D01*
G01X392974Y1084923D01*
G03X394448I737J1277D01*
G02X396634Y1084947I1114J-1928D01*
G01X396675Y1084923D01*
G03X398149I737J1277D01*
G02X400333Y1084947I1113J-1928D01*
G01X400374Y1084923D01*
G03X401848I737J1277D01*
G02X404016Y1084957I1115J-1928D01*
G01X404074Y1084923D01*
G03X405548I737J1277D01*
G02X407716Y1084957I1115J-1928D01*
G01X407774Y1084923D01*
G03X409248I737J1277D01*
G02X411416Y1084957I1115J-1928D01*
G01X411474Y1084923D01*
G02X412587Y1083051I-1112J-1928D01*
G01Y1082995D01*
G03X413290Y1081738I1475J0D01*
G01X413325Y1081718D01*
G03X414799I737J1277D01*
G01X414840Y1081742D01*
G02X417024Y1081718I1071J-1951D01*
G03X418498I737J1277D01*
G01X418539Y1081742D01*
G02X420725Y1081718I1072J-1951D01*
G02X421836Y1079852I-1114J-1927D01*
G01Y1079791D01*
G03X422539Y1078534I1475J0D01*
G01X422574Y1078514D01*
X422598Y1078500D01*
G02Y1074674I-1136J-1913D01*
G01X422574Y1074660D01*
X422539Y1074640D01*
G03X421836Y1073383I772J-1257D01*
G03X422387Y1072234I1475J1D01*
G01X422695Y1072316D01*
X423311Y1073383D01*
G01X421462Y1070178D02*
X422078Y1071245D01*
X421983Y1071596D01*
G02X421086Y1073327I1328J1786D01*
G01Y1073383D01*
G02X422175Y1075296I2225J0D01*
G01X422188Y1075304D01*
X422199Y1075310D01*
X422234Y1075330D01*
G03Y1077844I-772J1257D01*
G01X422199Y1077864D01*
X422175Y1077878D01*
G02X421086Y1079791I1136J1913D01*
G03X420383Y1081048I-1475J0D01*
G01X420348Y1081068D01*
G03X418874I-737J-1277D01*
G02X416648I-1113J1927D01*
G03X415174I-737J-1277D01*
G01X415116Y1081034D01*
G02X412948Y1081068I-1054J1961D01*
G02X411837Y1082934I1114J1927D01*
G01Y1082995D01*
G03X411134Y1084252I-1475J0D01*
G01X411099Y1084272D01*
G03X409625I-737J-1277D01*
G02X407457Y1084238I-1115J1928D01*
G01X407399Y1084272D01*
G03X405925I-737J-1277D01*
G02X403757Y1084238I-1115J1928D01*
G01X403699Y1084272D01*
G03X402225I-737J-1277D01*
G02X400057Y1084238I-1115J1928D01*
G01X399999Y1084272D01*
G03X398525I-737J-1277D01*
G02X396299I-1113J1928D01*
G03X394825I-737J-1277D01*
G02X392657Y1084238I-1115J1928D01*
G01X392599Y1084272D01*
G03X391125I-737J-1277D01*
G02X388939Y1084248I-1114J1928D01*
G01X388898Y1084272D01*
G03X387424I-737J-1277D01*
G02X385240Y1084248I-1113J1928D01*
G01X385199Y1084272D01*
G03X383725I-737J-1277D01*
G02X381557Y1084238I-1115J1928D01*
G01X381499Y1084272D01*
G03X380025I-737J-1277D01*
G02X377857Y1084238I-1115J1928D01*
G01X377799Y1084272D01*
G03X376325I-737J-1277D01*
G02X374157Y1084238I-1115J1928D01*
G01X374099Y1084272D01*
G03X372625I-737J-1277D01*
G02X370399I-1113J1928D01*
G03X368925I-737J-1277D01*
G02X366757Y1084238I-1115J1928D01*
G01X366699Y1084272D01*
G03X365225I-737J-1277D01*
G02X363039Y1084248I-1114J1928D01*
G01X362998Y1084272D01*
G03X361524I-737J-1277D01*
G02X359340Y1084248I-1113J1928D01*
G01X359299Y1084272D01*
G03X357825I-737J-1277D01*
G02X355639Y1084248I-1114J1928D01*
G01X355598Y1084272D01*
G03X354124I-737J-1277D01*
G02X351898I-1113J1928D01*
G03X350424I-737J-1277D01*
G02X348198I-1113J1928D01*
G03X346724I-737J-1277D01*
G02X344538Y1084248I-1114J1928D01*
G01X344497Y1084272D01*
G03X343023I-737J-1277D01*
G01X342965Y1084238D01*
G02X340797Y1084272I-1053J1962D01*
G03X340060Y1084473I-744J-1275D01*
G01X334806D01*
X333577Y1085702D01*
X332522D01*
X332442Y1085622D01*
X332355D01*
G01X435829Y909057D02*
X435503Y906320D01*
G03X435453Y905853I2175J-469D01*
G02X434750Y904596I-1475J0D01*
G01X434737Y904589D01*
X434715Y904576D01*
G03X433604Y902710I1114J-1927D01*
G01Y902649D01*
G02X432901Y901392I-1475J0D01*
G01X432866Y901372D01*
X432842Y901358D01*
G03X431753Y899445I1136J-1913D01*
G02X431050Y898188I-1475J0D01*
G01X431015Y898168D01*
G03X429904Y896327I1114J-1928D01*
G01Y896179D01*
G03X431015Y894313I2225J61D01*
G01X431050Y894293D01*
G02Y891779I-772J-1257D01*
G01X431015Y891759D01*
G02X429541I-737J1277D01*
G01X429500Y891783D01*
G03X427316Y891759I-1071J-1951D01*
G03X426204Y889871I1113J-1927D01*
G01Y889832D01*
G02X425501Y888575I-1475J0D01*
G01X425466Y888555D01*
G03X424353Y886683I1112J-1928D01*
G01Y886627D01*
G02X423650Y885370I-1475J0D01*
G01X423615Y885350D01*
G03X422504Y883484I1114J-1927D01*
G01Y883362D01*
G03X423615Y881496I2225J61D01*
G01X423650Y881476D01*
G02Y878962I-772J-1257D01*
G01X423615Y878942D01*
G03X422504Y877101I1114J-1928D01*
G01Y877014D01*
G02X421801Y875757I-1475J0D01*
G01X421766Y875737D01*
G02X420292I-737J1277D01*
G03X418124Y875771I-1114J-1927D01*
G01X418066Y875737D01*
X418042Y875723D01*
G03X416953Y873810I1136J-1913D01*
G02X416250Y872553I-1475J0D01*
G01X416215Y872533D01*
G03X415104Y870667I1114J-1927D01*
G01Y870606D01*
G02X414401Y869349I-1475J0D01*
G01X414366Y869329D01*
G02X412892I-737J1277D01*
G03X410666I-1113J-1928D01*
G03X409553Y867431I1113J-1928D01*
G01Y867401D01*
G02X408850Y866144I-1475J0D01*
G01X408815Y866124D01*
G02X407341I-737J1277D01*
G01X407300Y866148D01*
G03X405116Y866124I-1071J-1951D01*
G02X403642I-737J1277D01*
G01X403601Y866148D01*
G03X401415Y866124I-1072J-1951D01*
G02X399941I-737J1277D01*
G01X399900Y866148D01*
G03X397716Y866124I-1071J-1951D01*
G02X396242I-737J1277D01*
G01X396201Y866148D01*
G03X394015Y866124I-1072J-1951D01*
G02X392541I-737J1277D01*
G01X392500Y866148D01*
G03X390316Y866124I-1071J-1951D01*
G02X388842I-737J1277D01*
G01X388801Y866148D01*
G03X386615Y866124I-1072J-1951D01*
G02X385141I-737J1277D01*
G01X385100Y866148D01*
G03X382916Y866124I-1071J-1951D01*
G02X381442I-737J1277D01*
G01X381401Y866148D01*
G03X379215Y866124I-1072J-1951D01*
G02X377741I-737J1277D01*
G01X377700Y866148D01*
G03X375516Y866124I-1071J-1951D01*
G02X374042I-737J1277D01*
G01X374001Y866148D01*
G03X371815Y866124I-1072J-1951D01*
G02X370341I-737J1277D01*
G01X370300Y866148D01*
G03X368116Y866124I-1071J-1951D01*
G02X366642I-737J1277D01*
G01X366601Y866148D01*
G03X364415Y866124I-1072J-1951D01*
G02X362941I-737J1277D01*
G01X362900Y866148D01*
G03X360716Y866124I-1071J-1951D01*
G02X359242I-737J1277D01*
G01X359201Y866148D01*
G03X357015Y866124I-1072J-1951D01*
G02X355541I-737J1277D01*
G01X355500Y866148D01*
G03X353316Y866124I-1071J-1951D01*
G02X351842I-737J1277D01*
G03X349616I-1113J-1927D01*
G03X348504Y864236I1113J-1927D01*
G01Y864197D01*
G02X347801Y862940I-1475J0D01*
G01X347766Y862920D01*
G03X346654Y861032I1113J-1927D01*
G01Y860993D01*
G02X345951Y859736I-1475J0D01*
G01X345916Y859716D01*
X345868Y859688D01*
G03X344803Y857789I1161J-1899D01*
G02X344123Y856546I-1476J0D01*
G01X344064Y856512D01*
G03X342953Y854671I1114J-1928D01*
G01Y854584D01*
G02X342250Y853327I-1475J0D01*
G01X342215Y853307D01*
G03X341104Y851442I1113J-1926D01*
G01X341103Y851381D01*
Y850688D01*
X338546Y848131D01*
G01X443229Y909057D02*
G03X441138Y908191I0J-2957D01*
G01X440942Y907995D01*
G02X439825Y907532I-1117J1116D01*
G01X437926D01*
G03X437311Y907358I0J-1175D01*
G01X436907Y907110D01*
G03X436204Y905853I772J-1257D01*
G02X435116Y903940I-2226J0D01*
G01X435092Y903926D01*
X435057Y903906D01*
G03X434354Y902649I772J-1257D01*
G02X433265Y900736I-2225J0D01*
G01X433241Y900722D01*
X433206Y900702D01*
G03X432503Y899445I772J-1257D01*
G01Y899358D01*
G02X431392Y897517I-2225J87D01*
G01X431357Y897497D01*
G03Y894983I772J-1257D01*
G01X431392Y894963D01*
X431416Y894949D01*
G02Y891123I-1138J-1913D01*
G01X431392Y891109D01*
G02X429224Y891075I-1114J1927D01*
G01X429166Y891109D01*
G03X427692I-737J-1277D01*
G01X427657Y891089D01*
G03X426954Y889832I772J-1257D01*
G01Y889776D01*
G02X425841Y887904I-2225J56D01*
G01X425806Y887884D01*
G03X425103Y886627I772J-1257D01*
G01Y886566D01*
G02X423992Y884700I-2225J61D01*
G01X423957Y884680D01*
G03Y882166I772J-1257D01*
G01X423992Y882146D01*
X424016Y882132D01*
G02X425104Y880219I-1138J-1913D01*
G01Y880163D01*
G02X423992Y878291I-2226J56D01*
G01X423957Y878271D01*
G03X423254Y877014I772J-1257D01*
G02X422165Y875101I-2225J0D01*
G01X422141Y875087D01*
X422083Y875053D01*
G02X419915Y875087I-1054J1961D01*
G03X418441I-737J-1277D01*
G01X418406Y875067D01*
G03X417703Y873810I772J-1257D01*
G01Y873749D01*
G02X416592Y871883I-2225J61D01*
G01X416557Y871863D01*
G03X415854Y870606I772J-1257D01*
G01Y870550D01*
G02X414741Y868678I-2225J56D01*
G01X414700Y868654D01*
G02X412516Y868678I-1071J1952D01*
G03X411042I-737J-1277D01*
G01X411007Y868658D01*
G03X410304Y867401I772J-1257D01*
G02X409216Y865488I-2226J0D01*
G01X409192Y865474D01*
G02X407024Y865440I-1114J1927D01*
G01X406966Y865474D01*
G03X405492I-737J-1277D01*
G02X403266I-1113J1927D01*
G03X401792I-737J-1277D01*
G02X399624Y865440I-1114J1927D01*
G01X399566Y865474D01*
G03X398092I-737J-1277D01*
G02X395866I-1113J1927D01*
G03X394392I-737J-1277D01*
G02X392224Y865440I-1114J1927D01*
G01X392166Y865474D01*
G03X390692I-737J-1277D01*
G02X388466I-1113J1927D01*
G03X386992I-737J-1277D01*
G02X384824Y865440I-1114J1927D01*
G01X384766Y865474D01*
G03X383292I-737J-1277D01*
G02X381066I-1113J1927D01*
G03X379592I-737J-1277D01*
G02X377424Y865440I-1114J1927D01*
G01X377366Y865474D01*
G03X375892I-737J-1277D01*
G02X373666I-1113J1927D01*
G03X372192I-737J-1277D01*
G02X370024Y865440I-1114J1927D01*
G01X369966Y865474D01*
G03X368492I-737J-1277D01*
G02X366266I-1113J1927D01*
G03X364792I-737J-1277D01*
G02X362624Y865440I-1114J1927D01*
G01X362566Y865474D01*
G03X361092I-737J-1277D01*
G02X358866I-1113J1927D01*
G03X357392I-737J-1277D01*
G02X355224Y865440I-1114J1927D01*
G01X355166Y865474D01*
G03X353692I-737J-1277D01*
G02X351466I-1113J1927D01*
G03X349992I-737J-1277D01*
G01X349957Y865454D01*
G03X349254Y864197I772J-1257D01*
G01Y864158D01*
G02X348142Y862270I-2225J39D01*
G01X348107Y862250D01*
G03X347404Y860993I772J-1257D01*
G01Y860954D01*
G02X346292Y859066I-2225J39D01*
G01X346233Y859032D01*
G03X345553Y857789I796J-1243D01*
G01Y857733D01*
G02X344441Y855861I-2226J56D01*
G01X344406Y855841D01*
G03X343703Y854584I772J-1257D01*
G02X342614Y852671I-2225J0D01*
G01X342590Y852657D01*
G03X341853Y851414I737J-1277D01*
G01Y849123D01*
X340423Y847693D01*
G01X439529Y915466D02*
X440246Y916006D01*
X440746Y916382D01*
X441246Y916759D01*
X442003Y917329D01*
X442116Y917393D01*
G02X444340I1112J-1926D01*
G01X444341D01*
Y917392D01*
G02X445454Y915466I-1111J-1927D01*
G01Y915464D01*
G02X444343Y913539I-2223J0D01*
G01X444308Y913519D01*
G03Y911005I772J-1257D01*
G01X444343Y910985D01*
G02X445454Y909144I-1114J-1928D01*
G01Y908996D01*
G02X444343Y907130I-2225J61D01*
G01X444308Y907110D01*
G03X443605Y905853I772J-1257D01*
G01X443604D01*
Y905814D01*
G02X442492Y903926I-2225J39D01*
G01X442457Y903906D01*
G03X441754Y902649I772J-1257D01*
G02X440689Y900750I-2226J0D01*
G01X440641Y900722D01*
G03X439904Y899479I737J-1277D01*
G01Y899372D01*
G02X438792Y897517I-2225J73D01*
G01X438757Y897497D01*
G03X438054Y896240I772J-1257D01*
G02X436965Y894327I-2225J0D01*
G01X436941Y894313D01*
G03X436204Y893070I737J-1277D01*
G01Y892997D01*
G02X435092Y891109I-2225J39D01*
G01X435057Y891089D01*
G03X434354Y889832I772J-1257D01*
G01Y889776D01*
G02X433241Y887904I-2225J56D01*
G01X433206Y887884D01*
G03X432503Y886627I772J-1257D01*
G01Y886566D01*
G02X431392Y884700I-2225J61D01*
G01X431357Y884680D01*
G03Y882166I772J-1257D01*
G01X431392Y882146D01*
X431416Y882132D01*
G02X432504Y880219I-1138J-1913D01*
G01Y880163D01*
G02X431392Y878291I-2226J56D01*
G01X431357Y878271D01*
G03X430654Y877014I772J-1257D01*
G02X429565Y875101I-2225J0D01*
G01X429541Y875087D01*
X429483Y875053D01*
G02X427315Y875087I-1054J1961D01*
G03X425841I-737J-1277D01*
G01X425806Y875067D01*
G03X425103Y873810I772J-1257D01*
G01Y873749D01*
G02X423992Y871883I-2225J61D01*
G01X423957Y871863D01*
G03X423254Y870606I772J-1257D01*
G01Y870550D01*
G02X422141Y868678I-2225J56D01*
G03X421404Y867435I737J-1277D01*
G01Y867362D01*
G02X420292Y865474I-2225J39D01*
G02X418066I-1113J1927D01*
G03X416592I-737J-1277D01*
G02X414424Y865440I-1114J1927D01*
G01X414366Y865474D01*
G03X412892I-737J-1277D01*
G01X412857Y865454D01*
G03X412154Y864197I772J-1257D01*
G02X411065Y862284I-2225J0D01*
G01X411041Y862270D01*
X410983Y862236D01*
G02X408815Y862270I-1054J1961D01*
G03X407341I-737J-1277D01*
G01X407283Y862236D01*
G02X405115Y862270I-1054J1961D01*
G03X403641I-737J-1277D01*
G01X403583Y862236D01*
G02X401415Y862270I-1054J1961D01*
G03X399941I-737J-1277D01*
G01X399883Y862236D01*
G02X397715Y862270I-1054J1961D01*
G03X396241I-737J-1277D01*
G01X396183Y862236D01*
G02X394015Y862270I-1054J1961D01*
G03X392541I-737J-1277D01*
G01X392483Y862236D01*
G02X390315Y862270I-1054J1961D01*
G03X388841I-737J-1277D01*
G01X388783Y862236D01*
G02X386615Y862270I-1054J1961D01*
G03X385141I-737J-1277D01*
G01X385083Y862236D01*
G02X382915Y862270I-1054J1961D01*
G03X381441I-737J-1277D01*
G01X381383Y862236D01*
G02X379215Y862270I-1054J1961D01*
G03X377741I-737J-1277D01*
G01X377683Y862236D01*
G02X375515Y862270I-1054J1961D01*
G03X374041I-737J-1277D01*
G01X373983Y862236D01*
G02X371815Y862270I-1054J1961D01*
G03X370341I-737J-1277D01*
G01X370283Y862236D01*
G02X368115Y862270I-1054J1961D01*
G03X366641I-737J-1277D01*
G01X366583Y862236D01*
G02X364415Y862270I-1054J1961D01*
G03X362941I-737J-1277D01*
G01X362883Y862236D01*
G02X360715Y862270I-1054J1961D01*
G03X359241I-737J-1277D01*
G01X359183Y862236D01*
G02X357015Y862270I-1054J1961D01*
G03X355541I-737J-1277D01*
G01X355483Y862236D01*
G02X353315Y862270I-1054J1961D01*
G03X351841I-737J-1277D01*
G03X351104Y861027I737J-1277D01*
G01Y860954D01*
G02X349992Y859066I-2225J39D01*
G01X349957Y859046D01*
G03X349254Y857789I772J-1257D01*
G01Y857733D01*
G02X348141Y855861I-2225J56D01*
G01X348106Y855841D01*
G03X347403Y854584I772J-1257D01*
G02X346314Y852671I-2225J0D01*
G01X346290Y852657D01*
X346255Y852637D01*
G03X345552Y851380I772J-1257D01*
G01Y851319D01*
G02X344441Y849453I-2225J61D01*
G01X344406Y849433D01*
G03X343703Y848176I772J-1257D01*
G01Y846354D01*
G01X443229Y915466D02*
X443146Y914784D01*
X443046Y913963D01*
X442855Y912394D01*
Y912175D01*
G03X443966Y910334I2225J87D01*
G01X444001Y910314D01*
G02Y907800I-772J-1257D01*
G01X443966Y907780D01*
G03X442855Y905914I1114J-1927D01*
G01Y905853D01*
X442854D01*
G02X442151Y904596I-1475J0D01*
G01X442116Y904576D01*
X442068Y904548D01*
G03X441003Y902649I1161J-1899D01*
G02X440300Y901392I-1475J0D01*
G01X440265Y901372D01*
G03X439153Y899484I1113J-1927D01*
G01Y899411D01*
G02X438416Y898168I-1474J34D01*
G03X437304Y896313I1113J-1928D01*
G01Y896240D01*
G02X436601Y894983I-1475J0D01*
G01X436566Y894963D01*
X436542Y894949D01*
G03X435453Y893036I1136J-1913D01*
G01Y893002D01*
G02X434716Y891759I-1474J34D01*
G03X433604Y889871I1113J-1927D01*
G01Y889832D01*
G02X432901Y888575I-1475J0D01*
G01X432866Y888555D01*
G03X431753Y886683I1112J-1928D01*
G01Y886627D01*
G02X431050Y885370I-1475J0D01*
G01X431015Y885350D01*
G03X429904Y883484I1114J-1927D01*
G01Y883362D01*
G03X431015Y881496I2225J61D01*
G01X431050Y881476D01*
G02Y878962I-772J-1257D01*
G01X431015Y878942D01*
G03X429904Y877101I1114J-1928D01*
G01Y877014D01*
G02X429201Y875757I-1475J0D01*
G01X429166Y875737D01*
G02X427692I-737J1277D01*
G03X425524Y875771I-1114J-1927D01*
G01X425466Y875737D01*
X425442Y875723D01*
G03X424353Y873810I1136J-1913D01*
G02X423650Y872553I-1475J0D01*
G01X423615Y872533D01*
G03X422504Y870667I1114J-1927D01*
G01Y870606D01*
G02X421801Y869349I-1475J0D01*
G01X421766Y869329D01*
G03X420653Y867457I1112J-1928D01*
G01Y867367D01*
G02X419916Y866124I-1474J34D01*
G02X418442I-737J1277D01*
G01X418401Y866148D01*
G03X416215Y866124I-1072J-1951D01*
G02X414741I-737J1277D01*
G01X414700Y866148D01*
G03X412516Y866124I-1071J-1951D01*
G03X411404Y864236I1113J-1927D01*
G01Y864197D01*
G02X410701Y862940I-1475J0D01*
G01X410666Y862920D01*
G02X409192I-737J1277D01*
G03X407024Y862954I-1114J-1927D01*
G01X406966Y862920D01*
G02X405492I-737J1277D01*
G03X403324Y862954I-1114J-1927D01*
G01X403266Y862920D01*
G02X401792I-737J1277D01*
G03X399624Y862954I-1114J-1927D01*
G01X399566Y862920D01*
G02X398092I-737J1277D01*
G03X395924Y862954I-1114J-1927D01*
G01X395866Y862920D01*
G02X394392I-737J1277D01*
G03X392224Y862954I-1114J-1927D01*
G01X392166Y862920D01*
G02X390692I-737J1277D01*
G03X388524Y862954I-1114J-1927D01*
G01X388497Y862938D01*
X388466Y862920D01*
G02X386992I-737J1277D01*
G03X384824Y862954I-1114J-1927D01*
G01X384766Y862920D01*
G02X383292I-737J1277D01*
G03X381124Y862954I-1114J-1927D01*
G01X381066Y862920D01*
G02X379592I-737J1277D01*
G03X377424Y862954I-1114J-1927D01*
G01X377366Y862920D01*
G02X375892I-737J1277D01*
G03X373724Y862954I-1114J-1927D01*
G01X373666Y862920D01*
G02X372192I-737J1277D01*
G03X370024Y862954I-1114J-1927D01*
G01X369966Y862920D01*
G02X368492I-737J1277D01*
G03X366324Y862954I-1114J-1927D01*
G01X366266Y862920D01*
G02X364792I-737J1277D01*
G03X362624Y862954I-1114J-1927D01*
G01X362566Y862920D01*
G02X361092I-737J1277D01*
G03X358924Y862954I-1114J-1927D01*
G01X358866Y862920D01*
G02X357392I-737J1277D01*
G03X355224Y862954I-1114J-1927D01*
G01X355166Y862920D01*
G02X353692I-737J1277D01*
G03X351524Y862954I-1114J-1927D01*
G01X351466Y862920D01*
X351442Y862906D01*
G03X350353Y860993I1136J-1913D01*
G01Y860959D01*
G02X349616Y859716I-1474J34D01*
G03X348504Y857828I1113J-1927D01*
G01Y857789D01*
G02X347801Y856532I-1475J0D01*
G01X347766Y856512D01*
G03X346653Y854640I1112J-1928D01*
G01Y854584D01*
G02X345950Y853327I-1475J0D01*
G01X345915Y853307D01*
X345891Y853293D01*
G03X344802Y851380I1136J-1913D01*
G02X344099Y850123I-1475J0D01*
G01X344064Y850103D01*
G03X342953Y848237I1114J-1927D01*
G01X342603Y847887D01*
G01X401111Y1047749D02*
X398336Y1046146D01*
G02X396486I-925J1603D01*
G01X396433Y1046177D01*
G03X394636Y1046146I-871J-1633D01*
G02X392786I-925J1603D01*
G01X392733Y1046177D01*
G03X390936Y1046146I-871J-1633D01*
G02X389086I-925J1603D01*
G03X387236I-925J-1602D01*
G02X385386I-925J1603D01*
G01X385333Y1046177D01*
G03X383536Y1046146I-871J-1633D01*
G02X381686I-925J1603D01*
G01X381633Y1046177D01*
G03X379836Y1046146I-871J-1633D01*
G02X377986I-925J1603D01*
G01X377933Y1046177D01*
G03X376136Y1046146I-871J-1633D01*
G02X374286I-925J1603D01*
G01X374233Y1046177D01*
G03X372436Y1046146I-871J-1633D01*
G02X370586I-925J1603D01*
G01X370533Y1046177D01*
G03X368736Y1046146I-871J-1633D01*
G02X366886I-925J1603D01*
G01X366833Y1046177D01*
G03X365036Y1046146I-871J-1633D01*
G02X363186I-925J1603D01*
G03X361336I-925J-1602D01*
G02X359486I-925J1603D01*
G01X359433Y1046177D01*
G03X357636Y1046146I-871J-1633D01*
G02X355786I-925J1603D01*
G03X353936I-925J-1602D01*
G02X352086I-925J1603D01*
G03X350236I-925J-1602D01*
G02X348386I-925J1603D01*
G03X346536I-925J-1602D01*
G02X344686I-925J1603D01*
G03X343761Y1046394I-925J-1601D01*
G01X346780Y1055058D02*
X347617Y1055895D01*
G03X348199Y1056084I-154J1466D01*
G02X350425I1113J-1927D01*
G03X351899I737J1277D01*
G02X354067Y1056118I1114J-1927D01*
G01X354125Y1056084D01*
G03X355599I737J1277D01*
G02X357825I1113J-1927D01*
G03X359299I737J1277D01*
G02X361467Y1056118I1114J-1927D01*
G01X361525Y1056084D01*
G03X362999I737J1277D01*
G02X365185Y1056108I1114J-1927D01*
G01X365226Y1056084D01*
G03X366700I737J1277D01*
G02X368884Y1056108I1113J-1927D01*
G01X368925Y1056084D01*
G03X370399I737J1277D01*
G02X372567Y1056118I1114J-1927D01*
G01X372625Y1056084D01*
G03X374099I737J1277D01*
G02X376267Y1056118I1114J-1927D01*
G01X376325Y1056084D01*
G03X377799I737J1277D01*
G02X379967Y1056118I1114J-1927D01*
G01X380025Y1056084D01*
G03X381499I737J1277D01*
G02X383725I1113J-1927D01*
G03X385199I737J1277D01*
G02X387367Y1056118I1114J-1927D01*
G01X387425Y1056084D01*
G03X388899I737J1277D01*
G02X391085Y1056108I1114J-1927D01*
G01X391126Y1056084D01*
G03X392600I737J1277D01*
G02X394826I1113J-1927D01*
G03X396300I737J1277D01*
G02X398484Y1056108I1113J-1927D01*
G01X398525Y1056084D01*
G03X399999I737J1277D01*
G02X402167Y1056118I1114J-1927D01*
G01X402225Y1056084D01*
G03X403495Y1055987I736J1277D01*
G01X403578Y1056294D01*
X402962Y1057361D01*
G01X430278Y873810D02*
X431509D01*
X431768Y874069D01*
G02X435092Y875737I2211J-260D01*
G03X436566I737J1277D01*
G02X438792I1113J-1927D01*
G03X439411Y875535I790J1370D01*
G03X439627Y875526I174J1572D01*
G01X439630D01*
G03X440187Y875685I-30J1159D01*
G01X440566Y875907D01*
G03X441004Y876672I-448J764D01*
G01Y877087D01*
G02X442116Y878942I2225J-73D01*
G01X442117Y878941D01*
G03X442854Y880160I-738J1278D01*
G01Y880223D01*
X442853Y880222D01*
G03X442112Y881502I-1475J0D01*
G01X442071Y881525D01*
G02X442027Y885296I1148J1899D01*
G02X442116Y885350I1198J-1875D01*
G02X444306Y885371I1114J-1927D01*
G01X444341Y885350D01*
G03X445815I737J1277D01*
G01X445850Y885370D01*
G03X446553Y886627I-772J1257D01*
G01Y886683D01*
G02X447666Y888555I2225J-56D01*
G01X447724Y888589D01*
G02X449892Y888555I1053J-1962D01*
G03X451366I737J1277D01*
G01X451424Y888589D01*
G02X453592Y888555I1053J-1962D01*
G03X455066I737J1277D01*
G01X455124Y888589D01*
G02X457292Y888555I1053J-1962D01*
G03X458766I737J1277D01*
G01X458824Y888589D01*
G02X460992Y888555I1053J-1962D01*
G03X462466I737J1277D01*
G01X462524Y888589D01*
G02X464692Y888555I1053J-1962D01*
G03X466166I737J1277D01*
G01X466224Y888589D01*
G02X468392Y888555I1053J-1962D01*
G03X469866I737J1277D01*
G01X469924Y888589D01*
G02X472092Y888555I1053J-1962D01*
G03X473566I737J1277D01*
G01X473624Y888589D01*
G02X475792Y888555I1053J-1962D01*
G03X477266I737J1277D01*
G01X477324Y888589D01*
G02X479492Y888555I1053J-1962D01*
G03X480966I737J1277D01*
G01X481024Y888589D01*
G02X483192Y888555I1053J-1962D01*
G03X484666I737J1277D01*
G01X484724Y888589D01*
G02X486892Y888555I1053J-1962D01*
G03X488366I737J1277D01*
G01X488424Y888589D01*
G02X490592Y888555I1053J-1962D01*
G03X492066I737J1277D01*
G01X492124Y888589D01*
G02X494292Y888555I1053J-1962D01*
G03X495766I737J1277D01*
G01X495824Y888589D01*
G02X497992Y888555I1053J-1962D01*
G03X499466I737J1277D01*
G01X499524Y888589D01*
G02X501692Y888555I1053J-1962D01*
G03X503166I737J1277D01*
G01X503224Y888589D01*
G02X505392Y888555I1053J-1962D01*
G03X506866I737J1277D01*
G01X506924Y888589D01*
G02X509092Y888555I1053J-1962D01*
G02X509143Y888523I-1157J-1901D01*
G02X510203Y886568I-1164J-1896D01*
G01X510197Y886343D01*
G02X509332Y884846I-1811J48D01*
G01X509098Y884704D01*
X509091Y884700D01*
G03X508354Y883472I738J-1278D01*
G01Y883384D01*
G02X507242Y881496I-2225J39D01*
G01X507239Y881494D01*
X507232Y881490D01*
X507229Y881488D01*
X507210Y881478D01*
X507207Y881476D01*
G03X506504Y880219I772J-1257D01*
G01Y880163D01*
G02X505392Y878291I-2226J56D01*
G01X505357Y878271D01*
G03X504704Y877393I773J-1256D01*
G03X504663Y876850I1423J-381D01*
G03X505357Y875757I1466J164D01*
G01X505392Y875737D01*
G02X506503Y873871I-1114J-1927D01*
G01Y873666D01*
G03X507120Y872602I1226J0D01*
G01X507358Y872464D01*
G02X508354Y870714I-1039J-1750D01*
G01Y870606D01*
G03X509057Y869349I1475J0D01*
G01X509092Y869329D01*
G02X510204Y867474I-1113J-1928D01*
G01Y867367D01*
G03X510941Y866124I1474J34D01*
G01X510944Y866122D01*
X511151Y866000D01*
G02X512054Y864413I-943J-1587D01*
G01Y864197D01*
G03X512757Y862940I1475J0D01*
G01X512767Y862934D01*
X512775Y862930D01*
X512792Y862920D01*
G02X513903Y861054I-1114J-1927D01*
G01Y860932D01*
G02X512792Y859066I-2225J61D01*
G01X512757Y859046D01*
G03X512054Y857789I772J-1257D01*
G01Y857733D01*
G02X510941Y855861I-2225J56D01*
G03X510204Y854618I737J-1277D01*
G01Y854545D01*
G02X509092Y852657I-2225J39D01*
G01X509057Y852637D01*
G03X508354Y851406I772J-1257D01*
G03Y851340I1475J-33D01*
G01Y851321D01*
G03X509040Y850133I1439J39D01*
G01X509355Y849951D01*
G02X510064Y849155I-846J-1467D01*
G02X510197Y848515I-1488J-643D01*
G01Y848514D01*
G03X510204Y848127I13901J58D01*
G01Y848118D01*
X510215Y847838D01*
G03X510667Y847066I949J37D01*
G01X510941Y846899D01*
G02X512052Y845058I-1114J-1928D01*
G01Y844192D01*
G02X510929Y842887I-2225J779D01*
G03X510204Y842102I750J-1420D01*
G01Y839758D01*
X510579Y839383D01*
Y838643D01*
G01X437679Y873810D02*
X438527Y874658D01*
G02X438843Y874789I316J-315D01*
G01X439330D01*
G03X439637Y874776I252J2318D01*
G01X439639D01*
G03X440567Y875037I-36J1909D01*
G01X440946Y875259D01*
G03X441754Y876673I-828J1411D01*
G01Y877014D01*
G02X442457Y878271I1475J0D01*
G01X442492Y878291D01*
G03X443604Y880146I-1113J1928D01*
G01Y880222D01*
G03X442483Y882155I-2226J1D01*
G01X442451Y882173D01*
G02X442431Y884662I768J1251D01*
G02X442491Y884699I800J-1230D01*
G01X442492Y884700D01*
G02X443966I737J-1277D01*
G01X444024Y884666D01*
G03X446192Y884700I1054J1961D01*
G03X447303Y886566I-1114J1927D01*
G01Y886627D01*
G02X448006Y887884I1475J0D01*
G01X448041Y887904D01*
G02X449515I737J-1277D01*
G03X451683Y887870I1115J1928D01*
G01X451741Y887904D01*
G02X453215I737J-1277D01*
G03X455383Y887870I1115J1928D01*
G01X455441Y887904D01*
G02X456915I737J-1277D01*
G03X459083Y887870I1115J1928D01*
G01X459141Y887904D01*
G02X460615I737J-1277D01*
G03X462783Y887870I1115J1928D01*
G01X462841Y887904D01*
G02X464315I737J-1277D01*
G03X466483Y887870I1115J1928D01*
G01X466541Y887904D01*
G02X468015I737J-1277D01*
G03X470183Y887870I1115J1928D01*
G01X470241Y887904D01*
G02X471715I737J-1277D01*
G03X473883Y887870I1115J1928D01*
G01X473941Y887904D01*
G02X475415I737J-1277D01*
G03X477583Y887870I1115J1928D01*
G01X477641Y887904D01*
G02X479115I737J-1277D01*
G03X481283Y887870I1115J1928D01*
G01X481341Y887904D01*
G02X482815I737J-1277D01*
G03X484983Y887870I1115J1928D01*
G01X485041Y887904D01*
G02X486515I737J-1277D01*
G03X488683Y887870I1115J1928D01*
G01X488741Y887904D01*
G02X490215I737J-1277D01*
G03X492383Y887870I1115J1928D01*
G01X492441Y887904D01*
G02X493915I737J-1277D01*
G03X496083Y887870I1115J1928D01*
G01X496141Y887904D01*
G02X497615I737J-1277D01*
G03X499783Y887870I1115J1928D01*
G01X499841Y887904D01*
G02X501315I737J-1277D01*
G03X503483Y887870I1115J1928D01*
G01X503541Y887904D01*
G02X505015I737J-1277D01*
G03X507183Y887870I1115J1928D01*
G01X507241Y887904D01*
G02X508715I737J-1277D01*
G01X508750Y887884D01*
G02X509452Y886685I-772J-1257D01*
G02X509453Y886587I-1474J-64D01*
G01X509447Y886363D01*
G02X508941Y885487I-1061J29D01*
G01X508715Y885350D01*
G03X507604Y883484I1114J-1927D01*
G01Y883423D01*
G02X506901Y882166I-1475J0D01*
G01X506866Y882146D01*
X506850Y882137D01*
X506845Y882134D01*
X506818Y882118D01*
G03X505753Y880219I1161J-1899D01*
G02X505754Y880181I-1474J-58D01*
G02X505018Y878942I-1476J39D01*
G01X504975Y878917D01*
G03X503979Y877586I1155J-1902D01*
G03X503917Y876767I2148J-574D01*
G03X504964Y875118I2211J247D01*
G03X505015Y875087I1181J1886D01*
G01X505027Y875080D01*
X505033Y875077D01*
X505036Y875075D01*
G02X505753Y873859I-758J-1266D01*
G01Y873666D01*
G03X506748Y871950I1977J0D01*
G01X506919Y871851D01*
X506975Y871818D01*
G02X507604Y870714I-656J-1105D01*
G01Y870606D01*
G03X508675Y868702I2226J-1D01*
G01X508717Y868679D01*
X508716Y868678D01*
G02X509453Y867435I-737J-1277D01*
G01Y867401D01*
G03X510542Y865488I2225J0D01*
G01X510566Y865474D01*
X510565D01*
X510768Y865354D01*
G02X511304Y864413I-560J-942D01*
G01Y864197D01*
G03X512379Y862291I2226J-1D01*
G01X512402Y862278D01*
X512414Y862272D01*
X512415Y862270D01*
X512433Y862260D01*
X512450Y862250D01*
G02Y859736I-773J-1257D01*
G01X512419Y859718D01*
X512415Y859716D01*
G03X511304Y857850I1114J-1927D01*
G01Y857789D01*
G02X510601Y856532I-1475J0D01*
G01X510566Y856512D01*
G03X509453Y854640I1112J-1928D01*
G01Y854550D01*
G02X508716Y853307I-1474J34D01*
G03X507604Y851421I1113J-1927D01*
G03Y851332I2225J-44D01*
G01Y851311D01*
G03X508657Y849488I2189J49D01*
G01X508980Y849301D01*
G02X509375Y848857I-472J-817D01*
G02X509447Y848513I-798J-347D01*
G03X509454Y848091I14651J32D01*
G01Y848089D01*
X509465Y847808D01*
G03X510275Y846425I1699J67D01*
G01X510558Y846254D01*
X510565Y846249D01*
G02X511302Y845041I-738J-1279D01*
G01Y844336D01*
G02X510577Y843551I-1475J635D01*
G03X509454Y842246I1102J-2084D01*
G01Y839776D01*
X509079Y839401D01*
Y838643D01*
G01X452479Y873810D02*
G03X454130Y874258I0J3267D01*
G01X454679Y874579D01*
X455414Y875069D01*
X455596Y875177D01*
G03X456554Y876859I-1000J1683D01*
G01Y877014D01*
G02X458766Y878291I1475J-1D01*
G01X458824Y878257D01*
G03X460992Y878291I1053J1962D01*
G02X462466I737J-1277D01*
G03X464692I1113J1928D01*
G02X466166I737J-1277D01*
G01X466224Y878257D01*
G03X468392Y878291I1053J1962D01*
G02X469866I737J-1277D01*
G03X472092I1113J1928D01*
G02X473566I737J-1277D01*
G01X473624Y878257D01*
G03X475792Y878291I1053J1962D01*
G02X477266I737J-1277D01*
G03X479492I1113J1928D01*
G02X480966I737J-1277D01*
G01X481024Y878257D01*
G03X483192Y878291I1053J1962D01*
G02X484666I737J-1277D01*
G03X486892I1113J1928D01*
G02X488366I737J-1277D01*
G01X488424Y878257D01*
G03X490592Y878291I1053J1962D01*
G02X492066I737J-1277D01*
G03X494292I1113J1928D01*
G02X495766I737J-1277D01*
G01X495824Y878257D01*
G03X497992Y878291I1053J1962D01*
G02X499466I737J-1277D01*
G01X499501Y878271D01*
G02X500204Y877014I-772J-1257D01*
G01Y876953D01*
G03X501315Y875087I2225J61D01*
G01X501350Y875067D01*
G02X502053Y873810I-772J-1257D01*
G03X503124Y871906I2226J-1D01*
G01X503442Y871722D01*
G02X503904Y870918I-469J-804D01*
G01Y870569D01*
G02X503201Y869349I-1475J37D01*
G01X503166Y869329D01*
G03X502053Y867457I1112J-1928D01*
G01Y867202D01*
G03X502984Y865580I1878J0D01*
G01X503166Y865474D01*
X503172Y865471D01*
X503317Y865386D01*
G02X503904Y864361I-601J-1025D01*
G01Y864136D01*
G03X505015Y862270I2225J61D01*
G01X505050Y862250D01*
G02Y859736I-773J-1257D01*
G01X505019Y859718D01*
X505015Y859716D01*
G03X503904Y857850I1114J-1927D01*
G01Y857789D01*
G02X503201Y856532I-1475J0D01*
G01X503166Y856512D01*
G03X502053Y854640I1112J-1928D01*
G01Y854550D01*
G02X501316Y853307I-1474J34D01*
G01X501269Y853280D01*
G03X500204Y851422I1151J-1894D01*
G03Y851324I2225J-49D01*
G01Y851319D01*
G03X500208Y851224I2226J46D01*
G03X501275Y849476I2221J156D01*
G01X501277Y849475D01*
X501294Y849465D01*
G02X502053Y848159I-813J-1346D01*
G01Y848143D01*
G03X502054Y848091I2225J17D01*
G01Y848089D01*
X502060Y847934D01*
G03X502984Y846359I1934J76D01*
G01X503152Y846257D01*
X503159Y846253D01*
X503165Y846249D01*
G02X503902Y845041I-738J-1279D01*
G01Y844336D01*
G02X503177Y843551I-1475J635D01*
G03X502054Y842246I1102J-2084D01*
G01Y839256D01*
X501679Y838881D01*
Y838203D01*
G01X445078Y873810D02*
G02X447354Y875557I7778J-7777D01*
G01X447666Y875737D01*
G02X449892I1113J-1927D01*
G03X451366I737J1277D01*
G02X453592I1113J-1927D01*
G03X455066I737J1277D01*
G01X455072Y875740D01*
X455089Y875749D01*
X455213Y875822D01*
G03X455804Y876860I-616J1038D01*
G01Y877015D01*
G02X459144Y878940I2226J-2D01*
G01X459190Y878912D01*
G03X460617Y878941I687J1307D01*
G02X462841I1112J-1927D01*
G03X464317I738J1278D01*
G02X466544Y878940I1113J-1927D01*
G01X466590Y878912D01*
G03X468017Y878941I687J1307D01*
G02X470241I1112J-1927D01*
G03X471717I738J1278D01*
G02X473944Y878940I1113J-1927D01*
G01X473990Y878912D01*
G03X475417Y878941I687J1307D01*
G02X477641I1112J-1927D01*
G03X479117I738J1278D01*
G02X481344Y878940I1113J-1927D01*
G01X481390Y878912D01*
G03X482817Y878941I687J1307D01*
G02X485041I1112J-1927D01*
G03X486517I738J1278D01*
G02X488744Y878940I1113J-1927D01*
G01X488790Y878912D01*
G03X490217Y878941I687J1307D01*
G02X492441I1112J-1927D01*
G03X493917I738J1278D01*
G02X496144Y878940I1113J-1927D01*
G01X496190Y878912D01*
G03X497617Y878941I687J1307D01*
G02X499840Y878942I1112J-1927D01*
G01X499883Y878918D01*
G02X500954Y877014I-1155J-1903D01*
G01Y876965D01*
G03X501689Y875738I1475J50D01*
G01X501732Y875714D01*
G02X502804Y873810I-1155J-1904D01*
G03X503507Y872551I1476J-2D01*
G01X503819Y872371D01*
G02X504654Y870918I-847J-1453D01*
G01Y870560D01*
G02X503583Y868702I-2225J45D01*
G01X503540Y868678D01*
G03X502803Y867446I738J-1278D01*
G01Y867202D01*
G03X503362Y866228I1128J0D01*
G01X503554Y866117D01*
Y866118D01*
X503697Y866034D01*
G02X504654Y864361I-983J-1672D01*
G01Y864148D01*
G03X505390Y862921I1475J50D01*
G01X505432Y862897D01*
G02X505443Y859097I-1154J-1903D01*
G02X505392Y859066I-1181J1886D01*
G01X505357Y859046D01*
G03X504654Y857789I772J-1257D01*
G01Y857733D01*
G02X503541Y855861I-2225J56D01*
G03X502804Y854618I737J-1277D01*
G01Y854545D01*
G02X501692Y852657I-2225J39D01*
G01X501652Y852634D01*
G03X500954Y851411I767J-1249D01*
G01Y851406D01*
G03Y851340I1475J-33D01*
G03X500957Y851277I1475J39D01*
G03X501657Y850123I1472J104D01*
G01X501676Y850112D01*
G02X502803Y848176I-1195J-1992D01*
G03X502804Y848118I1475J-4D01*
G01X502810Y847963D01*
G03X503374Y847000I1184J47D01*
G01X503541Y846899D01*
G02X504652Y845058I-1114J-1928D01*
G01Y844192D01*
G02X503529Y842887I-2225J779D01*
G03X502804Y842102I750J-1420D01*
G01Y839338D01*
X503179Y838963D01*
Y838203D01*
G01X437679Y925079D02*
X435205Y923216D01*
X435092Y923152D01*
X435091D01*
G02X432866I-1112J1927D01*
G03X431392I-737J-1277D01*
G02X429166I-1113J1927D01*
G03X428429Y923349I-736J-1277D01*
G01X427317D01*
G01X445078Y918670D02*
X444462Y919737D01*
X444545Y920044D01*
G02X445815Y919947I534J-1374D01*
G03X448001Y919923I1114J1928D01*
G01X448042Y919947D01*
G02X449516I737J-1277D01*
G03X451700Y919923I1113J1928D01*
G01X451741Y919947D01*
G03X452854Y921819I-1112J1928D01*
G01Y922772D01*
X453457Y923375D01*
X462857D01*
X463204Y923028D01*
Y921788D01*
G03X464315Y919947I2225J87D01*
G03X466483Y919913I1115J1928D01*
G01X466541Y919947D01*
G02X468015I737J-1277D01*
G03X470183Y919913I1115J1928D01*
G01X470241Y919947D01*
G02X471715I737J-1277D01*
G03X473883Y919913I1115J1928D01*
G01X473941Y919947D01*
G02X475415I737J-1277D01*
G01X475456Y919923D01*
G03X477642Y919947I1072J1952D01*
G02X479116I737J-1277D01*
G03X481300Y919923I1113J1928D01*
G01X481341Y919947D01*
G02X482815I737J-1277D01*
G03X485041I1113J1928D01*
G02X486515I737J-1277D01*
G03X488683Y919913I1115J1928D01*
G01X488741Y919947D01*
G02X490215I737J-1277D01*
G03X492383Y919913I1115J1928D01*
G01X492441Y919947D01*
G02X493915I737J-1277D01*
G03X496101Y919923I1114J1928D01*
G01X496142Y919947D01*
G02X497616I737J-1277D01*
G03X499800Y919923I1113J1928D01*
G01X499841Y919947D01*
G02X501315I737J-1277D01*
G03X503483Y919913I1115J1928D01*
G01X503541Y919947D01*
G02X505015I737J-1277D01*
G03X507183Y919913I1115J1928D01*
G01X507241Y919947D01*
G02X508715I737J-1277D01*
G03X510941I1113J1928D01*
G02X512415I737J-1277D01*
G03X514583Y919913I1115J1928D01*
G01X514641Y919947D01*
G02X516115I737J-1277D01*
G03X518283Y919913I1115J1928D01*
G01X518341Y919947D01*
G02X519815I737J-1277D01*
G03X522001Y919923I1114J1928D01*
G01X522042Y919947D01*
G02X523516I737J-1277D01*
G03X525742I1113J1928D01*
G02X527216I737J-1277D01*
G03X529442I1113J1928D01*
G02X530916I737J-1277D01*
G03X533142I1113J1928D01*
G02X534616I737J-1277D01*
G03X536842I1113J1928D01*
G02X537579Y920144I736J-1277D01*
G01X540334D01*
X540337Y920147D01*
X541337D01*
G01X443229Y921875D02*
X443845Y920808D01*
X444195Y920715D01*
G02X446192Y920598I882J-2045D01*
G03X447666I737J1277D01*
G02X449892I1113J-1928D01*
G03X452104Y921875I737J1277D01*
G01Y923082D01*
X453146Y924124D01*
X463203D01*
X463954Y923373D01*
Y921875D01*
G03X464657Y920618I1475J0D01*
G01X464692Y920598D01*
G03X466166I737J1277D01*
G01X466224Y920632D01*
G02X468392Y920598I1053J-1962D01*
G03X469866I737J1277D01*
G01X469924Y920632D01*
G02X472092Y920598I1053J-1962D01*
G03X473566I737J1277D01*
G01X473607Y920622D01*
G02X475791Y920598I1071J-1952D01*
G03X477265I737J1277D01*
G02X479451Y920622I1114J-1928D01*
G01X479492Y920598D01*
G03X480966I737J1277D01*
G01X481007Y920622D01*
G02X483191Y920598I1071J-1952D01*
G03X484665I737J1277D01*
G01X484706Y920622D01*
G02X486892Y920598I1072J-1952D01*
G03X488366I737J1277D01*
G01X488424Y920632D01*
G02X490592Y920598I1053J-1962D01*
G03X492066I737J1277D01*
G01X492124Y920632D01*
G02X494292Y920598I1053J-1962D01*
G03X495766I737J1277D01*
G02X497992I1113J-1928D01*
G03X499466I737J1277D01*
G01X499524Y920632D01*
G02X501692Y920598I1053J-1962D01*
G03X503166I737J1277D01*
G01X503224Y920632D01*
G02X505392Y920598I1053J-1962D01*
G03X506866I737J1277D01*
G01X506907Y920622D01*
G02X509091Y920598I1071J-1952D01*
G03X510565I737J1277D01*
G01X510606Y920622D01*
G02X512792Y920598I1072J-1952D01*
G03X514266I737J1277D01*
G01X514324Y920632D01*
G02X516492Y920598I1053J-1962D01*
G03X517966I737J1277D01*
G01X518024Y920632D01*
G02X520192Y920598I1053J-1962D01*
G03X521666I737J1277D01*
G02X523892I1113J-1928D01*
G03X525366I737J1277D01*
G02X527592I1113J-1928D01*
G03X529066I737J1277D01*
G02X531292I1113J-1928D01*
G03X532766I737J1277D01*
G02X534992I1113J-1928D01*
G03X536466I737J1277D01*
G02X539554Y921425I3088J-5351D01*
G01X542117D01*
X542797Y922105D01*
G01X456327Y926551D02*
X455577Y925801D01*
X453213D01*
X451267Y923855D01*
X450004D01*
X448780Y925079D01*
G01X544899Y1032898D02*
X543318Y1034479D01*
Y1035630D01*
X543008Y1035940D01*
G03X540974Y1036208I-1192J-1192D01*
G02X538748I-1113J1928D01*
G03X537274I-737J-1277D01*
G02X535048I-1113J1928D01*
G03X533574I-737J-1277D01*
G02X531348I-1113J1928D01*
G03X529874I-737J-1277D01*
G01X529816Y1036174D01*
G02X527648Y1036208I-1053J1962D01*
G03X526174I-737J-1277D01*
G01X526116Y1036174D01*
G02X523948Y1036208I-1053J1962D01*
G03X522474I-737J-1277D01*
G01X522433Y1036184D01*
G02X520249Y1036208I-1071J1952D01*
G03X518775I-737J-1277D01*
G01X518734Y1036184D01*
G02X516548Y1036208I-1072J1952D01*
G03X515074I-737J-1277D01*
G01X515016Y1036174D01*
G02X512848Y1036208I-1053J1962D01*
G03X511374I-737J-1277D01*
G02X509148I-1113J1928D01*
G03X507674I-737J-1277D01*
G01X507616Y1036174D01*
G02X505448Y1036208I-1053J1962D01*
G03X503974I-737J-1277D01*
G01X503916Y1036174D01*
G02X501748Y1036208I-1053J1962D01*
G03X500274I-737J-1277D01*
G01X500216Y1036174D01*
G02X498048Y1036208I-1053J1962D01*
G03X496574I-737J-1277D01*
G01X496533Y1036184D01*
G02X494349Y1036208I-1071J1952D01*
G03X492875I-737J-1277D01*
G01X492834Y1036184D01*
G02X490648Y1036208I-1072J1952D01*
G03X489174I-737J-1277D01*
G01X489116Y1036174D01*
G02X486948Y1036208I-1053J1962D01*
G03X485474I-737J-1277D01*
G02X483290Y1036184I-1113J1928D01*
G01X483249Y1036208D01*
G03X481775I-737J-1277D01*
G01X481734Y1036184D01*
G02X479548Y1036208I-1072J1952D01*
G03X478810Y1036409I-744J-1275D01*
G01X478677D01*
X475987Y1039099D01*
X470139D01*
X469186Y1040052D01*
Y1041340D01*
G03X468483Y1042597I-1475J0D01*
G01X468448Y1042617D01*
G03X466974I-737J-1277D01*
G02X464748I-1113J1927D01*
G03X463274I-737J-1277D01*
G01X463216Y1042583D01*
G02X461048Y1042617I-1054J1961D01*
G03X459574I-737J-1277D01*
G01X459516Y1042583D01*
G02X457348Y1042617I-1054J1961D01*
G03X455874I-737J-1277D01*
G01X455816Y1042583D01*
G02X453648Y1042617I-1054J1961D01*
G01X453624Y1042631D01*
G02X452536Y1044544I1138J1913D01*
G03X451833Y1045801I-1475J0D01*
G01X451798Y1045821D01*
G02X450686Y1047709I1113J1927D01*
G01Y1047748D01*
G03X449983Y1049005I-1475J0D01*
G01X449948Y1049025D01*
X449924Y1049039D01*
G02X448836Y1050952I1138J1913D01*
G01Y1051008D01*
G02X449948Y1052880I2226J-56D01*
G02X451945Y1052997I1115J-1928D01*
G01X452295Y1053090D01*
X452911Y1054157D01*
G01X550040Y1036699D02*
Y1036735D01*
X548799Y1037249D01*
X542054D01*
G03X540598Y1036859I0J-2912D01*
G02X539124I-737J1277D01*
G03X536898I-1113J-1928D01*
G02X535424I-737J1277D01*
G03X533198I-1113J-1928D01*
G02X531724I-737J1277D01*
G03X529540Y1036883I-1113J-1928D01*
G01X529499Y1036859D01*
G02X528025I-737J1277D01*
G03X525857Y1036893I-1115J-1928D01*
G01X525799Y1036859D01*
G02X524325I-737J1277D01*
G03X522157Y1036893I-1115J-1928D01*
G01X522099Y1036859D01*
G02X520625I-737J1277D01*
G03X518399I-1113J-1928D01*
G02X516925I-737J1277D01*
G03X514757Y1036893I-1115J-1928D01*
G01X514699Y1036859D01*
G02X513225I-737J1277D01*
G03X511039Y1036883I-1114J-1928D01*
G01X510998Y1036859D01*
G02X509524I-737J1277D01*
G03X507340Y1036883I-1113J-1928D01*
G01X507299Y1036859D01*
G02X505825I-737J1277D01*
G03X503657Y1036893I-1115J-1928D01*
G01X503599Y1036859D01*
G02X502125I-737J1277D01*
G03X499957Y1036893I-1115J-1928D01*
G01X499899Y1036859D01*
G02X498425I-737J1277D01*
G03X496257Y1036893I-1115J-1928D01*
G01X496199Y1036859D01*
G02X494725I-737J1277D01*
G03X492499I-1113J-1928D01*
G02X491025I-737J1277D01*
G03X488857Y1036893I-1115J-1928D01*
G01X488799Y1036859D01*
G02X487325I-737J1277D01*
G03X485139Y1036883I-1114J-1928D01*
G01X485098Y1036859D01*
G02X483624I-737J1277D01*
G01X483583Y1036883D01*
G03X481399Y1036859I-1071J-1952D01*
G02X479925I-737J1277D01*
G03X479333Y1037096I-1115J-1928D01*
G01X476580Y1039849D01*
X470450D01*
X469936Y1040363D01*
Y1041401D01*
G03X466639Y1043291I-2225J-61D01*
G01X466598Y1043267D01*
G02X465124I-737J1277D01*
G03X462940Y1043291I-1113J-1927D01*
G01X462899Y1043267D01*
G02X461425I-737J1277D01*
G03X459257Y1043301I-1114J-1927D01*
G01X459199Y1043267D01*
G02X457725I-737J1277D01*
G03X455557Y1043301I-1114J-1927D01*
G01X455499Y1043267D01*
G02X453287Y1044544I-737J1277D01*
G03X452222Y1046443I-2226J0D01*
G01X452139Y1046491D01*
G02X451436Y1047748I772J1257D01*
G01Y1047809D01*
G03X450325Y1049675I-2225J-61D01*
G01X450290Y1049695D01*
G02X451595Y1052326I771J1257D01*
G01X451678Y1052019D01*
X451062Y1050952D01*
G01X462162Y1076587D02*
X460931D01*
X460673Y1076845D01*
G03X459575Y1078514I-2210J-258D01*
G01X459540Y1078534D01*
G02X458837Y1079791I772J1257D01*
G03X457748Y1081704I-2225J0D01*
G01X457724Y1081718D01*
X457683Y1081742D01*
G03X455499Y1081718I-1071J-1951D01*
G02X454025I-737J1277D01*
G03X451857Y1081752I-1114J-1927D01*
G01X451799Y1081718D01*
G02X450325I-737J1277D01*
G03X448139Y1081742I-1114J-1927D01*
G01X448098Y1081718D01*
G03X446986Y1079830I1113J-1927D01*
G01Y1079752D01*
G03X448098Y1077864I2225J39D01*
G01X448133Y1077844D01*
G02Y1075330I-772J-1257D01*
G01X448098Y1075310D01*
G03X446986Y1073422I1113J-1927D01*
G01Y1073310D01*
G03X448098Y1071455I2225J73D01*
G01X448133Y1071435D01*
G02Y1068921I-772J-1257D01*
G01X448098Y1068901D01*
G03X446986Y1067013I1113J-1927D01*
G01Y1066974D01*
G02X446283Y1065717I-1475J0D01*
G01X446248Y1065697D01*
G03X445136Y1063809I1113J-1927D01*
G01Y1063697D01*
G03X446248Y1061842I2225J73D01*
G01X446307Y1061808D01*
G02X446987Y1060565I-796J-1243D01*
G03X448075Y1058652I2226J0D01*
G01X448099Y1058638D01*
G03X450267Y1058604I1114J1927D01*
G01X450325Y1058638D01*
G02X451799I737J-1277D01*
G01X451834Y1058618D01*
G02X452537Y1057361I-772J-1257D01*
G01Y1057300D01*
G03X453648Y1055434I2225J61D01*
G01X453683Y1055414D01*
G02X454386Y1054157I-772J-1257D01*
G01Y1054101D01*
G03X455499Y1052229I2225J56D01*
G03X457723I1112J1928D01*
G01X457756Y1052248D01*
G02X459198Y1052229I704J-1296D01*
G03X461384Y1052205I1114J1928D01*
G01X461425Y1052229D01*
G02X462899I737J-1277D01*
G03X465123I1112J1928D01*
G01X465156Y1052248D01*
G02X466598Y1052229I704J-1296D01*
G03X468766Y1052195I1115J1928D01*
G01X468824Y1052229D01*
G02X470298I737J-1277D01*
G01X470339Y1052205D01*
G03X472525Y1052229I1072J1952D01*
G02X473999I737J-1277D01*
G03X476183Y1052205I1113J1928D01*
G01X476224Y1052229D01*
G02X477698I737J-1277D01*
G03X479884Y1052205I1114J1928D01*
G01X479925Y1052229D01*
G02X481399I737J-1277D01*
G01X481457Y1052195D01*
G03X483625Y1052229I1053J1962D01*
G02X485099I737J-1277D01*
G01X485157Y1052195D01*
G03X487325Y1052229I1053J1962D01*
G02X488799I737J-1277D01*
G01X488857Y1052195D01*
G03X491025Y1052229I1053J1962D01*
G02X492499I737J-1277D01*
G01X492540Y1052205D01*
G03X494724Y1052229I1071J1952D01*
G02X496198I737J-1277D01*
G01X496239Y1052205D01*
G03X498425Y1052229I1072J1952D01*
G02X499899I737J-1277D01*
G01X499957Y1052195D01*
G03X502125Y1052229I1053J1962D01*
G02X503599I737J-1277D01*
G01X503657Y1052195D01*
G03X505825Y1052229I1053J1962D01*
G02X507299I737J-1277D01*
G01X507357Y1052195D01*
G03X509525Y1052229I1053J1962D01*
G02X510999I737J-1277D01*
G01X511057Y1052195D01*
G03X513225Y1052229I1053J1962D01*
G02X514699I737J-1277D01*
G01X514757Y1052195D01*
G03X516925Y1052229I1053J1962D01*
G02X518399I737J-1277D01*
G03X520583Y1052205I1113J1928D01*
G01X520624Y1052229D01*
G02X522098I737J-1277D01*
G03X524324I1113J1928D01*
G02X525798I737J-1277D01*
G01X525839Y1052205D01*
G03X528025Y1052229I1072J1952D01*
G02X529499I737J-1277D01*
G01X529521Y1052216D01*
G03X531725Y1052230I1090J1941D01*
G02X533199I737J-1277D01*
G01X533267Y1052191D01*
G03X535424Y1052229I1044J1966D01*
G02X536898I737J-1277D01*
G03X539124I1113J1928D01*
G02X540598I737J-1277D01*
G03X542824I1113J1928D01*
G02X544298I737J-1277D01*
G03X545411Y1051931I1113J1928D01*
G01X545664D01*
X547001Y1050594D01*
G01X458462Y1076587D02*
X459693D01*
X459919Y1076813D01*
G03X459234Y1077844I-1458J-225D01*
G01X459199Y1077864D01*
G02X458087Y1079752I1113J1927D01*
G01Y1079791D01*
G03X457384Y1081048I-1475J0D01*
G01X457349Y1081068D01*
G03X455875I-737J-1277D01*
G01X455834Y1081044D01*
G02X453648Y1081068I-1072J1951D01*
G03X452174I-737J-1277D01*
G01X452116Y1081034D01*
G02X449948Y1081068I-1054J1961D01*
G03X448474I-737J-1277D01*
G01X448439Y1081048D01*
G03Y1078534I772J-1257D01*
G01X448474Y1078514D01*
G02X449586Y1076626I-1113J-1927D01*
G01Y1076548D01*
G02X448474Y1074660I-2225J39D01*
G01X448439Y1074640D01*
G03Y1072126I772J-1257D01*
G01X448474Y1072106D01*
G02X449587Y1070208I-1113J-1928D01*
G01Y1070178D01*
G02X448522Y1068279I-2226J0D01*
G01X448508Y1068270D01*
X448474Y1068251D01*
X448439Y1068231D01*
G03X447736Y1066974I772J-1257D01*
G01Y1066935D01*
G02X446624Y1065047I-2225J39D01*
G01X446589Y1065027D01*
G03Y1062513I772J-1257D01*
G01X446624Y1062493D01*
G02X447737Y1060595I-1113J-1928D01*
G01Y1060565D01*
G03X448426Y1059316I1477J0D01*
G01X448475Y1059288D01*
G03X449917Y1059269I738J1277D01*
G01X449918Y1059270D01*
X449950Y1059288D01*
G02X452174I1112J-1927D01*
G01X452198Y1059274D01*
G02X453287Y1057361I-1136J-1913D01*
G03X453990Y1056104I1475J0D01*
G01X454025Y1056084D01*
G02X455136Y1054218I-1114J-1927D01*
G01Y1054157D01*
G03X455839Y1052900I1475J0D01*
G01X455874Y1052880D01*
G03X457348I737J1277D01*
G01X457406Y1052914D01*
G02X459574Y1052880I1053J-1962D01*
G03X461016Y1052861I738J1277D01*
G01X461049Y1052880D01*
G02X463233Y1052904I1113J-1928D01*
G01X463274Y1052880D01*
G03X464748I737J1277D01*
G01X464806Y1052914D01*
G02X466974Y1052880I1053J-1962D01*
G03X468416Y1052861I738J1277D01*
G01X468449Y1052880D01*
X468490Y1052904D01*
G02X470674Y1052880I1071J-1952D01*
G03X472148I737J1277D01*
G02X474334Y1052904I1114J-1928D01*
G01X474375Y1052880D01*
G03X475849I737J1277D01*
G01X475907Y1052914D01*
G02X478075Y1052880I1053J-1962D01*
G03X479549I737J1277D01*
G02X481733Y1052904I1113J-1928D01*
G01X481774Y1052880D01*
G03X483248I737J1277D01*
G02X485416Y1052914I1115J-1928D01*
G01X485474Y1052880D01*
G03X486948I737J1277D01*
G02X489116Y1052914I1115J-1928D01*
G01X489174Y1052880D01*
G03X490648I737J1277D01*
G02X492816Y1052914I1115J-1928D01*
G01X492874Y1052880D01*
G03X494348I737J1277D01*
G02X496574I1113J-1928D01*
G03X498048I737J1277D01*
G02X500216Y1052914I1115J-1928D01*
G01X500274Y1052880D01*
G03X501748I737J1277D01*
G02X503916Y1052914I1115J-1928D01*
G01X503974Y1052880D01*
G03X505448I737J1277D01*
G02X507616Y1052914I1115J-1928D01*
G01X507674Y1052880D01*
G03X509148I737J1277D01*
G02X511316Y1052914I1115J-1928D01*
G01X511374Y1052880D01*
G03X512848I737J1277D01*
G02X515016Y1052914I1115J-1928D01*
G01X515074Y1052880D01*
G03X516548I737J1277D01*
G02X518734Y1052904I1114J-1928D01*
G01X518775Y1052880D01*
G03X520249I737J1277D01*
G01X520290Y1052904D01*
G02X522474Y1052880I1071J-1952D01*
G03X523948I737J1277D01*
G02X526174I1113J-1928D01*
G03X527648I737J1277D01*
G02X529816Y1052914I1115J-1928D01*
G01X529874Y1052880D01*
G03X531348I737J1277D01*
G02X533516Y1052914I1114J-1927D01*
G01X533574Y1052880D01*
G03X535048I737J1277D01*
G02X537274I1113J-1928D01*
G03X538748I737J1277D01*
G02X540974I1113J-1928D01*
G03X542448I737J1277D01*
G02X544674I1113J-1928D01*
G03X545411Y1052680I742J1276D01*
G01X546310D01*
X547255Y1051735D01*
X548163D01*
G01X458029Y909057D02*
X458644Y907991D01*
X458995Y907897D01*
G02X460992Y907781I883J-2043D01*
G02X462105Y905892I-1112J-1928D01*
G01X462104Y905853D01*
Y905819D01*
G03X462841Y904576I1474J34D01*
G01X462865Y904562D01*
G02X463954Y902649I-1136J-1913D01*
G03X464657Y901392I1475J0D01*
G01X464692Y901372D01*
G02X465803Y899506I-1114J-1927D01*
G01Y899445D01*
G03X466506Y898188I1475J0D01*
G01X466541Y898168D01*
G02X467654Y896296I-1112J-1928D01*
G01Y896240D01*
G03X468357Y894983I1475J0D01*
G01X468416Y894949D01*
G02X469504Y893036I-1138J-1913D01*
G03X471716Y891759I1475J0D01*
G02X473900Y891783I1113J-1927D01*
G01X473941Y891759D01*
G03X475415I737J1277D01*
G02X477601Y891783I1114J-1927D01*
G01X477642Y891759D01*
G03X479116I737J1277D01*
G02X481300Y891783I1113J-1927D01*
G01X481341Y891759D01*
G03X482815I737J1277D01*
G02X484983Y891793I1114J-1927D01*
G01X485041Y891759D01*
G03X486515I737J1277D01*
G02X488701Y891783I1114J-1927D01*
G01X488742Y891759D01*
G03X490216I737J1277D01*
G02X492400Y891783I1113J-1927D01*
G01X492441Y891759D01*
G03X493915I737J1277D01*
G02X496083Y891793I1114J-1927D01*
G01X496141Y891759D01*
G03X497615I737J1277D01*
G02X499801Y891783I1114J-1927D01*
G01X499842Y891759D01*
G03X501316I737J1277D01*
G02X503542I1113J-1927D01*
G03X505016I737J1277D01*
G02X507200Y891783I1113J-1927D01*
G01X507241Y891759D01*
G03X508715I737J1277D01*
G02X510883Y891793I1114J-1927D01*
G01X510941Y891759D01*
G03X512415I737J1277D01*
G02X514601Y891783I1114J-1927D01*
G01X514642Y891759D01*
G03X516116I737J1277D01*
G02X518300Y891783I1113J-1927D01*
G01X518341Y891759D01*
G03X519815I737J1277D01*
G02X521983Y891793I1114J-1927D01*
G01X522041Y891759D01*
G03X523515I737J1277D01*
G02X525701Y891783I1114J-1927D01*
G01X525742Y891759D01*
G03X527216I737J1277D01*
G02X529400Y891783I1113J-1927D01*
G01X529441Y891759D01*
G03X530915I737J1277D01*
G02X533101Y891783I1114J-1927D01*
G01X533142Y891759D01*
G03X534616I737J1277D01*
G02X536842I1113J-1927D01*
G03X537579Y891560I740J1276D01*
G01X538702D01*
X539532Y890730D01*
G01X539136Y889254D02*
X537579Y890811D01*
G02X536466Y891109I-1J2225D01*
G03X534992I-737J-1277D01*
G02X532766I-1113J1927D01*
G03X531292I-737J-1277D01*
G02X529124Y891075I-1114J1927D01*
G01X529066Y891109D01*
G03X527592I-737J-1277D01*
G02X525366I-1113J1927D01*
G03X523892I-737J-1277D01*
G02X521724Y891075I-1114J1927D01*
G01X521666Y891109D01*
G03X520192I-737J-1277D01*
G02X518024Y891075I-1114J1927D01*
G01X517966Y891109D01*
G03X516492I-737J-1277D01*
G02X514266I-1113J1927D01*
G03X512792I-737J-1277D01*
G02X510624Y891075I-1114J1927D01*
G01X510566Y891109D01*
G03X509092I-737J-1277D01*
G02X506924Y891075I-1114J1927D01*
G01X506866Y891109D01*
G03X505392I-737J-1277D01*
G02X503166I-1113J1927D01*
G03X501692I-737J-1277D01*
G02X499466I-1113J1927D01*
G03X497992I-737J-1277D01*
G02X495824Y891075I-1114J1927D01*
G01X495766Y891109D01*
G03X494292I-737J-1277D01*
G02X492124Y891075I-1114J1927D01*
G01X492066Y891109D01*
G03X490592I-737J-1277D01*
G02X488366I-1113J1927D01*
G03X486892I-737J-1277D01*
G02X484724Y891075I-1114J1927D01*
G01X484666Y891109D01*
G03X483192I-737J-1277D01*
G02X481024Y891075I-1114J1927D01*
G01X480966Y891109D01*
G03X479492I-737J-1277D01*
G02X477266I-1113J1927D01*
G03X475792I-737J-1277D01*
G02X473624Y891075I-1114J1927D01*
G01X473566Y891109D01*
G03X472092I-737J-1277D01*
G02X469866I-1113J1927D01*
G01X469818Y891137D01*
G02X468753Y893036I1161J1899D01*
G03X468050Y894293I-1475J0D01*
G01X468015Y894313D01*
G02X466904Y896179I1114J1927D01*
G01Y896240D01*
G03X466201Y897497I-1475J0D01*
G01X466166Y897517D01*
G02X465053Y899389I1112J1928D01*
G01Y899445D01*
G03X464350Y900702I-1475J0D01*
G01X464315Y900722D01*
G02X463204Y902588I1114J1927D01*
G01Y902649D01*
G03X462501Y903906I-1475J0D01*
G01X462466Y903926D01*
X462442Y903940D01*
G02X461353Y905854I1136J1913D01*
G03X460647Y907112I-1474J0D01*
G01X460616Y907130D01*
G03X459347Y907228I-737J-1276D01*
G01X459264Y906920D01*
X459878Y905855D01*
Y905853D01*
G01X540307Y916355D02*
X537915D01*
G02X536466Y916743I0J2898D01*
G03X534992I-737J-1277D01*
G02X532766I-1113J1927D01*
G03X531292I-737J-1277D01*
G02X529066I-1113J1927D01*
G03X527592I-737J-1277D01*
G01X527551Y916719D01*
G02X525365Y916743I-1072J1951D01*
G03X523891I-737J-1277D01*
G01X523850Y916719D01*
G02X521666Y916743I-1071J1951D01*
G03X520192I-737J-1277D01*
G02X518024Y916709I-1114J1927D01*
G01X517966Y916743D01*
G03X516492I-737J-1277D01*
G02X514324Y916709I-1114J1927D01*
G01X514266Y916743D01*
G03X512792I-737J-1277D01*
G02X510624Y916709I-1114J1927D01*
G01X510566Y916743D01*
G03X509092I-737J-1277D01*
G02X506924Y916709I-1114J1927D01*
G01X506866Y916743D01*
G03X505392I-737J-1277D01*
G02X503224Y916709I-1114J1927D01*
G01X503166Y916743D01*
G03X501692I-737J-1277D01*
G02X499506Y916719I-1114J1927D01*
G01X499465Y916743D01*
G03X497991I-737J-1277D01*
G01X497950Y916719D01*
G02X495766Y916743I-1071J1951D01*
G03X494292I-737J-1277D01*
G02X492124Y916709I-1114J1927D01*
G01X492066Y916743D01*
G03X490592I-737J-1277D01*
G02X488424Y916709I-1114J1927D01*
G01X488366Y916743D01*
G03X486892I-737J-1277D01*
G02X484724Y916709I-1114J1927D01*
G01X484666Y916743D01*
G03X483192I-737J-1277D01*
G02X481024Y916709I-1114J1927D01*
G01X480966Y916743D01*
G03X479492I-737J-1277D01*
G02X477266I-1113J1927D01*
G03X475792I-737J-1277D01*
G02X473606Y916719I-1114J1927D01*
G01X473565Y916743D01*
G03X472091I-737J-1277D01*
G02X469907Y916719I-1113J1927D01*
G01X469866Y916743D01*
G03X468392I-737J-1277D01*
G02X466224Y916709I-1114J1927D01*
G01X466166Y916743D01*
G03X464692I-737J-1277D01*
G02X462524Y916709I-1114J1927D01*
G01X462466Y916743D01*
X462442Y916757D01*
G02X461353Y918670I1136J1913D01*
G03X460650Y919927I-1475J0D01*
G01X460615Y919947D01*
G03X459141I-737J-1277D01*
G01X459083Y919913D01*
G02X457931Y919650I-1054J1962D01*
G02X457610Y919792I22J483D01*
G01X455658Y921744D01*
G03X455342Y921875I-316J-315D01*
G01X454329D01*
G01X542467Y914762D02*
X540739D01*
X540166Y914189D01*
G02X538692I-737J1277D01*
G03X536466I-1113J-1927D01*
G02X534992I-737J1277D01*
G03X532766I-1113J-1927D01*
G02X531292I-737J1277D01*
G03X529066I-1113J-1927D01*
G02X527592I-737J1277D01*
G01X527551Y914213D01*
G03X525365Y914189I-1072J-1951D01*
G02X523891I-737J1277D01*
G03X521707Y914213I-1113J-1927D01*
G01X521666Y914189D01*
G02X520192I-737J1277D01*
G03X518024Y914223I-1114J-1927D01*
G01X517966Y914189D01*
G02X516492I-737J1277D01*
G03X514324Y914223I-1114J-1927D01*
G01X514266Y914189D01*
G02X512792I-737J1277D01*
G03X510624Y914223I-1114J-1927D01*
G01X510566Y914189D01*
G02X509092I-737J1277D01*
G03X506866I-1113J-1927D01*
G02X505392I-737J1277D01*
G03X503224Y914223I-1114J-1927D01*
G01X503166Y914189D01*
G02X501692I-737J1277D01*
G03X499506Y914213I-1114J-1927D01*
G01X499465Y914189D01*
G02X497991I-737J1277D01*
G03X495807Y914213I-1113J-1927D01*
G01X495766Y914189D01*
G02X494292I-737J1277D01*
G03X492124Y914223I-1114J-1927D01*
G01X492066Y914189D01*
G02X490592I-737J1277D01*
G03X488424Y914223I-1114J-1927D01*
G01X488366Y914189D01*
G02X486892I-737J1277D01*
G03X484724Y914223I-1114J-1927D01*
G01X484666Y914189D01*
G02X483192I-737J1277D01*
G03X480966I-1113J-1927D01*
G02X479492I-737J1277D01*
G01X479434Y914223D01*
G03X477266Y914189I-1054J-1961D01*
G02X475792I-737J1277D01*
G03X473606Y914213I-1114J-1927D01*
G01X473565Y914189D01*
G02X472125Y914170I-737J1277D01*
G01X472092Y914189D01*
X472034Y914223D01*
G03X469866Y914189I-1054J-1961D01*
G02X468392I-737J1277D01*
G03X466224Y914223I-1114J-1927D01*
G01X466166Y914189D01*
G02X464692I-737J1277D01*
G03X462524Y914223I-1114J-1927D01*
G01X462466Y914189D01*
G02X461196Y914092I-736J1277D01*
G01X461113Y914399D01*
X461729Y915466D01*
G01X538057Y896695D02*
X536537D01*
X536013Y897219D01*
X533887D01*
G02X532766Y897517I-8J2226D01*
G03X531292I-737J-1277D01*
G02X529124Y897483I-1115J1928D01*
G01X529066Y897517D01*
G03X527592I-737J-1277D01*
G02X525366I-1113J1928D01*
G03X523892I-737J-1277D01*
G02X521666I-1113J1928D01*
G03X520192I-737J-1277D01*
G02X518024Y897483I-1115J1928D01*
G01X517966Y897517D01*
G03X516492I-737J-1277D01*
G02X514324Y897483I-1115J1928D01*
G01X514266Y897517D01*
G03X512792I-737J-1277D01*
G02X510624Y897483I-1115J1928D01*
G01X510566Y897517D01*
G03X509092I-737J-1277D01*
G02X506906Y897493I-1114J1928D01*
G01X506865Y897517D01*
G03X505391I-737J-1277D01*
G02X503165I-1113J1928D01*
G03X501691I-737J-1277D01*
G02X499507Y897493I-1113J1928D01*
G01X499466Y897517D01*
G03X497992I-737J-1277D01*
G02X495766I-1113J1928D01*
G03X494292I-737J-1277D01*
G02X492124Y897483I-1115J1928D01*
G01X492066Y897517D01*
G03X490592I-737J-1277D01*
G02X488424Y897483I-1115J1928D01*
G01X488366Y897517D01*
G03X486892I-737J-1277D01*
G02X484724Y897483I-1115J1928D01*
G01X484666Y897517D01*
G03X483192I-737J-1277D01*
G02X481006Y897493I-1114J1928D01*
G01X480965Y897517D01*
G03X479491I-737J-1277D01*
G02X477307Y897493I-1113J1928D01*
G01X477266Y897517D01*
G03X475792I-737J-1277D01*
G02X473624Y897483I-1115J1928D01*
G01X473566Y897517D01*
G03X472092I-737J-1277D01*
G02X469924Y897483I-1115J1928D01*
G01X469866Y897517D01*
G02X468753Y899389I1112J1928D01*
G01Y899445D01*
G03X468137Y901225I-2880J0D01*
G01X463707Y908685D01*
X463578Y912262D01*
G01X542197Y913539D02*
X540542D01*
G02X538316I-1113J1927D01*
G03X536842I-737J-1277D01*
G02X534616I-1113J1927D01*
G03X533142I-737J-1277D01*
G02X530916I-1113J1927D01*
G03X529442I-737J-1277D01*
G02X527216I-1113J1927D01*
G03X525742I-737J-1277D01*
G02X523556Y913515I-1114J1927D01*
G01X523515Y913539D01*
G03X522041I-737J-1277D01*
G01X521983Y913505D01*
G02X519815Y913539I-1054J1961D01*
G03X518341I-737J-1277D01*
G01X518283Y913505D01*
G02X516115Y913539I-1054J1961D01*
G03X514641I-737J-1277D01*
G01X514583Y913505D01*
G02X512415Y913539I-1054J1961D01*
G03X510941I-737J-1277D01*
G01X510900Y913515D01*
G02X508716Y913539I-1071J1951D01*
G03X507242I-737J-1277D01*
G01X507201Y913515D01*
G02X505015Y913539I-1072J1951D01*
G03X503541I-737J-1277D01*
G01X503483Y913505D01*
G02X501315Y913539I-1054J1961D01*
G03X499841I-737J-1277D01*
G02X497615I-1113J1927D01*
G03X496141I-737J-1277D01*
G01X496083Y913505D01*
G02X493915Y913539I-1054J1961D01*
G03X492441I-737J-1277D01*
G01X492383Y913505D01*
G02X490215Y913539I-1054J1961D01*
G03X488741I-737J-1277D01*
G01X488683Y913505D01*
G02X486515Y913539I-1054J1961D01*
G03X485041I-737J-1277D01*
G01X485000Y913515D01*
G02X482816Y913539I-1071J1951D01*
G03X481342I-737J-1277D01*
G02X479158Y913515I-1113J1927D01*
G01X479117Y913539D01*
G03X477643I-737J-1277D01*
G02X475415I-1114J1927D01*
G03X473941I-737J-1277D01*
G02X471757Y913515I-1113J1927D01*
G01X471716Y913539D01*
X471683Y913558D01*
G03X470243Y913539I-703J-1296D01*
G02X468015I-1114J1927D01*
G03X466541I-737J-1277D01*
G01X466483Y913505D01*
G02X464315Y913539I-1054J1961D01*
G03X462841I-737J-1277D01*
G01X462783Y913505D01*
G02X460845Y913423I-1054J1961D01*
G01X460494Y913329D01*
X459878Y912262D01*
G01X467278Y918670D02*
X468256Y917692D01*
X469137D01*
G02X470183Y917427I-7J-2226D01*
G01X470241Y917393D01*
G03X471715I737J1277D01*
G02X473941I1113J-1927D01*
G03X475415I737J1277D01*
G02X477601Y917417I1114J-1927D01*
G01X477642Y917393D01*
G03X479116I737J1277D01*
G02X481300Y917417I1113J-1927D01*
G01X481341Y917393D01*
G03X482815I737J1277D01*
G02X484983Y917427I1114J-1927D01*
G01X485041Y917393D01*
G03X486515I737J1277D01*
G02X488683Y917427I1114J-1927D01*
G01X488741Y917393D01*
G03X490215I737J1277D01*
G02X492383Y917427I1114J-1927D01*
G01X492441Y917393D01*
G03X493915I737J1277D01*
G02X496101Y917417I1114J-1927D01*
G01X496142Y917393D01*
G03X497616I737J1277D01*
G01X497657Y917417D01*
G02X499841Y917393I1071J-1951D01*
G03X501315I737J1277D01*
G02X503483Y917427I1114J-1927D01*
G01X503541Y917393D01*
G03X505015I737J1277D01*
G02X507183Y917427I1114J-1927D01*
G01X507241Y917393D01*
G03X508715I737J1277D01*
G02X510883Y917427I1114J-1927D01*
G01X510941Y917393D01*
G03X512415I737J1277D01*
G02X514583Y917427I1114J-1927D01*
G01X514641Y917393D01*
G03X516115I737J1277D01*
G02X518283Y917427I1114J-1927D01*
G01X518341Y917393D01*
G03X519815I737J1277D01*
G02X522001Y917417I1114J-1927D01*
G01X522042Y917393D01*
G03X523516I737J1277D01*
G01X523574Y917427D01*
G02X525742Y917393I1054J-1961D01*
G03X527216I737J1277D01*
G02X529442I1113J-1927D01*
G03X530916I737J1277D01*
G02X533142I1113J-1927D01*
G03X534616I737J1277D01*
G02X536842I1113J-1927D01*
G03X538316I737J1277D01*
G01X539198Y918275D01*
G01X454762Y1044544D02*
X456039Y1045821D01*
X457725D01*
G02X459199I737J-1277D01*
G01X459257Y1045787D01*
G03X461425Y1045821I1054J1961D01*
G02X462899I737J-1277D01*
G01X462940Y1045797D01*
G03X465124Y1045821I1071J1951D01*
G02X466598I737J-1277D01*
G01X466639Y1045797D01*
G03X468825Y1045821I1072J1951D01*
G02X471787Y1044544I1206J-1277D01*
G03X472524Y1043268I1473J0D01*
G01X472525Y1043267D01*
G03X473999I737J1277D01*
G01X474057Y1043301D01*
G02X476225Y1043267I1054J-1961D01*
G03X477699I737J1277D01*
G01X477824Y1043339D01*
X477928Y1043384D01*
G02X479925Y1043267I882J-2044D01*
G03X481399I737J1277D01*
G01X481457Y1043301D01*
G02X483625Y1043267I1054J-1961D01*
G03X485099I737J1277D01*
G01X485157Y1043301D01*
G02X487325Y1043267I1054J-1961D01*
G03X488799I737J1277D01*
G01X488857Y1043301D01*
G02X491025Y1043267I1054J-1961D01*
G03X492499I737J1277D01*
G01X492557Y1043301D01*
G02X494725Y1043267I1054J-1961D01*
G03X496199I737J1277D01*
G02X498383Y1043291I1113J-1927D01*
G01X498424Y1043267D01*
G03X499898I737J1277D01*
G01X499939Y1043291D01*
G02X502125Y1043267I1072J-1951D01*
G03X503599I737J1277D01*
G01X503657Y1043301D01*
G02X505825Y1043267I1054J-1961D01*
G03X507299I737J1277D01*
G01X507357Y1043301D01*
G02X509525Y1043267I1054J-1961D01*
G03X510999I737J1277D01*
G01X511057Y1043301D01*
G02X513225Y1043267I1054J-1961D01*
G03X514699I737J1277D01*
G01X514757Y1043301D01*
G02X516925Y1043267I1054J-1961D01*
G03X518399I737J1277D01*
G01X518457Y1043301D01*
G02X520625Y1043267I1054J-1961D01*
G03X522099I737J1277D01*
G02X524283Y1043291I1113J-1927D01*
G01X524324Y1043267D01*
G03X525798I737J1277D01*
G01X525839Y1043291D01*
G02X528025Y1043267I1072J-1951D01*
G03X529499I737J1277D01*
G01X529557Y1043301D01*
G02X531725Y1043267I1054J-1961D01*
G03X533199I737J1277D01*
G02X534167Y1043561I1114J-1926D01*
G02X534310Y1043565I134J-2221D01*
G01X538773D01*
X539224Y1043114D01*
X540575D01*
X541459Y1043998D01*
X543026D01*
G01X465860Y1050952D02*
X466819Y1049993D01*
X466847D01*
G02X467806Y1049973I0J-22985D01*
G02X468783Y1049700I-95J-2223D01*
G01X468824Y1049676D01*
G03X470298I737J1276D01*
G01X470339Y1049700D01*
G02X472525Y1049676I1072J-1951D01*
G03X473999I737J1276D01*
G01X474040Y1049700D01*
G02X476224Y1049676I1071J-1951D01*
G03X477698I737J1276D01*
G01X477739Y1049700D01*
G02X479925Y1049676I1072J-1951D01*
G03X481399I737J1276D01*
G01X481457Y1049710D01*
G02X483625Y1049676I1054J-1961D01*
G03X485099I737J1276D01*
G01X485157Y1049710D01*
G02X487325Y1049676I1054J-1961D01*
G03X488799I737J1276D01*
G01X488857Y1049710D01*
G02X491025Y1049676I1054J-1961D01*
G03X492499I737J1276D01*
G01X492540Y1049700D01*
G02X494724Y1049676I1071J-1951D01*
G03X496198I737J1276D01*
G01X496239Y1049700D01*
G02X498425Y1049676I1072J-1951D01*
G03X499899I737J1276D01*
G01X499957Y1049710D01*
G02X502125Y1049676I1054J-1961D01*
G03X503599I737J1276D01*
G01X503657Y1049710D01*
G02X505825Y1049676I1054J-1961D01*
G03X507299I737J1276D01*
G01X507357Y1049710D01*
G02X509525Y1049676I1054J-1961D01*
G03X510999I737J1276D01*
G01X511057Y1049710D01*
G02X513225Y1049676I1054J-1961D01*
G03X514699I737J1276D01*
G01X514757Y1049710D01*
G02X516925Y1049676I1054J-1961D01*
G03X518399I737J1276D01*
G01X518440Y1049700D01*
G02X520624Y1049676I1071J-1951D01*
G03X522098I737J1276D01*
G02X524324I1113J-1927D01*
G03X525798I737J1276D01*
G01X525839Y1049700D01*
G02X528025Y1049676I1072J-1951D01*
G03X529499I737J1276D01*
G01X529557Y1049710D01*
G02X531725Y1049676I1054J-1961D01*
G03X533199I737J1277D01*
G01X533240Y1049700D01*
G02X535424Y1049676I1071J-1951D01*
G03X536162Y1049475I743J1274D01*
G01X536949D01*
X539914Y1049923D01*
G01X545088Y1058989D02*
X540426D01*
G03X539124Y1058638I0J-2590D01*
G02X536898I-1113J1927D01*
G03X535424I-737J-1277D01*
G02X533240Y1058614I-1113J1927D01*
G01X533199Y1058638D01*
G03X531725I-737J-1277D01*
G02X529557Y1058604I-1114J1927D01*
G01X529499Y1058638D01*
G03X528025I-737J-1277D01*
G02X525857Y1058604I-1114J1927D01*
G01X525799Y1058638D01*
G03X524325I-737J-1277D01*
G02X522099I-1113J1927D01*
G03X520625I-737J-1277D01*
G02X518457Y1058604I-1114J1927D01*
G01X518399Y1058638D01*
G03X516925I-737J-1277D01*
G02X514757Y1058604I-1114J1927D01*
G01X514699Y1058638D01*
G03X513225I-737J-1277D01*
G02X511057Y1058604I-1114J1927D01*
G01X510999Y1058638D01*
G03X509525I-737J-1277D01*
G02X507357Y1058604I-1114J1927D01*
G01X507299Y1058638D01*
G03X505825I-737J-1277D01*
G02X503657Y1058604I-1114J1927D01*
G01X503599Y1058638D01*
G03X502125I-737J-1277D01*
G02X499957Y1058604I-1114J1927D01*
G01X499899Y1058638D01*
G03X498425I-737J-1277D01*
G02X496257Y1058604I-1114J1927D01*
G01X496199Y1058638D01*
G03X494725I-737J-1277D01*
G02X492557Y1058604I-1114J1927D01*
G01X492499Y1058638D01*
G03X491025I-737J-1277D01*
G02X488857Y1058604I-1114J1927D01*
G01X488799Y1058638D01*
G03X487325I-737J-1277D01*
G02X485139Y1058614I-1114J1927D01*
G01X485098Y1058638D01*
G03X483624I-737J-1277D01*
G02X481398I-1113J1927D01*
G03X479924I-737J-1277D01*
G01X479883Y1058614D01*
G02X477699Y1058638I-1071J1951D01*
G03X476225I-737J-1277D01*
G02X474039Y1058614I-1114J1927D01*
G01X473998Y1058638D01*
G03X472524I-737J-1277D01*
G01X472466Y1058604D01*
G02X470298Y1058638I-1054J1961D01*
G03X468824I-737J-1277D01*
G01X468783Y1058614D01*
G02X466599Y1058638I-1071J1951D01*
G03X465125I-737J-1277D01*
G01X465084Y1058614D01*
G02X463128Y1058522I-1072J1951D01*
G01X462777Y1058428D01*
X462161Y1057361D01*
G01X460312Y1054157D02*
X459696Y1055224D01*
X459779Y1055531D01*
G02X461049Y1055434I534J-1374D01*
G01X461090Y1055410D01*
G03X463274Y1055434I1071J1951D01*
G02X464748I737J-1277D01*
G03X466934Y1055410I1114J1927D01*
G01X466975Y1055434D01*
G02X468449I737J-1277D01*
G01X468490Y1055410D01*
G03X470674Y1055434I1071J1951D01*
G02X472148I737J-1277D01*
G01X472189Y1055410D01*
G03X474375Y1055434I1072J1951D01*
G02X475849I737J-1277D01*
G03X478075I1113J1927D01*
G02X479549I737J-1277D01*
G01X479590Y1055410D01*
G03X481774Y1055434I1071J1951D01*
G02X483248I737J-1277D01*
G03X485474I1113J1927D01*
G02X486948I737J-1277D01*
G03X489116Y1055400I1114J1927D01*
G01X489174Y1055434D01*
G02X490648I737J-1277D01*
G03X492816Y1055400I1114J1927D01*
G01X492874Y1055434D01*
G02X494348I737J-1277D01*
G03X496516Y1055400I1114J1927D01*
G01X496574Y1055434D01*
G02X498048I737J-1277D01*
G03X500216Y1055400I1114J1927D01*
G01X500274Y1055434D01*
G02X501748I737J-1277D01*
G03X503916Y1055400I1114J1927D01*
G01X503974Y1055434D01*
G02X505448I737J-1277D01*
G03X507616Y1055400I1114J1927D01*
G01X507674Y1055434D01*
G02X509148I737J-1277D01*
G03X511316Y1055400I1114J1927D01*
G01X511374Y1055434D01*
G02X512848I737J-1277D01*
G03X515016Y1055400I1114J1927D01*
G01X515074Y1055434D01*
G02X516548I737J-1277D01*
G03X518734Y1055410I1114J1927D01*
G01X518775Y1055434D01*
G02X520249I737J-1277D01*
G03X522433Y1055410I1113J1927D01*
G01X522474Y1055434D01*
G02X523948I737J-1277D01*
G03X526116Y1055400I1114J1927D01*
G01X526174Y1055434D01*
G02X527648I737J-1277D01*
G03X529816Y1055400I1114J1927D01*
G01X529874Y1055434D01*
G02X531348I737J-1277D01*
G03X533516Y1055400I1114J1927D01*
G01X533574Y1055434D01*
G02X535048I737J-1277D01*
G03X537274I1113J1927D01*
G02X539040Y1055909I1766J-3046D01*
G01X545084D01*
X545088Y1055913D01*
G01X458462Y1057361D02*
X459078Y1056294D01*
X459429Y1056200D01*
G02X461383Y1056108I883J-2043D01*
G01X461424Y1056084D01*
G03X462898I737J1277D01*
G01X462939Y1056108D01*
G02X465125Y1056084I1072J-1951D01*
G03X466599I737J1277D01*
G02X468783Y1056108I1113J-1927D01*
G01X468824Y1056084D01*
G03X470298I737J1277D01*
G02X472524I1113J-1927D01*
G03X473998I737J1277D01*
G02X476184Y1056108I1114J-1927D01*
G01X476225Y1056084D01*
G03X477699I737J1277D01*
G02X479883Y1056108I1113J-1927D01*
G01X479924Y1056084D01*
G03X481398I737J1277D01*
G02X483624I1113J-1927D01*
G03X485098I737J1277D01*
G01X485139Y1056108D01*
G02X487325Y1056084I1072J-1951D01*
G03X488799I737J1277D01*
G01X488857Y1056118D01*
G02X491025Y1056084I1054J-1961D01*
G03X492499I737J1277D01*
G01X492557Y1056118D01*
G02X494725Y1056084I1054J-1961D01*
G03X496199I737J1277D01*
G01X496257Y1056118D01*
G02X498425Y1056084I1054J-1961D01*
G03X499899I737J1277D01*
G01X499957Y1056118D01*
G02X502125Y1056084I1054J-1961D01*
G03X503599I737J1277D01*
G01X503657Y1056118D01*
G02X505825Y1056084I1054J-1961D01*
G03X507299I737J1277D01*
G01X507357Y1056118D01*
G02X509525Y1056084I1054J-1961D01*
G03X510999I737J1277D01*
G01X511057Y1056118D01*
G02X513225Y1056084I1054J-1961D01*
G03X514699I737J1277D01*
G01X514757Y1056118D01*
G02X516925Y1056084I1054J-1961D01*
G03X518399I737J1277D01*
G02X520625I1113J-1927D01*
G03X522099I737J1277D01*
G01X522157Y1056118D01*
G02X524325Y1056084I1054J-1961D01*
G03X525799I737J1277D01*
G01X525857Y1056118D01*
G02X528025Y1056084I1054J-1961D01*
G03X529499I737J1277D01*
G01X529557Y1056118D01*
G02X531725Y1056084I1054J-1961D01*
G03X533199I737J1277D01*
G01X533240Y1056108D01*
G02X535424Y1056084I1071J-1951D01*
G03X536898I737J1277D01*
G02X541695Y1057369I4797J-8310D01*
G01X545080D01*
X545088Y1057377D01*
G01X541387Y1060538D02*
X540645Y1059797D01*
X540644D01*
G03X538748Y1059288I0J-3787D01*
G02X537274I-737J1277D01*
G03X535048I-1113J-1927D01*
G02X533574I-737J1277D01*
G01X533516Y1059322D01*
G03X531348Y1059288I-1054J-1961D01*
G02X529874I-737J1277D01*
G01X529816Y1059322D01*
G03X527648Y1059288I-1054J-1961D01*
G02X526174I-737J1277D01*
G01X526133Y1059312D01*
G03X523949Y1059288I-1071J-1951D01*
G02X522475I-737J1277D01*
G01X522434Y1059312D01*
G03X520248Y1059288I-1072J-1951D01*
G02X518774I-737J1277D01*
G01X518716Y1059322D01*
G03X516548Y1059288I-1054J-1961D01*
G02X515074I-737J1277D01*
G01X515016Y1059322D01*
G03X512848Y1059288I-1054J-1961D01*
G02X511374I-737J1277D01*
G01X511316Y1059322D01*
G03X509148Y1059288I-1054J-1961D01*
G02X507674I-737J1277D01*
G01X507616Y1059322D01*
G03X505448Y1059288I-1054J-1961D01*
G02X503974I-737J1277D01*
G01X503916Y1059322D01*
G03X501748Y1059288I-1054J-1961D01*
G02X500274I-737J1277D01*
G01X500216Y1059322D01*
G03X498048Y1059288I-1054J-1961D01*
G02X496574I-737J1277D01*
G01X496516Y1059322D01*
G03X494348Y1059288I-1054J-1961D01*
G02X492874I-737J1277D01*
G01X492816Y1059322D01*
G03X490648Y1059288I-1054J-1961D01*
G02X489174I-737J1277D01*
G01X489116Y1059322D01*
G03X486948Y1059288I-1054J-1961D01*
G02X485474I-737J1277D01*
G03X483248I-1113J-1927D01*
G02X481774I-737J1277D01*
G03X479590Y1059312I-1113J-1927D01*
G01X479549Y1059288D01*
G02X478075I-737J1277D01*
G01X478034Y1059312D01*
G03X475848Y1059288I-1072J-1951D01*
G02X474374I-737J1277D01*
G03X472190Y1059312I-1113J-1927D01*
G01X472149Y1059288D01*
G02X470675I-737J1277D01*
G03X468507Y1059322I-1114J-1927D01*
G01X468449Y1059288D01*
G02X466975I-737J1277D01*
G03X464749I-1113J-1927D01*
G02X463479Y1059191I-736J1277D01*
G01X463396Y1059498D01*
X464012Y1060565D01*
G01X458460Y1050952D02*
X460452Y1049217D01*
G02X461048Y1049026I-141J-1467D01*
G03X462595Y1048769I1115J1926D01*
G03X463252Y1049012I-434J2182D01*
G01X463274Y1049025D01*
G02X464748I737J-1276D01*
G01X464770Y1049012D01*
G03X466974Y1049026I1090J1940D01*
G02X468448I737J-1276D01*
G01X468502Y1048994D01*
G03X470674Y1049025I1058J1958D01*
G02X472148I737J-1276D01*
G03X474316Y1048991I1114J1927D01*
G01X474374Y1049025D01*
G02X475848I737J-1276D01*
G03X478074I1113J1927D01*
G02X479548I737J-1276D01*
G03X481716Y1048991I1114J1927D01*
G01X481774Y1049025D01*
G02X483248I737J-1276D01*
G03X485416Y1048991I1114J1927D01*
G01X485474Y1049025D01*
G02X486948I737J-1276D01*
G03X489116Y1048991I1114J1927D01*
G01X489174Y1049025D01*
G02X490648I737J-1276D01*
G03X492816Y1048991I1114J1927D01*
G01X492874Y1049025D01*
G02X494348I737J-1276D01*
G03X496574I1113J1927D01*
G02X498048I737J-1276D01*
G03X500216Y1048991I1114J1927D01*
G01X500274Y1049025D01*
G02X501748I737J-1276D01*
G03X503916Y1048991I1114J1927D01*
G01X503974Y1049025D01*
G02X505448I737J-1276D01*
G03X507616Y1048991I1114J1927D01*
G01X507674Y1049025D01*
G02X509148I737J-1276D01*
G03X511316Y1048991I1114J1927D01*
G01X511374Y1049025D01*
G02X512848I737J-1276D01*
G03X515016Y1048991I1114J1927D01*
G01X515074Y1049025D01*
G02X516548I737J-1276D01*
G03X518716Y1048991I1114J1927D01*
G01X518774Y1049025D01*
G02X520248I737J-1276D01*
G03X522474I1113J1927D01*
G02X523948I737J-1276D01*
G03X526174I1113J1927D01*
G02X527648I737J-1276D01*
G03X529816Y1048991I1114J1927D01*
G01X529874Y1049025D01*
X529917Y1049050D01*
G02X531348Y1049026I694J-1301D01*
G03X533516Y1048992I1114J1927D01*
G01X533574Y1049026D01*
G02X535005Y1049050I737J-1277D01*
G03X536161Y1048726I1156J1902D01*
G01X538106D01*
X538883Y1047949D01*
X541940D01*
X543914Y1049923D01*
G01X467711Y1066974D02*
X470559Y1065764D01*
X470674Y1065697D01*
G03X472148I737J1277D01*
G02X474316Y1065731I1114J-1927D01*
G01X474374Y1065697D01*
G03X475848I737J1277D01*
G02X478016Y1065731I1114J-1927D01*
G01X478074Y1065697D01*
G03X479548I737J1277D01*
G02X481734Y1065721I1114J-1927D01*
G01X481775Y1065697D01*
G03X483249I737J1277D01*
G02X485433Y1065721I1113J-1927D01*
G01X485474Y1065697D01*
G03X486948I737J1277D01*
G02X489116Y1065731I1114J-1927D01*
G01X489174Y1065697D01*
G03X490648I737J1277D01*
G02X492816Y1065731I1114J-1927D01*
G01X492874Y1065697D01*
G03X494348I737J1277D01*
G02X496516Y1065731I1114J-1927D01*
G01X496574Y1065697D01*
G03X498048I737J1277D01*
G02X500216Y1065731I1114J-1927D01*
G01X500274Y1065697D01*
G03X501748I737J1277D01*
G02X503916Y1065731I1114J-1927D01*
G01X503974Y1065697D01*
G03X505448I737J1277D01*
G02X507616Y1065731I1114J-1927D01*
G01X507674Y1065697D01*
G03X509148I737J1277D01*
G02X511316Y1065731I1114J-1927D01*
G01X511374Y1065697D01*
G03X512848I737J1277D01*
G02X515016Y1065731I1114J-1927D01*
G01X515074Y1065697D01*
G03X516548I737J1277D01*
G02X518716Y1065731I1114J-1927D01*
G01X518774Y1065697D01*
G03X520248I737J1277D01*
G02X522416Y1065731I1114J-1927D01*
G01X522474Y1065697D01*
G03X523948I737J1277D01*
G02X526174I1113J-1927D01*
G03X527648I737J1277D01*
G02X529816Y1065731I1114J-1927D01*
G01X529874Y1065697D01*
G03X531348I737J1277D01*
G02X533516Y1065731I1114J-1927D01*
G01X533574Y1065697D01*
G03X535048I737J1277D01*
G02X537216Y1065731I1114J-1927D01*
G01X537274Y1065697D01*
G03X538748I737J1277D01*
G01X538783Y1065717D01*
G03X539486Y1066974I-772J1257D01*
G01Y1067035D01*
G02X540597Y1068901I2225J-61D01*
G01X540599D01*
X540657Y1068935D01*
G02X542825Y1068901I1054J-1961D01*
G03X544299I737J1277D01*
G01X544357Y1068935D01*
G02X546525Y1068901I1054J-1961D01*
G03X547262Y1068701I742J1276D01*
G01X548401D01*
G01X456611Y1066974D02*
X459240Y1065023D01*
G03X461424Y1065047I1071J1951D01*
G02X462898I737J-1277D01*
G01X462939Y1065023D01*
G03X465125Y1065047I1072J1951D01*
G02X466598I737J-1276D01*
G01X466599D01*
X466657Y1065013D01*
G03X468825Y1065047I1054J1961D01*
G02X470299I737J-1277D01*
G01X470357Y1065013D01*
G03X472525Y1065047I1054J1961D01*
G02X473999I737J-1277D01*
G01X474057Y1065013D01*
G03X476225Y1065047I1054J1961D01*
G02X477699I737J-1277D01*
G01X477757Y1065013D01*
G03X479925Y1065047I1054J1961D01*
G02X481399I737J-1277D01*
G03X483625I1113J1927D01*
G02X485099I737J-1277D01*
G01X485157Y1065013D01*
G03X487325Y1065047I1054J1961D01*
G02X488799I737J-1277D01*
G01X488857Y1065013D01*
G03X491025Y1065047I1054J1961D01*
G02X492499I737J-1277D01*
G01X492557Y1065013D01*
G03X494725Y1065047I1054J1961D01*
G02X496199I737J-1277D01*
G01X496257Y1065013D01*
G03X498425Y1065047I1054J1961D01*
G02X499899I737J-1277D01*
G01X499957Y1065013D01*
G03X502125Y1065047I1054J1961D01*
G02X503599I737J-1277D01*
G01X503657Y1065013D01*
G03X505825Y1065047I1054J1961D01*
G02X507299I737J-1277D01*
G01X507357Y1065013D01*
G03X509525Y1065047I1054J1961D01*
G02X510999I737J-1277D01*
G01X511057Y1065013D01*
G03X513225Y1065047I1054J1961D01*
G02X514699I737J-1277D01*
G01X514757Y1065013D01*
G03X516925Y1065047I1054J1961D01*
G02X518399I737J-1277D01*
G01X518457Y1065013D01*
G03X520625Y1065047I1054J1961D01*
G02X522099I737J-1277D01*
G01X522140Y1065023D01*
G03X524324Y1065047I1071J1951D01*
G02X525798I737J-1277D01*
G01X525839Y1065023D01*
G03X528025Y1065047I1072J1951D01*
G02X529499I737J-1277D01*
G01X529557Y1065013D01*
G03X531725Y1065047I1054J1961D01*
G02X533199I737J-1277D01*
G01X533257Y1065013D01*
G03X535425Y1065047I1054J1961D01*
G02X536899I737J-1277D01*
G01X536957Y1065013D01*
G03X539125Y1065047I1054J1961D01*
G03X540236Y1066913I-1114J1927D01*
G01Y1066974D01*
G02X540939Y1068231I1475J0D01*
G01X540974Y1068251D01*
G02X542448I737J-1277D01*
G03X544616Y1068217I1114J1927D01*
G01X544674Y1068251D01*
G02X546148I737J-1277D01*
G03X547262Y1067952I1114J1926D01*
G01X548716D01*
X549336Y1067332D01*
G01X469129Y902649D02*
G02X469503Y899506I-13019J-3143D01*
G01Y899445D01*
G03X470206Y898188I1475J0D01*
G01X470241Y898168D01*
G03X471715I737J1277D01*
G02X473883Y898202I1115J-1928D01*
G01X473941Y898168D01*
G03X475415I737J1277D01*
G02X477583Y898202I1115J-1928D01*
G01X477641Y898168D01*
G03X479115I737J1277D01*
G02X481341I1113J-1928D01*
G03X482815I737J1277D01*
G02X484983Y898202I1115J-1928D01*
G01X485041Y898168D01*
G03X486515I737J1277D01*
G02X488683Y898202I1115J-1928D01*
G01X488741Y898168D01*
G03X490215I737J1277D01*
G02X492383Y898202I1115J-1928D01*
G01X492441Y898168D01*
G03X493915I737J1277D01*
G02X496101Y898192I1114J-1928D01*
G01X496142Y898168D01*
G03X497616I737J1277D01*
G02X499800Y898192I1113J-1928D01*
G01X499841Y898168D01*
G03X501315I737J1277D01*
G02X503541I1113J-1928D01*
G03X505015I737J1277D01*
G02X507241I1113J-1928D01*
G03X508715I737J1277D01*
G02X510883Y898202I1115J-1928D01*
G01X510941Y898168D01*
G03X512415I737J1277D01*
G02X514583Y898202I1115J-1928D01*
G01X514641Y898168D01*
G03X516115I737J1277D01*
G02X518283Y898202I1115J-1928D01*
G01X518341Y898168D01*
G03X519815I737J1277D01*
G02X522001Y898192I1114J-1928D01*
G01X522042Y898168D01*
G03X523516I737J1277D01*
G02X525742I1113J-1928D01*
G03X527216I737J1277D01*
G02X529400Y898192I1113J-1928D01*
G01X529441Y898168D01*
G03X530915I737J1277D01*
G02X533101Y898192I1114J-1928D01*
G01X533142Y898168D01*
G03X534616I737J1277D01*
G02X536842I1113J-1928D01*
G01X537175Y897835D01*
X539177D01*
G01X474678Y893036D02*
X474062Y894103D01*
X474145Y894410D01*
G02X475415Y894313I534J-1374D01*
G03X477601Y894289I1114J1927D01*
G01X477642Y894313D01*
G02X479116I737J-1277D01*
G01X479157Y894289D01*
G03X481341Y894313I1071J1951D01*
G02X482815I737J-1277D01*
G03X484983Y894279I1114J1927D01*
G01X485041Y894313D01*
G02X486515I737J-1277D01*
G03X488701Y894289I1114J1927D01*
G01X488742Y894313D01*
G02X490216I737J-1277D01*
G03X492400Y894289I1113J1927D01*
G01X492441Y894313D01*
G02X493915I737J-1277D01*
G03X496083Y894279I1114J1927D01*
G01X496141Y894313D01*
G02X497615I737J-1277D01*
G03X499801Y894289I1114J1927D01*
G01X499842Y894313D01*
G02X501316I737J-1277D01*
G01X501374Y894279D01*
G03X503542Y894313I1054J1961D01*
G02X505016I737J-1277D01*
G01X505057Y894289D01*
G03X507241Y894313I1071J1951D01*
G02X508715I737J-1277D01*
G03X510883Y894279I1114J1927D01*
G01X510941Y894313D01*
G02X512415I737J-1277D01*
G03X514601Y894289I1114J1927D01*
G01X514642Y894313D01*
G02X516116I737J-1277D01*
G03X518300Y894289I1113J1927D01*
G01X518341Y894313D01*
G02X519815I737J-1277D01*
G03X521983Y894279I1114J1927D01*
G01X522041Y894313D01*
G02X523515I737J-1277D01*
G03X525701Y894289I1114J1927D01*
G01X525742Y894313D01*
G02X527216I737J-1277D01*
G03X529400Y894289I1113J1927D01*
G01X529441Y894313D01*
G02X530915I737J-1277D01*
G03X533101Y894289I1114J1927D01*
G01X533142Y894313D01*
G02X534616I737J-1277D01*
G03X536842I1113J1927D01*
G02X538316I737J-1277D01*
G03X539236Y894022I1115J1926D01*
G03X539660Y894004I424J4987D01*
G01X539663D01*
X540919Y892748D01*
G01X472829Y896240D02*
X473445Y895173D01*
X473795Y895080D01*
G02X475792Y894963I882J-2044D01*
G03X477266I737J1277D01*
G02X479450Y894987I1113J-1927D01*
G01X479491Y894963D01*
G03X480965I737J1277D01*
G01X481006Y894987D01*
G02X483192Y894963I1072J-1951D01*
G03X484666I737J1277D01*
G01X484724Y894997D01*
G02X486892Y894963I1054J-1961D01*
G03X488366I737J1277D01*
G02X490592I1113J-1927D01*
G03X492066I737J1277D01*
G01X492124Y894997D01*
G02X494292Y894963I1054J-1961D01*
G03X495766I737J1277D01*
G01X495824Y894997D01*
G02X497992Y894963I1054J-1961D01*
G03X499466I737J1277D01*
G02X501650Y894987I1113J-1927D01*
G01X501691Y894963D01*
G03X503165I737J1277D01*
G02X505333Y894997I1114J-1927D01*
G01X505391Y894963D01*
G03X506865I737J1277D01*
G01X506906Y894987D01*
G02X509092Y894963I1072J-1951D01*
G03X510566I737J1277D01*
G01X510624Y894997D01*
G02X512792Y894963I1054J-1961D01*
G03X514266I737J1277D01*
G02X516492I1113J-1927D01*
G03X517966I737J1277D01*
G01X518024Y894997D01*
G02X520192Y894963I1054J-1961D01*
G03X521666I737J1277D01*
G01X521724Y894997D01*
G02X523892Y894963I1054J-1961D01*
G03X525366I737J1277D01*
G02X527592I1113J-1927D01*
G03X529066I737J1277D01*
G01X529124Y894997D01*
G02X531292Y894963I1054J-1961D01*
G03X532766I737J1277D01*
G02X534992I1113J-1927D01*
G03X536466I737J1277D01*
G02X538577Y895026I1114J-1927D01*
G03X539575Y894789I999J1988D01*
G01X540868D01*
X541674Y893983D01*
G01X478378Y899445D02*
X478994Y900512D01*
X479345Y900606D01*
G03X481283Y900688I884J2043D01*
G01X481341Y900722D01*
G02X482815I737J-1277D01*
G03X485041I1113J1927D01*
G02X486515I737J-1277D01*
G03X488683Y900688I1114J1927D01*
G01X488741Y900722D01*
G02X490215I737J-1277D01*
G03X492383Y900688I1114J1927D01*
G01X492441Y900722D01*
G02X493915I737J-1277D01*
G03X496101Y900698I1114J1927D01*
G01X496142Y900722D01*
G02X497616I737J-1277D01*
G03X499800Y900698I1113J1927D01*
G01X499841Y900722D01*
G02X501315I737J-1277D01*
G03X503483Y900688I1114J1927D01*
G01X503541Y900722D01*
G02X505015I737J-1277D01*
G03X507183Y900688I1114J1927D01*
G01X507241Y900722D01*
G02X508715I737J-1277D01*
G03X510941I1113J1927D01*
G02X512415I737J-1277D01*
G03X514583Y900688I1114J1927D01*
G01X514641Y900722D01*
G02X516115I737J-1277D01*
G03X518283Y900688I1114J1927D01*
G01X518341Y900722D01*
G02X519815I737J-1277D01*
G03X522001Y900698I1114J1927D01*
G01X522042Y900722D01*
G02X523516I737J-1277D01*
G03X525742I1113J1927D01*
G02X527216I737J-1277D01*
G03X529400Y900698I1113J1927D01*
G01X529441Y900722D01*
G02X530915I737J-1277D01*
G03X533101Y900698I1114J1927D01*
G01X533142Y900722D01*
G02X534616I737J-1277D01*
G03X536842I1113J1927D01*
G02X538316I737J-1277D01*
G02X538623Y900489I-731J-1282D01*
G01X539117Y899995D01*
X540447D01*
G01X480229Y902649D02*
X479613Y901582D01*
X479696Y901275D01*
G03X480966Y901372I534J1374D01*
G01X481007Y901396D01*
G02X483191Y901372I1071J-1951D01*
G03X484665I737J1277D01*
G01X484706Y901396D01*
G02X486892Y901372I1072J-1951D01*
G03X488366I737J1277D01*
G01X488424Y901406D01*
G02X490592Y901372I1054J-1961D01*
G03X492066I737J1277D01*
G01X492124Y901406D01*
G02X494292Y901372I1054J-1961D01*
G03X495766I737J1277D01*
G02X497992I1113J-1927D01*
G03X499466I737J1277D01*
G01X499524Y901406D01*
G02X501692Y901372I1054J-1961D01*
G03X503166I737J1277D01*
G01X503224Y901406D01*
G02X505392Y901372I1054J-1961D01*
G03X506866I737J1277D01*
G01X506907Y901396D01*
G02X509091Y901372I1071J-1951D01*
G03X510565I737J1277D01*
G01X510606Y901396D01*
G02X512792Y901372I1072J-1951D01*
G03X514266I737J1277D01*
G01X514324Y901406D01*
G02X516492Y901372I1054J-1961D01*
G03X517966I737J1277D01*
G01X518024Y901406D01*
G02X520192Y901372I1054J-1961D01*
G03X521666I737J1277D01*
G02X523892I1113J-1927D01*
G03X525366I737J1277D01*
G02X527592I1113J-1927D01*
G03X529066I737J1277D01*
G01X529124Y901406D01*
G02X531292Y901372I1054J-1961D01*
G03X532766I737J1277D01*
G02X534992I1113J-1927D01*
G03X536466I737J1277D01*
G02X538692I1113J-1927D01*
G01X541044D01*
G01X538171Y904125D02*
G02X537040Y904456I0J2099D01*
G03X536842Y904576I-2555J-3992D01*
G03X534616I-1113J-1927D01*
G02X533142I-737J1277D01*
G03X530916I-1113J-1927D01*
G02X529442I-737J1277D01*
G03X527216I-1113J-1927D01*
G02X525742I-737J1277D01*
G01X525701Y904600D01*
G03X523515Y904576I-1072J-1951D01*
G02X522041I-737J1277D01*
G01X522000Y904600D01*
G03X519816Y904576I-1071J-1951D01*
G02X518342I-737J1277D01*
G01X518301Y904600D01*
G03X516115Y904576I-1072J-1951D01*
G02X514641I-737J1277D01*
G01X514583Y904610D01*
G03X512415Y904576I-1054J-1961D01*
G02X510941I-737J1277D01*
G03X508715I-1113J-1927D01*
G02X507241I-737J1277D01*
G01X507183Y904610D01*
G03X505015Y904576I-1054J-1961D01*
G02X503541I-737J1277D01*
G01X503483Y904610D01*
G03X501315Y904576I-1054J-1961D01*
G02X499841I-737J1277D01*
G01X499783Y904610D01*
G03X497615Y904576I-1054J-1961D01*
G02X496141I-737J1277D01*
G01X496100Y904600D01*
G03X493916Y904576I-1071J-1951D01*
G02X492442I-737J1277D01*
G01X492401Y904600D01*
G03X490215Y904576I-1072J-1951D01*
G02X488741I-737J1277D01*
G01X488683Y904610D01*
G03X486515Y904576I-1054J-1961D01*
G02X485041I-737J1277D01*
G03X482815I-1113J-1927D01*
G02X481341I-737J1277D01*
G01X481283Y904610D01*
G03X479115Y904576I-1054J-1961D01*
G02X477641I-737J1277D01*
G01X477583Y904610D01*
G03X475415Y904576I-1054J-1961D01*
G03X474318Y902907I1114J-1927D01*
G01X474060Y902649D01*
X472829D01*
G01X480228Y909057D02*
X478997D01*
X478772Y908832D01*
G03X479491Y907780I1457J224D01*
G03X480965I737J1277D01*
G01X481006Y907804D01*
G02X483192Y907780I1072J-1951D01*
G03X484666I737J1277D01*
G01X484724Y907814D01*
G02X486892Y907780I1054J-1961D01*
G03X488366I737J1277D01*
G01X488424Y907814D01*
G02X490592Y907780I1054J-1961D01*
G03X492066I737J1277D01*
G02X494292I1113J-1927D01*
G03X495766I737J1277D01*
G01X495824Y907814D01*
G02X497992Y907780I1054J-1961D01*
G03X499466I737J1277D01*
G01X499524Y907814D01*
G02X501692Y907780I1054J-1961D01*
G03X503166I737J1277D01*
G01X503224Y907814D01*
G02X505392Y907780I1054J-1961D01*
G03X506866I737J1277D01*
G01X506924Y907814D01*
G02X509092Y907780I1054J-1961D01*
G03X510566I737J1277D01*
G01X510624Y907814D01*
G02X512792Y907780I1054J-1961D01*
G03X514266I737J1277D01*
G01X514324Y907814D01*
G02X516492Y907780I1054J-1961D01*
G03X517966I737J1277D01*
G02X520150Y907804I1113J-1927D01*
G01X520191Y907780D01*
G03X521665I737J1277D01*
G01X521706Y907804D01*
G02X523892Y907780I1072J-1951D01*
G03X525366I737J1277D01*
G02X527592I1113J-1927D01*
G03X529066I737J1277D01*
G02X531292I1113J-1927D01*
G03X532766I737J1277D01*
G02X534992I1113J-1927D01*
G03X536466I737J1277D01*
G02X538692I1113J-1927D01*
G03X540166I737J1277D01*
G01X540224Y907814D01*
G02X542392Y907780I1054J-1961D01*
G03X543866I737J1277D01*
G01X543907Y907804D01*
G02X546091Y907780I1071J-1951D01*
G03X547565I737J1277D01*
G02X548649Y908079I1115J-1927D01*
G01X550703D01*
G01X476529Y902649D02*
X475298D01*
X475072Y902875D01*
G02X475757Y903906I1458J-225D01*
G01X475792Y903926D01*
G02X477266I737J-1277D01*
G01X477324Y903892D01*
G03X479492Y903926I1054J1961D01*
G02X480966I737J-1277D01*
G01X481007Y903902D01*
G03X483191Y903926I1071J1951D01*
G02X484665I737J-1277D01*
G01X484706Y903902D01*
G03X486892Y903926I1072J1951D01*
G02X488366I737J-1277D01*
G01X488424Y903892D01*
G03X490592Y903926I1054J1961D01*
G02X492066I737J-1277D01*
G03X494292I1113J1927D01*
G02X495766I737J-1277D01*
G01X495824Y903892D01*
G03X497992Y903926I1054J1961D01*
G02X499466I737J-1277D01*
G01X499524Y903892D01*
G03X501692Y903926I1054J1961D01*
G02X503166I737J-1277D01*
G01X503224Y903892D01*
G03X505392Y903926I1054J1961D01*
G02X506866I737J-1277D01*
G01X506907Y903902D01*
G03X509091Y903926I1071J1951D01*
G02X510565I737J-1277D01*
G01X510606Y903902D01*
G03X512792Y903926I1072J1951D01*
G02X514266I737J-1277D01*
G01X514324Y903892D01*
G03X516492Y903926I1054J1961D01*
G02X517966I737J-1277D01*
G03X520192I1113J1927D01*
G02X521666I737J-1277D01*
G01X521724Y903892D01*
G03X523892Y903926I1054J1961D01*
G02X525366I737J-1277D01*
G03X527592I1113J1927D01*
G02X529066I737J-1277D01*
G03X531292I1113J1927D01*
G02X532766I737J-1277D01*
G03X534992I1113J1927D01*
G02X536466I737J-1277D01*
G02X536772Y903692I-735J-1278D01*
G01X537363Y903101D01*
X543385D01*
X543897Y902589D01*
G01X551961Y909222D02*
X550358Y909886D01*
X545549D01*
G02X543850Y910333I0J3453D01*
G01X543647Y910448D01*
G03X542376Y910336I-518J-1391D01*
G02X540400Y910191I-1135J1926D01*
G01X540150Y910333D01*
X540010Y910412D01*
G03X538692Y910334I-581J-1355D01*
G02X536466I-1113J1928D01*
G03X534992I-737J-1277D01*
G02X532766I-1113J1928D01*
G03X531292I-737J-1277D01*
G02X529066I-1113J1928D01*
G03X527592I-737J-1277D01*
G02X525366I-1113J1928D01*
G03X523892I-737J-1277D01*
G02X521706Y910310I-1114J1928D01*
G01X521665Y910334D01*
G03X520191I-737J-1277D01*
G02X518007Y910310I-1113J1928D01*
G01X517966Y910334D01*
G03X516492I-737J-1277D01*
G02X514324Y910300I-1115J1928D01*
G01X514266Y910334D01*
G03X512792I-737J-1277D01*
G02X510624Y910300I-1115J1928D01*
G01X510566Y910334D01*
G03X509092I-737J-1277D01*
G02X506866I-1113J1928D01*
G03X505392I-737J-1277D01*
G02X503224Y910300I-1115J1928D01*
G01X503166Y910334D01*
G03X501692I-737J-1277D01*
G02X499524Y910300I-1115J1928D01*
G01X499466Y910334D01*
G03X497992I-737J-1277D01*
G02X495824Y910300I-1115J1928D01*
G01X495766Y910334D01*
G03X494292I-737J-1277D01*
G02X492124Y910300I-1115J1928D01*
G01X492066Y910334D01*
G03X490592I-737J-1277D01*
G02X488424Y910300I-1115J1928D01*
G01X488366Y910334D01*
G03X486892I-737J-1277D01*
G02X484724Y910300I-1115J1928D01*
G01X484666Y910334D01*
G03X483192I-737J-1277D01*
G01X483151Y910310D01*
G02X480965Y910334I-1072J1952D01*
G03X479525Y910353I-737J-1277D01*
G01X479492Y910334D01*
X479434Y910300D01*
G02X477266Y910334I-1053J1962D01*
G03X475792I-737J-1277D01*
G02X473624Y910300I-1115J1928D01*
G01X473566Y910334D01*
G03X472092I-737J-1277D01*
G01X472057Y910314D01*
G03X471372Y909283I773J-1256D01*
G01X471598Y909057D01*
X472829D01*
G01X552360Y910972D02*
X549794D01*
X549457Y910635D01*
X545549D01*
G02X544219Y910986I0J2696D01*
G01X543963Y911131D01*
G03X541995Y910983I-834J-2074D01*
G02X540724Y910871I-753J1279D01*
G01X540521Y910986D01*
X540341Y911088D01*
G03X538316Y910985I-912J-2031D01*
G02X536842I-737J1277D01*
G03X534616I-1113J-1928D01*
G02X533142I-737J1277D01*
G03X530916I-1113J-1928D01*
G02X529442I-737J1277D01*
G03X527216I-1113J-1928D01*
G02X525742I-737J1277D01*
G01X525701Y911009D01*
G03X523515Y910985I-1072J-1952D01*
G02X522041I-737J1277D01*
G03X519815I-1113J-1928D01*
G02X518341I-737J1277D01*
G01X518283Y911019D01*
G03X516115Y910985I-1053J-1962D01*
G02X514641I-737J1277D01*
G01X514583Y911019D01*
G03X512415Y910985I-1053J-1962D01*
G02X510941I-737J1277D01*
G01X510900Y911009D01*
G03X508716Y910985I-1071J-1952D01*
G02X507242I-737J1277D01*
G01X507201Y911009D01*
G03X505015Y910985I-1072J-1952D01*
G02X503541I-737J1277D01*
G01X503483Y911019D01*
G03X501315Y910985I-1053J-1962D01*
G02X499841I-737J1277D01*
G01X499783Y911019D01*
G03X497615Y910985I-1053J-1962D01*
G02X496141I-737J1277D01*
G01X496083Y911019D01*
G03X493915Y910985I-1053J-1962D01*
G02X492441I-737J1277D01*
G01X492383Y911019D01*
G03X490215Y910985I-1053J-1962D01*
G02X488741I-737J1277D01*
G01X488683Y911019D01*
G03X486515Y910985I-1053J-1962D01*
G02X485041I-737J1277D01*
G01X485000Y911009D01*
G03X482816Y910985I-1071J-1952D01*
G02X481342I-737J1277D01*
G03X479174Y911019I-1115J-1928D01*
G01X479116Y910985D01*
X479083Y910966D01*
G02X477643Y910985I-703J1296D01*
G03X475415I-1114J-1928D01*
G02X473941I-737J1277D01*
G03X471717I-1112J-1928D01*
G03X470618Y909315I1112J-1928D01*
G01X470360Y909057D01*
X469129D01*
G01X552860Y905952D02*
X550861D01*
X550047Y906766D01*
X549416Y907130D01*
G03X547942I-737J-1277D01*
G02X545756Y907106I-1114J1927D01*
G01X545715Y907130D01*
G03X544241I-737J-1277D01*
G01X544183Y907096D01*
G02X542015Y907130I-1054J1961D01*
G03X540541I-737J-1277D01*
G01X540500Y907106D01*
G02X538316Y907130I-1071J1951D01*
G03X536842I-737J-1277D01*
G02X534616I-1113J1927D01*
G03X533142I-737J-1277D01*
G02X530916I-1113J1927D01*
G03X529442I-737J-1277D01*
G02X527216I-1113J1927D01*
G03X525742I-737J-1277D01*
G01X525701Y907106D01*
G02X523515Y907130I-1072J1951D01*
G03X522041I-737J-1277D01*
G02X519857Y907106I-1113J1927D01*
G01X519816Y907130D01*
G03X518342I-737J-1277D01*
G01X518301Y907106D01*
G02X516115Y907130I-1072J1951D01*
G03X514641I-737J-1277D01*
G01X514583Y907096D01*
G02X512415Y907130I-1054J1961D01*
G03X510941I-737J-1277D01*
G01X510883Y907096D01*
G02X508715Y907130I-1054J1961D01*
G03X507241I-737J-1277D01*
G01X507183Y907096D01*
G02X505015Y907130I-1054J1961D01*
G03X503541I-737J-1277D01*
G01X503483Y907096D01*
G02X501315Y907130I-1054J1961D01*
G03X499841I-737J-1277D01*
G01X499783Y907096D01*
G02X497615Y907130I-1054J1961D01*
G03X496141I-737J-1277D01*
G01X496100Y907106D01*
G02X493916Y907130I-1071J1951D01*
G03X492442I-737J-1277D01*
G01X492401Y907106D01*
G02X490215Y907130I-1072J1951D01*
G03X488741I-737J-1277D01*
G01X488683Y907096D01*
G02X486515Y907130I-1054J1961D01*
G03X485041I-737J-1277D01*
G01X484983Y907096D01*
G02X482815Y907130I-1054J1961D01*
G03X481341I-737J-1277D01*
G02X479115I-1113J1927D01*
G02X478017Y908800I1112J1927D01*
G01X477760Y909057D01*
X476529D01*
G01X541617Y933159D02*
X541530D01*
X541395Y933294D01*
X535106D01*
G03X533141Y932764I0J-3908D01*
G01X533110Y932746D01*
G03X532404Y931488I768J-1258D01*
G01Y931415D01*
G02X529066Y929560I-2225J73D01*
G03X527592I-737J-1277D01*
G02X525366I-1113J1928D01*
G03X523892I-737J-1277D01*
G02X521706Y929536I-1114J1928D01*
G01X521665Y929560D01*
G03X520191I-737J-1277D01*
G02X518007Y929536I-1113J1928D01*
G01X517966Y929560D01*
G03X516492I-737J-1277D01*
G02X514324Y929526I-1115J1928D01*
G01X514266Y929560D01*
G03X512792I-737J-1277D01*
G02X510624Y929526I-1115J1928D01*
G01X510566Y929560D01*
G03X509092I-737J-1277D01*
G02X506866I-1113J1928D01*
G03X505392I-737J-1277D01*
G02X503224Y929526I-1115J1928D01*
G01X503166Y929560D01*
G03X501692I-737J-1277D01*
G02X499524Y929526I-1115J1928D01*
G01X499466Y929560D01*
G03X497992I-737J-1277D01*
G02X495806Y929536I-1114J1928D01*
G01X495765Y929560D01*
G03X494291I-737J-1277D01*
G02X492107Y929536I-1113J1928D01*
G01X492066Y929560D01*
G03X490592I-737J-1277D01*
G02X488424Y929526I-1115J1928D01*
G01X488366Y929560D01*
G03X486892I-737J-1277D01*
G02X484724Y929526I-1115J1928D01*
G01X484666Y929560D01*
G03X483192I-737J-1277D01*
G02X480966I-1113J1928D01*
G03X479696Y929657I-736J-1277D01*
G01X479613Y929350D01*
X480229Y928283D01*
G01X541617Y934179D02*
X541530D01*
X541394Y934043D01*
X535105D01*
G03X532765Y933412I1J-4657D01*
G01X532742Y933401D01*
G03X531653Y931488I1136J-1913D01*
G01Y931454D01*
G02X529442Y930211I-1474J34D01*
G03X527216I-1113J-1928D01*
G02X525742I-737J1277D01*
G01X525701Y930235D01*
G03X523515Y930211I-1072J-1952D01*
G02X522041I-737J1277D01*
G03X519815I-1113J-1928D01*
G02X518341I-737J1277D01*
G01X518283Y930245D01*
G03X516115Y930211I-1053J-1962D01*
G02X514641I-737J1277D01*
G01X514583Y930245D01*
G03X512415Y930211I-1053J-1962D01*
G02X510941I-737J1277D01*
G01X510900Y930235D01*
G03X508716Y930211I-1071J-1952D01*
G02X507242I-737J1277D01*
G01X507201Y930235D01*
G03X505015Y930211I-1072J-1952D01*
G02X503541I-737J1277D01*
G01X503483Y930245D01*
G03X501315Y930211I-1053J-1962D01*
G02X499841I-737J1277D01*
G01X499783Y930245D01*
G03X497615Y930211I-1053J-1962D01*
G02X496141I-737J1277D01*
G03X493915I-1113J-1928D01*
G02X492441I-737J1277D01*
G01X492383Y930245D01*
G03X490215Y930211I-1053J-1962D01*
G02X488741I-737J1277D01*
G01X488683Y930245D01*
G03X486515Y930211I-1053J-1962D01*
G02X485041I-737J1277D01*
G01X485000Y930235D01*
G03X482816Y930211I-1071J-1952D01*
G02X481342I-737J1277D01*
G01X481301Y930235D01*
G03X479424Y930359I-1072J-1952D01*
G03X479345Y930327I796J-2079D01*
G01X478994Y930421D01*
X478378Y931488D01*
G01X548837Y927411D02*
X548750D01*
X548615Y927546D01*
X545788D01*
X541096Y922854D01*
X537577D01*
G02X537085Y922909I0J2225D01*
G02X536466Y923152I494J2169D01*
G03X534992I-737J-1277D01*
G02X532766I-1113J1927D01*
G03X531292I-737J-1277D01*
G02X529066I-1113J1927D01*
G03X527592I-737J-1277D01*
G02X525366I-1113J1927D01*
G03X523892I-737J-1277D01*
G02X521724Y923118I-1114J1927D01*
G01X521666Y923152D01*
G03X520192I-737J-1277D01*
G02X517966I-1113J1927D01*
G03X516492I-737J-1277D01*
G02X514324Y923118I-1114J1927D01*
G01X514266Y923152D01*
G03X512792I-737J-1277D01*
G02X510606Y923128I-1114J1927D01*
G01X510565Y923152D01*
G03X509091I-737J-1277D01*
G02X506907Y923128I-1113J1927D01*
G01X506866Y923152D01*
G03X505392I-737J-1277D01*
G02X503224Y923118I-1114J1927D01*
G01X503166Y923152D01*
G03X501692I-737J-1277D01*
G02X499524Y923118I-1114J1927D01*
G01X499466Y923152D01*
G03X497992I-737J-1277D01*
G02X495824Y923118I-1114J1927D01*
G01X495766Y923152D01*
G03X494292I-737J-1277D01*
G02X492066I-1113J1927D01*
G03X490592I-737J-1277D01*
G02X488424Y923118I-1114J1927D01*
G01X488366Y923152D01*
G03X486892I-737J-1277D01*
G02X484706Y923128I-1114J1927D01*
G01X484665Y923152D01*
G03X483191I-737J-1277D01*
G02X481007Y923128I-1113J1927D01*
G01X480942Y923166D01*
G02X479879Y924738I1136J1913D01*
G02X479868Y924820I2199J337D01*
G01X479609Y925079D01*
X478378D01*
G01X548837Y928431D02*
X548750D01*
X548614Y928295D01*
X545477D01*
X540785Y923603D01*
X537578D01*
G02X536841Y923802I3J1475D01*
G01X536800Y923826D01*
G03X534616Y923802I-1071J-1951D01*
G02X533142I-737J1277D01*
G03X530916I-1113J-1927D01*
G02X529442I-737J1277D01*
G03X527216I-1113J-1927D01*
G02X525742I-737J1277D01*
G01X525701Y923826D01*
G03X523515Y923802I-1072J-1951D01*
G02X522041I-737J1277D01*
G01X522000Y923826D01*
G03X519816Y923802I-1071J-1951D01*
G02X518342I-737J1277D01*
G01X518301Y923826D01*
G03X516115Y923802I-1072J-1951D01*
G02X514641I-737J1277D01*
G01X514583Y923836D01*
G03X512415Y923802I-1054J-1961D01*
G02X510941I-737J1277D01*
G03X508715I-1113J-1927D01*
G02X507241I-737J1277D01*
G01X507183Y923836D01*
G03X505015Y923802I-1054J-1961D01*
G02X503541I-737J1277D01*
G01X503483Y923836D01*
G03X501315Y923802I-1054J-1961D01*
G02X499841I-737J1277D01*
G01X499783Y923836D01*
G03X497615Y923802I-1054J-1961D01*
G02X496141I-737J1277D01*
G01X496100Y923826D01*
G03X493916Y923802I-1071J-1951D01*
G02X492442I-737J1277D01*
G01X492401Y923826D01*
G03X490215Y923802I-1072J-1951D01*
G02X488741I-737J1277D01*
G01X488683Y923836D01*
G03X486515Y923802I-1054J-1961D01*
G02X485041I-737J1277D01*
G03X482815I-1113J-1927D01*
G02X481341I-737J1277D01*
G01X481335Y923805D01*
G02X480621Y924853I744J1274D01*
G01X480847Y925079D01*
X482078D01*
G01X542167Y938739D02*
X542080D01*
X541945Y938874D01*
X539429D01*
G02X539236Y938882I-4J2226D01*
G02X538316Y939173I195J2217D01*
G03X536842I-737J-1277D01*
G02X534616I-1113J1927D01*
G03X533142I-737J-1277D01*
G02X530916I-1113J1927D01*
G03X529442I-737J-1277D01*
G02X527216I-1113J1927D01*
G03X525742I-737J-1277D01*
G02X523516I-1113J1927D01*
G03X522042I-737J-1277D01*
G01X522001Y939149D01*
G02X519815Y939173I-1072J1951D01*
G03X518341I-737J-1277D01*
G01X518283Y939139D01*
G02X516115Y939173I-1054J1961D01*
G03X514641I-737J-1277D01*
G01X514583Y939139D01*
G02X512415Y939173I-1054J1961D01*
G03X510941I-737J-1277D01*
G02X508715I-1113J1927D01*
G03X507241I-737J-1277D01*
G01X507183Y939139D01*
G02X505015Y939173I-1054J1961D01*
G03X503541I-737J-1277D01*
G01X503483Y939139D01*
G02X501315Y939173I-1054J1961D01*
G03X499841I-737J-1277D01*
G01X499800Y939149D01*
G02X497616Y939173I-1071J1951D01*
G03X496142I-737J-1277D01*
G01X496101Y939149D01*
G02X493915Y939173I-1072J1951D01*
G03X492441I-737J-1277D01*
G01X492383Y939139D01*
G02X490215Y939173I-1054J1961D01*
G03X488741I-737J-1277D01*
G01X488683Y939139D01*
G02X486515Y939173I-1054J1961D01*
G03X485041I-737J-1277D01*
G02X482815I-1113J1927D01*
G03X481341I-737J-1277D01*
G01X481283Y939139D01*
G02X479424Y939025I-1053J1961D01*
G02X479345Y939057I796J2078D01*
G01X478994Y938963D01*
X478378Y937896D01*
G01X542167Y939759D02*
X542080D01*
X541944Y939623D01*
X539428D01*
G02X539301Y939629I6J1476D01*
G02X538691Y939822I130J1471D01*
G03X536467I-1112J-1926D01*
G02X534991I-738J1278D01*
G03X532767I-1112J-1926D01*
G02X531291I-738J1278D01*
G03X529067I-1112J-1926D01*
G02X527591I-738J1278D01*
G03X525367I-1112J-1926D01*
G02X523891I-738J1278D01*
G03X521665Y939821I-1112J-1926D01*
G01X521632Y939801D01*
G02X520190Y939822I-702J1299D01*
G03X517964Y939821I-1112J-1926D01*
G01X517917Y939793D01*
G02X516490Y939822I-687J1307D01*
G03X514264Y939821I-1112J-1926D01*
G01X514217Y939793D01*
G02X512790Y939822I-687J1307D01*
G03X510566I-1112J-1926D01*
G02X509090I-738J1278D01*
G03X506864Y939821I-1112J-1926D01*
G01X506817Y939793D01*
G02X505390Y939822I-687J1307D01*
G03X503164Y939821I-1112J-1926D01*
G01X503117Y939793D01*
G02X501690Y939822I-687J1307D01*
G03X499464Y939821I-1112J-1926D01*
G01X499431Y939801D01*
G02X497991Y939822I-701J1299D01*
G03X495765Y939821I-1112J-1926D01*
G01X495732Y939801D01*
G02X494290Y939822I-702J1299D01*
G03X492064Y939821I-1112J-1926D01*
G01X492017Y939793D01*
G02X490590Y939822I-687J1307D01*
G03X488364Y939821I-1112J-1926D01*
G01X488317Y939793D01*
G02X486890Y939822I-687J1307D01*
G03X484666I-1112J-1926D01*
G02X483190I-738J1278D01*
G03X480964Y939821I-1112J-1926D01*
G01X480917Y939793D01*
G02X479695Y939724I-687J1307D01*
G01X479696Y939726D01*
X479613Y940033D01*
X480229Y941100D01*
G01X538289Y965150D02*
X537034D01*
X536543Y964659D01*
X535180D01*
X534381Y965458D01*
X532766D01*
G02X531292I-737J1277D01*
G03X529124Y965492I-1115J-1928D01*
G01X529066Y965458D01*
G02X527592I-737J1277D01*
G03X525366I-1113J-1928D01*
G02X523892I-737J1277D01*
G03X521706Y965482I-1114J-1928D01*
G01X521665Y965458D01*
G02X520191I-737J1277D01*
G01X520150Y965482D01*
G03X517966Y965458I-1071J-1952D01*
G02X516492I-737J1277D01*
G03X514324Y965492I-1115J-1928D01*
G01X514266Y965458D01*
G02X512792I-737J1277D01*
G03X510624Y965492I-1115J-1928D01*
G01X510566Y965458D01*
G02X509092I-737J1277D01*
G03X506924Y965492I-1115J-1928D01*
G01X506866Y965458D01*
G02X505392I-737J1277D01*
G03X503206Y965482I-1114J-1928D01*
G01X503165Y965458D01*
G02X501691I-737J1277D01*
G01X501650Y965482D01*
G03X499466Y965458I-1071J-1952D01*
G02X497992I-737J1277D01*
G03X495806Y965482I-1114J-1928D01*
G01X495765Y965458D01*
G02X494291I-737J1277D01*
G01X494250Y965482D01*
G03X492066Y965458I-1071J-1952D01*
G02X490592I-737J1277D01*
G03X488424Y965492I-1115J-1928D01*
G01X488366Y965458D01*
G02X486892I-737J1277D01*
G03X484724Y965492I-1115J-1928D01*
G01X484666Y965458D01*
X484663Y965457D01*
X484643Y965446D01*
G02X483211I-716J1241D01*
G01X483191Y965457D01*
X480237Y966716D01*
X480229Y966735D01*
G01X536570Y961986D02*
X532561D01*
X531740Y962807D01*
Y964222D01*
X531347Y964615D01*
G02X530915Y964807I683J2119D01*
G03X529441I-737J-1277D01*
G01X529400Y964783D01*
G02X527216Y964807I-1071J1952D01*
G03X525742I-737J-1277D01*
G01X525701Y964783D01*
G02X523515Y964807I-1072J1952D01*
G03X522041I-737J-1277D01*
G02X519857Y964783I-1113J1928D01*
G01X519816Y964807D01*
G03X518342I-737J-1277D01*
G01X518301Y964783D01*
G02X516115Y964807I-1072J1952D01*
G03X514641I-737J-1277D01*
G01X514583Y964773D01*
G02X512415Y964807I-1053J1962D01*
G03X510941I-737J-1277D01*
G01X510883Y964773D01*
G02X508715Y964807I-1053J1962D01*
G03X507241I-737J-1277D01*
G01X507183Y964773D01*
G02X505015Y964807I-1053J1962D01*
G03X503541I-737J-1277D01*
G02X501357Y964783I-1113J1928D01*
G01X501316Y964807D01*
G03X499842I-737J-1277D01*
G01X499801Y964783D01*
G02X497615Y964807I-1072J1952D01*
G03X496141I-737J-1277D01*
G02X493957Y964783I-1113J1928D01*
G01X493916Y964807D01*
G03X492442I-737J-1277D01*
G01X492401Y964783D01*
G02X490215Y964807I-1072J1952D01*
G03X488741I-737J-1277D01*
G01X488683Y964773D01*
G02X486515Y964807I-1053J1962D01*
G03X485041I-737J-1277D01*
G01X484878Y964710D01*
X482098Y963521D01*
X482078Y963529D01*
G01X480229Y979552D02*
X479613Y980619D01*
X479696Y980926D01*
G02X480966Y980829I534J-1374D01*
G01X481007Y980805D01*
G03X483191Y980829I1071J1951D01*
G02X484665I737J-1277D01*
G01X484706Y980805D01*
G03X486892Y980829I1072J1951D01*
G02X488366I737J-1277D01*
G01X488424Y980795D01*
G03X490592Y980829I1054J1961D01*
G02X492066I737J-1277D01*
G03X494292I1113J1927D01*
G02X495766I737J-1277D01*
G01X495824Y980795D01*
G03X497992Y980829I1054J1961D01*
G02X499466I737J-1277D01*
G01X499524Y980795D01*
G03X501692Y980829I1054J1961D01*
G02X503166I737J-1277D01*
G01X503224Y980795D01*
G03X505392Y980829I1054J1961D01*
G02X506866I737J-1277D01*
G01X506907Y980805D01*
G03X509091Y980829I1071J1951D01*
G02X510565I737J-1277D01*
G01X510606Y980805D01*
G03X512792Y980829I1072J1951D01*
G02X514266I737J-1277D01*
G01X514324Y980795D01*
G03X516492Y980829I1054J1961D01*
G02X517966I737J-1277D01*
G03X520192I1113J1927D01*
G02X520929Y981028I740J-1276D01*
G01X522598D01*
G01X478378Y982756D02*
X478994Y981689D01*
X479345Y981595D01*
G02X481283Y981513I884J-2043D01*
G01X481341Y981479D01*
G03X482815I737J1277D01*
G02X485041I1113J-1927D01*
G03X486515I737J1277D01*
G02X488683Y981513I1114J-1927D01*
G01X488741Y981479D01*
G03X490215I737J1277D01*
G02X492401Y981503I1114J-1927D01*
G01X492442Y981479D01*
G03X493916I737J1277D01*
G02X496100Y981503I1113J-1927D01*
G01X496141Y981479D01*
G03X497615I737J1277D01*
G02X499783Y981513I1114J-1927D01*
G01X499841Y981479D01*
G03X501315I737J1277D01*
G02X503483Y981513I1114J-1927D01*
G01X503541Y981479D01*
G03X505015I737J1277D01*
G02X507183Y981513I1114J-1927D01*
G01X507241Y981479D01*
G03X508715I737J1277D01*
G02X510941I1113J-1927D01*
G03X512415I737J1277D01*
G02X514583Y981513I1114J-1927D01*
G01X514641Y981479D01*
G03X516115I737J1277D01*
G02X518301Y981503I1114J-1927D01*
G01X518342Y981479D01*
G03X519816I737J1277D01*
G02X520929Y981777I1112J-1927D01*
G01X523816Y984664D01*
G01X528346Y975368D02*
X524628D01*
G03X523516Y975070I0J-2224D01*
G02X522042I-737J1277D01*
G01X522001Y975094D01*
G03X519815Y975070I-1072J-1951D01*
G02X518341I-737J1277D01*
G03X516157Y975094I-1113J-1927D01*
G01X516116Y975070D01*
G02X514642I-737J1277D01*
G01X514601Y975094D01*
G03X512415Y975070I-1072J-1951D01*
G02X510941I-737J1277D01*
G01X510883Y975104D01*
G03X508715Y975070I-1054J-1961D01*
G02X507241I-737J1277D01*
G01X507183Y975104D01*
G03X505015Y975070I-1054J-1961D01*
G02X503541I-737J1277D01*
G01X503483Y975104D01*
G03X501315Y975070I-1054J-1961D01*
G02X499841I-737J1277D01*
G03X497657Y975094I-1113J-1927D01*
G01X497616Y975070D01*
G02X496142I-737J1277D01*
G01X496101Y975094D01*
G03X493915Y975070I-1072J-1951D01*
G02X492441I-737J1277D01*
G01X492383Y975104D01*
G03X490215Y975070I-1054J-1961D01*
G02X488741I-737J1277D01*
G01X488683Y975104D01*
G03X486515Y975070I-1054J-1961D01*
G02X485041I-737J1277D01*
G01X484983Y975104D01*
G03X482815Y975070I-1054J-1961D01*
G02X481341I-737J1277D01*
G01X481283Y975104D01*
G03X480382Y975364I-1054J-1961D01*
G01X478378Y976347D01*
G01X480662Y1031727D02*
X483436Y1030125D01*
G03X485286I925J1602D01*
G02X487136I925J-1602D01*
G03X488933Y1030094I926J1602D01*
G01X488986Y1030125D01*
G02X490836I925J-1602D01*
G03X492633Y1030094I926J1602D01*
G01X492686Y1030125D01*
G02X494536I925J-1602D01*
G03X496386I925J1602D01*
G02X498236I925J-1602D01*
G03X500033Y1030094I926J1602D01*
G01X500086Y1030125D01*
G02X501936I925J-1602D01*
G03X503733Y1030094I926J1602D01*
G01X503786Y1030125D01*
G02X505636I925J-1602D01*
G03X507433Y1030094I926J1602D01*
G01X507486Y1030125D01*
G02X509336I925J-1602D01*
G03X511133Y1030094I926J1602D01*
G01X511186Y1030125D01*
G02X513036I925J-1602D01*
G03X514833Y1030094I926J1602D01*
G01X514886Y1030125D01*
G02X516736I925J-1602D01*
G03X518533Y1030094I926J1602D01*
G01X518586Y1030125D01*
G02X520436I925J-1602D01*
G03X522286I925J1602D01*
G02X524136I925J-1602D01*
G03X525933Y1030094I926J1602D01*
G01X525986Y1030125D01*
G02X527836I925J-1602D01*
G03X529633Y1030094I926J1602D01*
G01X529686Y1030125D01*
G02X531536I925J-1602D01*
G03X533386I925J1602D01*
G02X535236I925J-1602D01*
G02X535619Y1029831I-925J-1602D01*
G01X536552Y1028898D01*
G01X469562Y1044544D02*
X470641Y1044794D01*
X471037Y1044544D01*
Y1044542D01*
G03X472148Y1042617I2223J0D01*
G03X474316Y1042583I1114J1927D01*
G01X474374Y1042617D01*
G02X475848I737J-1277D01*
G03X478016Y1042583I1114J1927D01*
G01X478074Y1042617D01*
X478164Y1042670D01*
X478278Y1042714D01*
G02X479548Y1042617I534J-1374D01*
G03X481716Y1042583I1114J1927D01*
G01X481774Y1042617D01*
G02X483248I737J-1277D01*
G03X485416Y1042583I1114J1927D01*
G01X485474Y1042617D01*
G02X486948I737J-1277D01*
G03X489116Y1042583I1114J1927D01*
G01X489174Y1042617D01*
G02X490648I737J-1277D01*
G03X492816Y1042583I1114J1927D01*
G01X492874Y1042617D01*
G02X494348I737J-1277D01*
G03X496534Y1042593I1114J1927D01*
G01X496575Y1042617D01*
G02X498049I737J-1277D01*
G01X498090Y1042593D01*
G03X500274Y1042617I1071J1951D01*
G02X501748I737J-1277D01*
G03X503916Y1042583I1114J1927D01*
G01X503974Y1042617D01*
G02X505448I737J-1277D01*
G03X507616Y1042583I1114J1927D01*
G01X507674Y1042617D01*
G02X509148I737J-1277D01*
G03X511316Y1042583I1114J1927D01*
G01X511374Y1042617D01*
G02X512848I737J-1277D01*
G03X515016Y1042583I1114J1927D01*
G01X515074Y1042617D01*
G02X516548I737J-1277D01*
G03X518716Y1042583I1114J1927D01*
G01X518774Y1042617D01*
G02X520248I737J-1277D01*
G03X522434Y1042593I1114J1927D01*
G01X522475Y1042617D01*
G02X523949I737J-1277D01*
G01X523990Y1042593D01*
G03X526174Y1042617I1071J1951D01*
G02X527648I737J-1277D01*
G03X529816Y1042583I1114J1927D01*
G01X529874Y1042617D01*
G02X531348I737J-1277D01*
G03X533516Y1042583I1114J1927D01*
G01X533574Y1042617D01*
G02X534311Y1042816I740J-1276D01*
G01X538462D01*
X538913Y1042365D01*
X543101D01*
G01X480662Y1038136D02*
X480046Y1039203D01*
X480129Y1039510D01*
G02X481399Y1039413I534J-1374D01*
G01X481440Y1039389D01*
G03X483624Y1039413I1071J1951D01*
G02X485098I737J-1277D01*
G01X485139Y1039389D01*
G03X487325Y1039413I1072J1951D01*
G02X488799I737J-1277D01*
G01X488857Y1039379D01*
G03X491025Y1039413I1054J1961D01*
G02X492499I737J-1277D01*
G01X492557Y1039379D01*
G03X494725Y1039413I1054J1961D01*
G02X496199I737J-1277D01*
G03X498425I1113J1927D01*
G02X499899I737J-1277D01*
G01X499957Y1039379D01*
G03X502125Y1039413I1054J1961D01*
G02X503599I737J-1277D01*
G01X503657Y1039379D01*
G03X505825Y1039413I1054J1961D01*
G02X507299I737J-1277D01*
G01X507340Y1039389D01*
G03X509524Y1039413I1071J1951D01*
G02X510998I737J-1277D01*
G01X511039Y1039389D01*
G03X513225Y1039413I1072J1951D01*
G02X514699I737J-1277D01*
G01X514757Y1039379D01*
G03X516925Y1039413I1054J1961D01*
G02X518399I737J-1277D01*
G01X518457Y1039379D01*
G03X520625Y1039413I1054J1961D01*
G02X522099I737J-1277D01*
G03X524325I1113J1927D01*
G02X525799I737J-1277D01*
G01X525857Y1039379D01*
G03X528025Y1039413I1054J1961D01*
G02X529499I737J-1277D01*
G01X529540Y1039389D01*
G03X531724Y1039413I1071J1951D01*
G02X533198I737J-1277D01*
G03X535424I1113J1927D01*
G02X536161Y1039612I740J-1276D01*
G01X541985D01*
X542070Y1039527D01*
G01X478811Y1041340D02*
X479427Y1040273D01*
X479778Y1040179D01*
G02X481716Y1040097I884J-2043D01*
G01X481774Y1040063D01*
G03X483248I737J1277D01*
G02X485474I1113J-1927D01*
G03X486948I737J1277D01*
G02X489116Y1040097I1114J-1927D01*
G01X489174Y1040063D01*
G03X490648I737J1277D01*
G02X492816Y1040097I1114J-1927D01*
G01X492874Y1040063D01*
G03X494348I737J1277D01*
G02X496534Y1040087I1114J-1927D01*
G01X496575Y1040063D01*
G03X498049I737J1277D01*
G02X500233Y1040087I1113J-1927D01*
G01X500274Y1040063D01*
G03X501748I737J1277D01*
G02X503916Y1040097I1114J-1927D01*
G01X503974Y1040063D01*
G03X505448I737J1277D01*
G02X507616Y1040097I1114J-1927D01*
G01X507674Y1040063D01*
G03X509148I737J1277D01*
G02X511374I1113J-1927D01*
G03X512848I737J1277D01*
G02X515016Y1040097I1114J-1927D01*
G01X515074Y1040063D01*
G03X516548I737J1277D01*
G02X518716Y1040097I1114J-1927D01*
G01X518774Y1040063D01*
G03X520248I737J1277D01*
G02X522434Y1040087I1114J-1927D01*
G01X522475Y1040063D01*
G03X523949I737J1277D01*
G02X526133Y1040087I1113J-1927D01*
G01X526174Y1040063D01*
G03X527648I737J1277D01*
G02X529816Y1040097I1114J-1927D01*
G01X529874Y1040063D01*
G03X531348I737J1277D01*
G02X533574I1113J-1927D01*
G03X535048I737J1277D01*
G02X537161Y1040629I2113J-3660D01*
G01X538118D01*
G01X480662Y1044544D02*
G03X482062Y1044919I0J2801D01*
G01X483625Y1045821D01*
G02X485099I737J-1277D01*
G01X485157Y1045787D01*
G03X487325Y1045821I1054J1961D01*
G02X488799I737J-1277D01*
G01X488857Y1045787D01*
G03X491025Y1045821I1054J1961D01*
G02X492499I737J-1277D01*
G01X492557Y1045787D01*
G03X494725Y1045821I1054J1961D01*
G02X496199I737J-1277D01*
G01X496240Y1045797D01*
G03X498424Y1045821I1071J1951D01*
G02X499898I737J-1277D01*
G01X499939Y1045797D01*
G03X502125Y1045821I1072J1951D01*
G02X503599I737J-1277D01*
G01X503657Y1045787D01*
G03X505825Y1045821I1054J1961D01*
G02X507299I737J-1277D01*
G01X507357Y1045787D01*
G03X509525Y1045821I1054J1961D01*
G02X510999I737J-1277D01*
G01X511057Y1045787D01*
G03X513225Y1045821I1054J1961D01*
G02X514699I737J-1277D01*
G01X514757Y1045787D01*
G03X516925Y1045821I1054J1961D01*
G02X518399I737J-1277D01*
G01X518457Y1045787D01*
G03X520625Y1045821I1054J1961D01*
G02X522099I737J-1277D01*
G01X522140Y1045797D01*
G03X524324Y1045821I1071J1951D01*
G02X525798I737J-1277D01*
G01X525839Y1045797D01*
G03X528025Y1045821I1072J1951D01*
G02X529499I737J-1277D01*
G01X529557Y1045787D01*
G03X531725Y1045821I1054J1961D01*
G02X533199I737J-1277D01*
G03X534311Y1045523I1112J1926D01*
G01X538489D01*
X539168Y1046202D01*
X542948D01*
X543279Y1046533D01*
X545180D01*
X545454Y1046259D01*
G01X473262Y1044544D02*
G02X475848Y1046471I9545J-10110D01*
G02X478016Y1046505I1114J-1927D01*
G01X478074Y1046471D01*
G03X479548I737J1277D01*
G02X481716Y1046505I1114J-1927D01*
G01X481774Y1046471D01*
G03X483248I737J1277D01*
G02X485416Y1046505I1114J-1927D01*
G01X485474Y1046471D01*
G03X486948I737J1277D01*
G02X489116Y1046505I1114J-1927D01*
G01X489174Y1046471D01*
G03X490648I737J1277D01*
G02X492816Y1046505I1114J-1927D01*
G01X492874Y1046471D01*
G03X494348I737J1277D01*
G02X496516Y1046505I1114J-1927D01*
G01X496574Y1046471D01*
G03X498048I737J1277D01*
G02X500274I1113J-1927D01*
G03X501748I737J1277D01*
G02X503916Y1046505I1114J-1927D01*
G01X503974Y1046471D01*
G03X505448I737J1277D01*
G02X507616Y1046505I1114J-1927D01*
G01X507674Y1046471D01*
G03X509148I737J1277D01*
G02X511316Y1046505I1114J-1927D01*
G01X511374Y1046471D01*
G03X512848I737J1277D01*
G02X515016Y1046505I1114J-1927D01*
G01X515074Y1046471D01*
G03X516548I737J1277D01*
G02X518716Y1046505I1114J-1927D01*
G01X518774Y1046471D01*
G03X520248I737J1277D01*
G02X522416Y1046505I1114J-1927D01*
G01X522474Y1046471D01*
G03X523948I737J1277D01*
G02X526174I1113J-1927D01*
G03X527648I737J1277D01*
G02X529816Y1046505I1114J-1927D01*
G01X529874Y1046471D01*
G03X531348I737J1277D01*
G02X533516Y1046505I1114J-1927D01*
G01X533574Y1046471D01*
G03X534311Y1046274I736J1277D01*
G01X538180D01*
X538857Y1046951D01*
X542637D01*
X542968Y1047282D01*
X545257D01*
X545454Y1047479D01*
G01X1362850Y189924D02*
X1362789Y189863D01*
Y189671D01*
X1360159Y187041D01*
X1357801D01*
X1357420Y187422D01*
X1355666D01*
X1355665Y187423D01*
X1355646D01*
G03X1353831Y186311I115J-2225D01*
G02X1352630Y185573I-1280J737D01*
G01X1352378D01*
G02X1351345Y186183I0J1180D01*
G01X1351275Y186311D01*
X1351272Y186316D01*
G03X1349347Y187423I-1921J-1114D01*
G01X1349202Y187422D01*
G03X1347419Y186311I148J-2224D01*
G02X1346367Y185588I-1282J738D01*
G01X1346137Y185818D01*
Y187049D01*
G01X1363572Y189202D02*
X1363511Y189141D01*
X1363319D01*
X1360470Y186292D01*
X1357490D01*
X1357109Y186673D01*
X1355684D01*
G03X1354481Y185935I77J-1475D01*
G02X1352670Y184824I-1929J1114D01*
G01Y184825D01*
G02X1352649Y184824I-116J2223D01*
G01X1352378D01*
G02X1350688Y185822I0J1930D01*
G01X1350624Y185940D01*
G03X1349350Y186674I-1273J-737D01*
G01X1349238Y186673D01*
G03X1348069Y185936I113J-1475D01*
G02X1346484Y184846I-1932J1112D01*
G02X1346390Y184833I-352J2202D01*
G01X1346137Y184580D01*
Y183349D01*
G01X1352551Y187048D02*
X1353620Y187663D01*
X1353715Y188015D01*
G02X1353682Y188096I2046J881D01*
G02X1355646Y191123I2079J802D01*
G01X1357721D01*
X1360324Y193726D01*
Y193918D01*
X1360385Y193979D01*
G01X1355761Y188898D02*
X1354692Y188283D01*
X1354384Y188367D01*
G02X1354481Y189635I1378J532D01*
G02X1355684Y190373I1280J-737D01*
G01X1358031D01*
X1360854Y193196D01*
X1361046D01*
X1361107Y193257D01*
G01X1306033Y943548D02*
X1306120D01*
X1306256Y943412D01*
X1313089D01*
X1313091Y943414D01*
X1313713D01*
X1320276Y936851D01*
G03X1320584Y936619I1034J1053D01*
G03X1322058I737J1277D01*
G02X1324242Y936643I1113J-1928D01*
G01X1324283Y936619D01*
G03X1325757I737J1277D01*
G02X1327925Y936653I1115J-1928D01*
G01X1327983Y936619D01*
G03X1329457I737J1277D01*
G02X1331625Y936653I1115J-1928D01*
G01X1331683Y936619D01*
G03X1333157I737J1277D01*
G02X1335343Y936643I1114J-1928D01*
G01X1335384Y936619D01*
G03X1336858I737J1277D01*
G01X1336899Y936643D01*
G02X1339083Y936619I1071J-1952D01*
G03X1340557I737J1277D01*
G02X1342725Y936653I1115J-1928D01*
G01X1342783Y936619D01*
G03X1344257I737J1277D01*
G02X1346425Y936653I1115J-1928D01*
G01X1346483Y936619D01*
G03X1347957I737J1277D01*
G02X1350125Y936653I1115J-1928D01*
G01X1350183Y936619D01*
G03X1351657I737J1277D01*
G02X1353825Y936653I1115J-1928D01*
G01X1353883Y936619D01*
G03X1355357I737J1277D01*
G02X1357525Y936653I1115J-1928D01*
G01X1357583Y936619D01*
G03X1359057I737J1277D01*
G02X1361243Y936643I1114J-1928D01*
G01X1361284Y936619D01*
G03X1362758I737J1277D01*
G01X1362799Y936643D01*
G02X1364983Y936619I1071J-1952D01*
G03X1366457I737J1277D01*
G02X1368625Y936653I1115J-1928D01*
G01X1368683Y936619D01*
G03X1370157I737J1277D01*
G02X1373496Y934747I1114J-1928D01*
G01Y934691D01*
G03X1374178Y933447I1476J0D01*
G01X1374287Y933385D01*
G03X1375655I684J1197D01*
G01X1375764Y933447D01*
G03X1376428Y934465I-794J1243D01*
G01X1376202Y934691D01*
X1374971D01*
G01X1306033Y942528D02*
X1306120D01*
X1306255Y942663D01*
X1313400D01*
X1313402Y942665D01*
X1319746Y936321D01*
G03X1320242Y935948I1574J1576D01*
G03X1322434Y935968I1078J1948D01*
G02X1323908I737J-1277D01*
G01X1323966Y935934D01*
G03X1326134Y935968I1053J1962D01*
G02X1327608I737J-1277D01*
G01X1327666Y935934D01*
G03X1329834Y935968I1053J1962D01*
G02X1331308I737J-1277D01*
G01X1331366Y935934D01*
G03X1333534Y935968I1053J1962D01*
G02X1335008I737J-1277D01*
G03X1337192Y935944I1113J1928D01*
G01X1337233Y935968D01*
G02X1338707I737J-1277D01*
G01X1338748Y935944D01*
G03X1340934Y935968I1072J1952D01*
G02X1342408I737J-1277D01*
G01X1342466Y935934D01*
G03X1344634Y935968I1053J1962D01*
G02X1346108I737J-1277D01*
G01X1346166Y935934D01*
G03X1348334Y935968I1053J1962D01*
G02X1349808I737J-1277D01*
G01X1349866Y935934D01*
G03X1352034Y935968I1053J1962D01*
G02X1353508I737J-1277D01*
G01X1353566Y935934D01*
G03X1355734Y935968I1053J1962D01*
G02X1357208I737J-1277D01*
G01X1357266Y935934D01*
G03X1359434Y935968I1053J1962D01*
G02X1360908I737J-1277D01*
G03X1363092Y935944I1113J1928D01*
G01X1363133Y935968D01*
G02X1364607I737J-1277D01*
G01X1364648Y935944D01*
G03X1366834Y935968I1072J1952D01*
G02X1368308I737J-1277D01*
G01X1368366Y935934D01*
G03X1370534Y935968I1053J1962D01*
G02X1372746Y934691I737J-1277D01*
G01X1372747D01*
G03X1373793Y932804I2225J0D01*
G01X1373916Y932734D01*
G03X1376026I1055J1848D01*
G01X1376149Y932804D01*
Y932803D01*
G03X1377170Y934350I-1178J1888D01*
G03X1377181Y934432I-2199J337D01*
G01X1377440Y934691D01*
X1378671D01*
G01X1518207Y933508D02*
X1518120D01*
X1517984Y933644D01*
X1511306D01*
X1509215Y935735D01*
G03X1508908Y935968I-1035J-1045D01*
G03X1507434I-737J-1277D01*
G02X1505208I-1113J1928D01*
G03X1503734I-737J-1277D01*
G01X1503693Y935944D01*
G02X1501507Y935968I-1072J1952D01*
G03X1500033I-737J-1277D01*
G01X1499992Y935944D01*
G02X1497808Y935968I-1071J1952D01*
G03X1496334I-737J-1277D01*
G02X1494166Y935934I-1115J1928D01*
G01X1494108Y935968D01*
G03X1492634I-737J-1277D01*
G02X1490466Y935934I-1115J1928D01*
G01X1490408Y935968D01*
G03X1488934I-737J-1277D01*
G02X1486766Y935934I-1115J1928D01*
G01X1486708Y935968D01*
G03X1485234I-737J-1277D01*
G02X1483066Y935934I-1115J1928D01*
G01X1483008Y935968D01*
G03X1481534I-737J-1277D01*
G02X1479366Y935934I-1115J1928D01*
G01X1479308Y935968D01*
G03X1477834I-737J-1277D01*
G02X1475666Y935934I-1115J1928D01*
G01X1475608Y935968D01*
G03X1474134I-737J-1277D01*
G02X1471908I-1113J1928D01*
G03X1470434I-737J-1277D01*
G02X1468266Y935934I-1115J1928D01*
G01X1468208Y935968D01*
G03X1466734I-737J-1277D01*
G02X1464566Y935934I-1115J1928D01*
G01X1464508Y935968D01*
G03X1463034I-737J-1277D01*
G02X1460866Y935934I-1115J1928D01*
G01X1460808Y935968D01*
G03X1458597Y934749I-737J-1278D01*
G01X1458596Y934748D01*
Y934691D01*
G02X1457507Y932778I-2225J0D01*
G01X1457487Y932766D01*
X1457483Y932764D01*
X1457452Y932746D01*
G03X1456746Y931488I768J-1258D01*
G01Y931401D01*
G02X1455917Y929752I-2224J85D01*
G02X1455850Y929701I-1381J1745D01*
G01X1455755Y929350D01*
X1456371Y928283D01*
G01X1518207Y934528D02*
X1518120D01*
X1517985Y934393D01*
X1511617D01*
X1509745Y936265D01*
X1509744Y936267D01*
G03X1509649Y936356I-1568J-1579D01*
G03X1509284Y936619I-1477J-1665D01*
G03X1507058I-1113J-1927D01*
G02X1505584I-737J1277D01*
G03X1503358I-1113J-1928D01*
G02X1501884I-737J1277D01*
G03X1499716Y936653I-1115J-1928D01*
G01X1499658Y936619D01*
G02X1498184I-737J1277D01*
G01X1498143Y936643D01*
G03X1495957Y936619I-1072J-1952D01*
G02X1494483I-737J1277D01*
G01X1494425Y936653D01*
G03X1492257Y936619I-1053J-1962D01*
G02X1490783I-737J1277D01*
G01X1490725Y936653D01*
G03X1488557Y936619I-1053J-1962D01*
G02X1487083I-737J1277D01*
G01X1487025Y936653D01*
G03X1484857Y936619I-1053J-1962D01*
G02X1483383I-737J1277D01*
G01X1483325Y936653D01*
G03X1481157Y936619I-1053J-1962D01*
G02X1479683I-737J1277D01*
G01X1479625Y936653D01*
G03X1477457Y936619I-1053J-1962D01*
G02X1475983I-737J1277D01*
G01X1475942Y936643D01*
G03X1473758Y936619I-1071J-1952D01*
G02X1472284I-737J1277D01*
G01X1472243Y936643D01*
G03X1470057Y936619I-1072J-1952D01*
G02X1468583I-737J1277D01*
G01X1468525Y936653D01*
G03X1466357Y936619I-1053J-1962D01*
G02X1464883I-737J1277D01*
G01X1464825Y936653D01*
G03X1462657Y936619I-1053J-1962D01*
G02X1461183I-737J1277D01*
G01X1461125Y936653D01*
G03X1457846Y934778I-1054J-1962D01*
G01Y934691D01*
G02X1457164Y933447I-1476J0D01*
G01X1457108Y933415D01*
G03X1455996Y931549I1112J-1927D01*
G01Y931454D01*
G02X1455445Y930339I-1474J35D01*
G01X1455138Y930421D01*
X1454522Y931488D01*
G01X1518207Y930895D02*
X1518120D01*
X1517985Y930760D01*
X1516502D01*
G03X1514455Y930210I1J-4088D01*
G02X1512983Y930211I-735J1278D01*
G01X1512925Y930245D01*
G03X1510757Y930211I-1053J-1962D01*
G02X1509283I-737J1277D01*
G01X1509242Y930235D01*
G03X1507058Y930211I-1071J-1952D01*
G02X1505584I-737J1277D01*
G03X1503358I-1113J-1928D01*
G02X1501884I-737J1277D01*
G01X1501843Y930235D01*
G03X1499657Y930211I-1072J-1952D01*
G02X1498183I-737J1277D01*
G03X1495957I-1113J-1928D01*
G02X1494483I-737J1277D01*
G01X1494425Y930245D01*
G03X1492257Y930211I-1053J-1962D01*
G02X1490783I-737J1277D01*
G01X1490725Y930245D01*
G03X1488557Y930211I-1053J-1962D01*
G02X1487083I-737J1277D01*
G01X1487042Y930235D01*
G03X1484858Y930211I-1071J-1952D01*
G02X1483384I-737J1277D01*
G01X1483343Y930235D01*
G03X1481157Y930211I-1072J-1952D01*
G02X1479683I-737J1277D01*
G01X1479625Y930245D01*
G03X1477457Y930211I-1053J-1962D01*
G02X1475983I-737J1277D01*
G01X1475925Y930245D01*
G03X1473757Y930211I-1053J-1962D01*
G02X1472283I-737J1277D01*
G03X1470057I-1113J-1928D01*
G02X1468583I-737J1277D01*
G01X1468525Y930245D01*
G03X1466357Y930211I-1053J-1962D01*
G02X1464883I-737J1277D01*
G01X1464825Y930245D01*
G03X1462657Y930211I-1053J-1962D01*
G02X1461183I-737J1277D01*
G01X1461142Y930235D01*
G03X1457846Y928356I-1071J-1952D01*
G01Y928283D01*
G02X1457143Y927026I-1475J0D01*
G01X1457114Y927009D01*
X1457108Y927006D01*
X1457097Y927000D01*
X1457084Y926992D01*
G03X1456021Y925420I1136J-1913D01*
G03X1456010Y925338I2199J-337D01*
G01X1455751Y925079D01*
X1454520D01*
G01X1518207Y929875D02*
X1518120D01*
X1517984Y930011D01*
X1516503D01*
G03X1514831Y929562I0J-3339D01*
G01X1514833Y929559D01*
G02X1512666Y929526I-1113J1929D01*
G01X1512608Y929560D01*
G03X1511134I-737J-1277D01*
G02X1508966Y929526I-1115J1928D01*
G01X1508908Y929560D01*
G03X1507434I-737J-1277D01*
G02X1505208I-1113J1928D01*
G03X1503734I-737J-1277D01*
G02X1501508I-1113J1928D01*
G03X1500034I-737J-1277D01*
G02X1497848Y929536I-1114J1928D01*
G01X1497807Y929560D01*
G03X1496333I-737J-1277D01*
G02X1494149Y929536I-1113J1928D01*
G01X1494108Y929560D01*
G03X1492634I-737J-1277D01*
G02X1490466Y929526I-1115J1928D01*
G01X1490408Y929560D01*
G03X1488934I-737J-1277D01*
G02X1486766Y929526I-1115J1928D01*
G01X1486708Y929560D01*
G03X1485234I-737J-1277D01*
G02X1483008I-1113J1928D01*
G03X1481534I-737J-1277D01*
G02X1479366Y929526I-1115J1928D01*
G01X1479308Y929560D01*
G03X1477834I-737J-1277D01*
G02X1475666Y929526I-1115J1928D01*
G01X1475608Y929560D01*
G03X1474134I-737J-1277D01*
G02X1471948Y929536I-1114J1928D01*
G01X1471907Y929560D01*
G03X1470433I-737J-1277D01*
G02X1468249Y929536I-1113J1928D01*
G01X1468208Y929560D01*
G03X1466734I-737J-1277D01*
G02X1464566Y929526I-1115J1928D01*
G01X1464508Y929560D01*
G03X1463034I-737J-1277D01*
G02X1460866Y929526I-1115J1928D01*
G01X1460808Y929560D01*
G03X1458596Y928283I-737J-1277D01*
G02X1457507Y926370I-2225J0D01*
G01X1457486Y926358D01*
X1457448Y926336D01*
G03X1456763Y925305I773J-1256D01*
G01X1456989Y925079D01*
X1458220D01*
G01X1306033Y938249D02*
X1306120D01*
X1306256Y938113D01*
X1314884D01*
X1314885Y938114D01*
X1316108Y936892D01*
G02X1317996Y934692I-338J-2200D01*
G01Y934658D01*
G03X1318733Y933415I1474J34D01*
G01X1318736Y933413D01*
X1318757Y933401D01*
G02X1319846Y931488I-1136J-1913D01*
G03X1320549Y930231I1475J0D01*
G01X1320932Y930012D01*
X1321321D01*
G03X1322059Y930210I0J1476D01*
G01X1322058Y930211D01*
G02X1324284I1113J-1928D01*
G03X1325758I737J1277D01*
G02X1327942Y930235I1113J-1928D01*
G01X1327983Y930211D01*
G03X1329457I737J1277D01*
G02X1331625Y930245I1115J-1928D01*
G01X1331683Y930211D01*
G03X1333157I737J1277D01*
G02X1335383I1113J-1928D01*
G03X1336857I737J1277D01*
G02X1339025Y930245I1115J-1928D01*
G01X1339083Y930211D01*
G03X1340557I737J1277D01*
G02X1342725Y930245I1115J-1928D01*
G01X1342783Y930211D01*
G03X1344257I737J1277D01*
G02X1346443Y930235I1114J-1928D01*
G01X1346484Y930211D01*
G03X1347958I737J1277D01*
G02X1350142Y930235I1113J-1928D01*
G01X1350183Y930211D01*
G03X1351657I737J1277D01*
G02X1353825Y930245I1115J-1928D01*
G01X1353883Y930211D01*
G03X1355357I737J1277D01*
G02X1357525Y930245I1115J-1928D01*
G01X1357583Y930211D01*
G03X1359057I737J1277D01*
G02X1361283I1113J-1928D01*
G03X1362757I737J1277D01*
G02X1364925Y930245I1115J-1928D01*
G01X1364983Y930211D01*
G03X1366457I737J1277D01*
G02X1368625Y930245I1115J-1928D01*
G01X1368683Y930211D01*
G03X1370157I737J1277D01*
G02X1372343Y930235I1114J-1928D01*
G01X1372384Y930211D01*
G03X1373858I737J1277D01*
G02X1376042Y930235I1113J-1928D01*
G01X1376083Y930211D01*
G03X1377353Y930114I736J1277D01*
G01X1377436Y930421D01*
X1376820Y931488D01*
G01X1306033Y937229D02*
X1306120D01*
X1306255Y937364D01*
X1314574D01*
X1315771Y936167D01*
G02X1317245Y934726I0J-1475D01*
G01Y934692D01*
G03X1318334Y932779I2225J0D01*
G01X1318358Y932765D01*
X1318364Y932762D01*
X1318393Y932745D01*
G02X1319096Y931488I-772J-1257D01*
G01Y931415D01*
G03X1320208Y929560I2225J73D01*
G01X1320724Y929262D01*
X1321321D01*
G03X1322434Y929560I0J2226D01*
G02X1323908I737J-1277D01*
G03X1326134I1113J1928D01*
G02X1327608I737J-1277D01*
G01X1327666Y929526D01*
G03X1329834Y929560I1053J1962D01*
G02X1331308I737J-1277D01*
G01X1331349Y929536D01*
G03X1333533Y929560I1071J1952D01*
G02X1335007I737J-1277D01*
G01X1335048Y929536D01*
G03X1337234Y929560I1072J1952D01*
G02X1338708I737J-1277D01*
G01X1338766Y929526D01*
G03X1340934Y929560I1053J1962D01*
G02X1342408I737J-1277D01*
G01X1342466Y929526D01*
G03X1344634Y929560I1053J1962D01*
G02X1346108I737J-1277D01*
G03X1348334I1113J1928D01*
G02X1349808I737J-1277D01*
G01X1349866Y929526D01*
G03X1352034Y929560I1053J1962D01*
G02X1353508I737J-1277D01*
G01X1353566Y929526D01*
G03X1355734Y929560I1053J1962D01*
G02X1357208I737J-1277D01*
G01X1357249Y929536D01*
G03X1359433Y929560I1071J1952D01*
G02X1360907I737J-1277D01*
G01X1360948Y929536D01*
G03X1363134Y929560I1072J1952D01*
G02X1364608I737J-1277D01*
G01X1364666Y929526D01*
G03X1366834Y929560I1053J1962D01*
G02X1368308I737J-1277D01*
G01X1368366Y929526D01*
G03X1370534Y929560I1053J1962D01*
G02X1372008I737J-1277D01*
G03X1374234I1113J1928D01*
G02X1375708I737J-1277D01*
G01X1375766Y929526D01*
G03X1377625Y929412I1053J1962D01*
G03X1377704Y929444I-796J2080D01*
G01X1378055Y929350D01*
X1378671Y928283D01*
G01X1430471Y921875D02*
X1433318Y920664D01*
X1433433Y920597D01*
X1433434Y920598D01*
G03X1434908I737J1277D01*
G01X1434966Y920632D01*
G02X1437134Y920598I1053J-1962D01*
G03X1438608I737J1277D01*
G01X1438666Y920632D01*
G02X1440834Y920598I1053J-1962D01*
G03X1442308I737J1277D01*
G01X1442366Y920632D01*
G02X1444534Y920598I1053J-1962D01*
G03X1446007I737J1276D01*
G01X1446008D01*
X1446066Y920632D01*
G02X1448234Y920598I1053J-1962D01*
G03X1449708I737J1277D01*
G01X1449749Y920622D01*
G02X1451933Y920598I1071J-1952D01*
G03X1453407I737J1277D01*
G02X1455593Y920622I1114J-1928D01*
G01X1455634Y920598D01*
G03X1457108I737J1277D01*
G01X1457149Y920622D01*
G02X1459333Y920598I1071J-1952D01*
G03X1460807I737J1277D01*
G01X1460848Y920622D01*
G02X1463034Y920598I1072J-1952D01*
G03X1464508I737J1277D01*
G01X1464566Y920632D01*
G02X1466734Y920598I1053J-1962D01*
G03X1468208I737J1277D01*
G01X1468266Y920632D01*
G02X1470434Y920598I1053J-1962D01*
G03X1471908I737J1277D01*
G02X1474134I1113J-1928D01*
G03X1475608I737J1277D01*
G01X1475666Y920632D01*
G02X1477834Y920598I1053J-1962D01*
G03X1479308I737J1277D01*
G01X1479366Y920632D01*
G02X1481534Y920598I1053J-1962D01*
G03X1483008I737J1277D01*
G01X1483049Y920622D01*
G02X1485233Y920598I1071J-1952D01*
G03X1486707I737J1277D01*
G01X1486748Y920622D01*
G02X1488934Y920598I1072J-1952D01*
G01X1489107Y920498D01*
G03X1490507I700J1213D01*
G01X1490508D01*
X1490870Y920630D01*
G02X1492567Y920622I836J-2592D01*
G02X1492679Y920572I-243J-696D01*
G03X1494108Y920598I691J1303D01*
G01X1494166Y920632D01*
G02X1496334Y920598I1053J-1962D01*
G03X1497808I737J1277D01*
G02X1500034I1113J-1928D01*
G03X1501508I737J1277D01*
G02X1503734I1113J-1928D01*
G03X1505208I737J1277D01*
G02X1507434I1113J-1928D01*
G03X1508908I737J1277D01*
G02X1511134I1113J-1928D01*
G01X1511206Y920557D01*
G03X1512611Y920597I666J1318D01*
G01X1514741Y921964D01*
G01X1306617Y185199D02*
X1302575D01*
X1300808Y186966D01*
X1299890D01*
X1298119Y185195D01*
X1295197D01*
X1294824Y184822D01*
X1293034D01*
X1291928Y183716D01*
X1291264D01*
G01X1303407Y183349D02*
X1299665D01*
X1297968Y181652D01*
X1291865D01*
X1290787Y180574D01*
X1290014D01*
G01X1378671Y909057D02*
X1378055Y907990D01*
X1377704Y907896D01*
G03X1375766Y907814I-884J-2043D01*
G01X1375708Y907780D01*
G02X1374234I-737J1277D01*
G03X1372066Y907814I-1114J-1927D01*
G01X1372008Y907780D01*
G02X1370534I-737J1277D01*
G03X1368366Y907814I-1114J-1927D01*
G01X1368308Y907780D01*
G02X1366834I-737J1277D01*
G03X1364666Y907814I-1114J-1927D01*
G01X1364608Y907780D01*
G02X1363134I-737J1277D01*
G03X1360948Y907804I-1114J-1927D01*
G01X1360907Y907780D01*
G02X1359433I-737J1277D01*
G01X1359392Y907804D01*
G03X1357208Y907780I-1071J-1951D01*
G02X1355734I-737J1277D01*
G03X1353566Y907814I-1114J-1927D01*
G01X1353508Y907780D01*
G02X1352034I-737J1277D01*
G03X1349866Y907814I-1114J-1927D01*
G01X1349808Y907780D01*
G02X1348334I-737J1277D01*
G03X1346166Y907814I-1114J-1927D01*
G01X1346108Y907780D01*
G02X1344634I-737J1277D01*
G03X1342466Y907814I-1114J-1927D01*
G01X1342408Y907780D01*
G02X1340934I-737J1277D01*
G03X1338766Y907814I-1114J-1927D01*
G01X1338708Y907780D01*
G02X1337234I-737J1277D01*
G03X1335048Y907804I-1114J-1927D01*
G01X1335007Y907780D01*
G02X1333533I-737J1277D01*
G01X1333492Y907804D01*
G03X1331308Y907780I-1071J-1951D01*
G02X1329834I-737J1277D01*
G03X1327666Y907814I-1114J-1927D01*
G01X1327608Y907780D01*
G02X1326134I-737J1277D01*
G03X1323966Y907814I-1114J-1927D01*
G01X1323908Y907780D01*
G02X1323171Y907581I-740J1276D01*
G01X1321523D01*
X1320140Y908964D01*
X1313867D01*
G01X1399020Y918670D02*
X1396472Y919761D01*
G02X1396057Y919947I698J2114D01*
G03X1394583I-737J-1277D01*
G01X1394525Y919913D01*
G02X1392357Y919947I-1053J1962D01*
G03X1390883I-737J-1277D01*
G01X1390825Y919913D01*
G02X1388657Y919947I-1053J1962D01*
G03X1387183I-737J-1277D01*
G01X1387125Y919913D01*
G02X1384957Y919947I-1053J1962D01*
G03X1383483I-737J-1277D01*
G01X1383425Y919913D01*
G02X1381257Y919947I-1053J1962D01*
G03X1379783I-737J-1277D01*
G01X1379725Y919913D01*
G02X1377557Y919947I-1053J1962D01*
G03X1376083I-737J-1277D01*
G02X1373857I-1113J1928D01*
G03X1372383I-737J-1277D01*
G01X1372325Y919913D01*
G02X1370157Y919947I-1053J1962D01*
G03X1368683I-737J-1277D01*
G01X1368625Y919913D01*
G02X1366457Y919947I-1053J1962D01*
G03X1364983I-737J-1277D01*
G01X1364942Y919923D01*
G02X1362758Y919947I-1071J1952D01*
G03X1361284I-737J-1277D01*
G01X1361243Y919923D01*
G02X1359057Y919947I-1072J1952D01*
G03X1357583I-737J-1277D01*
G01X1357525Y919913D01*
G02X1355357Y919947I-1053J1962D01*
G03X1353883I-737J-1277D01*
G01X1353825Y919913D01*
G02X1351657Y919947I-1053J1962D01*
G03X1350183I-737J-1277D01*
G02X1347957I-1113J1928D01*
G03X1346483I-737J-1277D01*
G01X1346425Y919913D01*
G02X1344257Y919947I-1053J1962D01*
G03X1342783I-737J-1277D01*
G01X1342725Y919913D01*
G02X1340557Y919947I-1053J1962D01*
G03X1339083I-737J-1277D01*
G01X1339042Y919923D01*
G02X1336858Y919947I-1071J1952D01*
G03X1335384I-737J-1277D01*
G01X1335343Y919923D01*
G02X1333157Y919947I-1072J1952D01*
G03X1331683I-737J-1277D01*
G01X1331625Y919913D01*
G02X1329457Y919947I-1053J1962D01*
G03X1327983I-737J-1277D01*
G01X1327925Y919913D01*
G02X1325757Y919947I-1053J1962D01*
G03X1324283I-737J-1277D01*
G01X1324242Y919923D01*
G02X1322058Y919947I-1071J1952D01*
G03X1320574Y920347I-1484J-2551D01*
G01X1313005D01*
X1312117Y921235D01*
G01X1391550Y925219D02*
X1378768D01*
X1377864Y926123D01*
G03X1377557Y926356I-1038J-1049D01*
G03X1376083I-737J-1277D01*
G01X1376025Y926322D01*
G02X1373857Y926356I-1054J1961D01*
G03X1372383I-737J-1277D01*
G01X1372325Y926322D01*
G02X1370157Y926356I-1054J1961D01*
G03X1368683I-737J-1277D01*
G01X1368625Y926322D01*
G02X1366457Y926356I-1054J1961D01*
G03X1364983I-737J-1277D01*
G01X1364925Y926322D01*
G02X1362757Y926356I-1054J1961D01*
G03X1361283I-737J-1277D01*
G02X1359099Y926332I-1113J1927D01*
G01X1359058Y926356D01*
G03X1357584I-737J-1277D01*
G01X1357543Y926332D01*
G02X1355357Y926356I-1072J1951D01*
G03X1353883I-737J-1277D01*
G01X1353825Y926322D01*
G02X1351657Y926356I-1054J1961D01*
G03X1350183I-737J-1277D01*
G01X1350125Y926322D01*
G02X1347957Y926356I-1054J1961D01*
G03X1346483I-737J-1277D01*
G01X1346425Y926322D01*
G02X1344257Y926356I-1054J1961D01*
G03X1342783I-737J-1277D01*
G01X1342725Y926322D01*
G02X1340557Y926356I-1054J1961D01*
G03X1339083I-737J-1277D01*
G01X1339025Y926322D01*
G02X1336857Y926356I-1054J1961D01*
G03X1335383I-737J-1277D01*
G02X1333199Y926332I-1113J1927D01*
G01X1333158Y926356D01*
G03X1331684I-737J-1277D01*
G01X1331643Y926332D01*
G02X1329457Y926356I-1072J1951D01*
G03X1327983I-737J-1277D01*
G01X1327925Y926322D01*
G02X1325757Y926356I-1054J1961D01*
G03X1323977Y926122I-738J-1277D01*
G01X1323569Y925714D01*
X1321527D01*
G01X1384653Y1066974D02*
X1385269Y1065907D01*
X1385186Y1065600D01*
G02X1383916Y1065697I-534J1374D01*
G01X1383858Y1065731D01*
G03X1381690Y1065697I-1054J-1961D01*
G02X1380216I-737J1277D01*
G01X1380175Y1065721D01*
G03X1377991Y1065697I-1071J-1951D01*
G02X1376517I-737J1277D01*
G03X1374291I-1113J-1927D01*
G02X1372817I-737J1277D01*
G01X1372776Y1065721D01*
G03X1370590Y1065697I-1072J-1951D01*
G02X1369116I-737J1277D01*
G01X1369058Y1065731D01*
G03X1366890Y1065697I-1054J-1961D01*
G02X1365416I-737J1277D01*
G03X1363190I-1113J-1927D01*
G02X1361716I-737J1277D01*
G01X1361658Y1065731D01*
G03X1359490Y1065697I-1054J-1961D01*
G02X1358016I-737J1277D01*
G01X1357958Y1065731D01*
G03X1355790Y1065697I-1054J-1961D01*
G02X1354316I-737J1277D01*
G01X1354258Y1065731D01*
G03X1352090Y1065697I-1054J-1961D01*
G02X1350616I-737J1277D01*
G01X1350575Y1065721D01*
G03X1348391Y1065697I-1071J-1951D01*
G02X1346917I-737J1277D01*
G01X1346876Y1065721D01*
G03X1344690Y1065697I-1072J-1951D01*
G02X1343216I-737J1277D01*
G01X1343158Y1065731D01*
G03X1340990Y1065697I-1054J-1961D01*
G02X1339516I-737J1277D01*
G03X1337290I-1113J-1927D01*
G02X1335816I-737J1277D01*
G01X1335758Y1065731D01*
G03X1333590Y1065697I-1054J-1961D01*
G02X1332116I-737J1277D01*
G03X1329890I-1113J-1927D01*
G02X1328416I-737J1277D01*
G03X1326190I-1113J-1927D01*
G02X1324716I-737J1277D01*
G03X1322490I-1113J-1927D01*
G02X1321016I-737J1277D01*
G03X1318790I-1113J-1927D01*
G02X1318052Y1065497I-742J1276D01*
G01X1317147D01*
X1316313Y1066331D01*
X1314312D01*
G01X1397604Y1076587D02*
X1396988Y1077654D01*
X1396637Y1077748D01*
G02X1394699Y1077830I-884J2043D01*
G01X1394641Y1077864D01*
G03X1393167I-737J-1277D01*
G02X1390999Y1077830I-1114J1927D01*
G01X1390941Y1077864D01*
G03X1389467I-737J-1277D01*
G02X1387299Y1077830I-1114J1927D01*
G01X1387241Y1077864D01*
G03X1385767I-737J-1277D01*
G02X1383581Y1077840I-1114J1927D01*
G01X1383540Y1077864D01*
G02X1382428Y1079752I1113J1927D01*
G01Y1079791D01*
G03X1381725Y1081048I-1475J0D01*
G01X1381690Y1081068D01*
G03X1380216I-737J-1277D01*
G01X1380158Y1081034D01*
G02X1377990Y1081068I-1054J1961D01*
G03X1376516I-737J-1277D01*
G01X1376458Y1081034D01*
G02X1374290Y1081068I-1054J1961D01*
G03X1372816I-737J-1277D01*
G01X1372758Y1081034D01*
G02X1370590Y1081068I-1054J1961D01*
G03X1369116I-737J-1277D01*
G01X1369058Y1081034D01*
G02X1366890Y1081068I-1054J1961D01*
G03X1365416I-737J-1277D01*
G02X1363190I-1113J1927D01*
G03X1361716I-737J-1277D01*
G01X1361658Y1081034D01*
G02X1359490Y1081068I-1054J1961D01*
G03X1358016I-737J-1277D01*
G01X1357958Y1081034D01*
G02X1355790Y1081068I-1054J1961D01*
G03X1354316I-737J-1277D01*
G01X1354258Y1081034D01*
G02X1352090Y1081068I-1054J1961D01*
G03X1350616I-737J-1277D01*
G01X1350558Y1081034D01*
G02X1348390Y1081068I-1054J1961D01*
G03X1346916I-737J-1277D01*
G01X1346858Y1081034D01*
G02X1344690Y1081068I-1054J1961D01*
G03X1343216I-737J-1277D01*
G01X1343158Y1081034D01*
G02X1340990Y1081068I-1054J1961D01*
G03X1339516I-737J-1277D01*
G02X1337332Y1081044I-1113J1927D01*
G01X1337291Y1081068D01*
G03X1335817I-737J-1277D01*
G01X1335776Y1081044D01*
G02X1333590Y1081068I-1072J1951D01*
G03X1332116I-737J-1277D01*
G02X1329890I-1113J1927D01*
G03X1328416I-737J-1277D01*
G02X1326190I-1113J1927D01*
G03X1324716I-737J-1277D01*
G02X1322490I-1113J1927D01*
G03X1321016I-737J-1277D01*
G02X1318848Y1081034I-1114J1927D01*
G01X1318790Y1081068D01*
G03X1317316I-737J-1277D01*
G02X1313977Y1082934I-1114J1927D01*
G01Y1084927D01*
X1313190Y1085714D01*
G01X1300212Y166699D02*
X1299100D01*
X1298724Y166323D01*
X1297666D01*
X1297008Y166324D01*
G03X1295750Y165622I-2J-1475D01*
G01X1295730Y165586D01*
G02X1293875Y164474I-1928J1113D01*
G01X1292576D01*
X1291224Y163122D01*
G01X1309817Y175949D02*
X1306056D01*
X1304446Y174339D01*
X1302504D01*
X1301856Y173691D01*
Y165925D01*
X1300893Y164962D01*
X1299493D01*
X1297493Y162962D01*
X1296193D01*
X1294756Y161525D01*
X1292486D01*
X1291544Y160583D01*
G01X1290624Y175227D02*
X1292055D01*
X1292693Y175865D01*
X1294163D01*
G01X1296999Y187049D02*
X1295886D01*
X1294409Y185572D01*
X1291316D01*
X1291291Y185597D01*
G01X1378671Y896240D02*
X1378055Y897307D01*
X1377704Y897401D01*
G02X1375766Y897483I-884J2044D01*
G01X1375708Y897517D01*
G03X1374234I-737J-1277D01*
G02X1372066Y897483I-1115J1928D01*
G01X1372008Y897517D01*
G03X1370534I-737J-1277D01*
G02X1368348Y897493I-1114J1928D01*
G01X1368307Y897517D01*
G03X1366833I-737J-1277D01*
G02X1364649Y897493I-1113J1928D01*
G01X1364608Y897517D01*
G03X1363134I-737J-1277D01*
G02X1360908I-1113J1928D01*
G03X1359434I-737J-1277D01*
G02X1357266Y897483I-1115J1928D01*
G01X1357208Y897517D01*
G03X1355734I-737J-1277D01*
G02X1353566Y897483I-1115J1928D01*
G01X1353508Y897517D01*
G03X1352034I-737J-1277D01*
G02X1349866Y897483I-1115J1928D01*
G01X1349808Y897517D01*
G03X1348334I-737J-1277D01*
G02X1346166Y897483I-1115J1928D01*
G01X1346108Y897517D01*
G03X1344634I-737J-1277D01*
G02X1342466Y897483I-1115J1928D01*
G01X1342408Y897517D01*
G03X1340934I-737J-1277D01*
G02X1338748Y897493I-1114J1928D01*
G01X1338707Y897517D01*
G03X1337233I-737J-1277D01*
G01X1337192Y897493D01*
G02X1335008Y897517I-1071J1952D01*
G03X1333534I-737J-1277D01*
G02X1331366Y897483I-1115J1928D01*
G01X1331308Y897517D01*
G03X1329834I-737J-1277D01*
G02X1327666Y897483I-1115J1928D01*
G01X1327608Y897517D01*
G03X1326134I-737J-1277D01*
G02X1323966Y897483I-1115J1928D01*
G01X1323908Y897517D01*
G03X1322434I-737J-1277D01*
G01X1322393Y897493D01*
G02X1320207Y897517I-1072J1952D01*
G03X1318735Y897915I-1472J-2524D01*
G01X1316497D01*
G01X1374971Y896240D02*
X1375587Y895173D01*
X1375504Y894866D01*
G02X1374234Y894963I-534J1374D01*
G03X1372066Y894997I-1114J-1927D01*
G01X1372008Y894963D01*
G02X1370534I-737J1277D01*
G03X1368348Y894987I-1114J-1927D01*
G01X1368307Y894963D01*
G02X1366833I-737J1277D01*
G01X1366792Y894987D01*
G03X1364608Y894963I-1071J-1951D01*
G02X1363134I-737J1277D01*
G03X1360966Y894997I-1114J-1927D01*
G01X1360908Y894963D01*
G02X1359434I-737J1277D01*
G03X1357266Y894997I-1114J-1927D01*
G01X1357208Y894963D01*
G02X1355734I-737J1277D01*
G03X1353508I-1113J-1927D01*
G02X1352034I-737J1277D01*
G03X1349866Y894997I-1114J-1927D01*
G01X1349808Y894963D01*
G02X1348334I-737J1277D01*
G03X1346166Y894997I-1114J-1927D01*
G01X1346108Y894963D01*
G02X1344634I-737J1277D01*
G03X1342466Y894997I-1114J-1927D01*
G01X1342408Y894963D01*
G02X1340934I-737J1277D01*
G03X1338748Y894987I-1114J-1927D01*
G01X1338707Y894963D01*
G02X1337233I-737J1277D01*
G01X1337192Y894987D01*
G03X1335008Y894963I-1071J-1951D01*
G02X1333534I-737J1277D01*
G03X1331366Y894997I-1114J-1927D01*
G01X1331308Y894963D01*
G02X1329834I-737J1277D01*
G03X1327666Y894997I-1114J-1927D01*
G01X1327608Y894963D01*
G02X1326134I-737J1277D01*
G03X1323966Y894997I-1114J-1927D01*
G01X1323908Y894963D01*
G02X1322434I-737J1277D01*
G01X1322393Y894987D01*
G03X1320207Y894963I-1072J-1951D01*
G02X1318733I-737J1277D01*
G03X1316549Y894987I-1113J-1927D01*
G01X1316508Y894963D01*
G02X1315034I-737J1277D01*
G01X1314993Y894987D01*
G03X1312807Y894963I-1072J-1951D01*
G02X1311333I-737J1277D01*
G02X1311027Y895197I735J1278D01*
G01X1310765Y895459D01*
X1310157D01*
G01X1382371Y909057D02*
X1382077Y908850D01*
X1380420Y907682D01*
G02X1379807Y907144I-1749J1375D01*
G01X1379783Y907130D01*
X1379748Y907110D01*
G03X1379045Y905853I772J-1257D01*
G01Y905792D01*
G02X1377934Y903926I-2225J61D01*
G02X1375748Y903902I-1114J1927D01*
G01X1375707Y903926D01*
G03X1374233I-737J-1277D01*
G02X1372049Y903902I-1113J1927D01*
G01X1372008Y903926D01*
G03X1370534I-737J-1277D01*
G02X1368366Y903892I-1114J1927D01*
G01X1368308Y903926D01*
G03X1366834I-737J-1277D01*
G02X1364666Y903892I-1114J1927D01*
G01X1364608Y903926D01*
G03X1363134I-737J-1277D01*
G02X1360966Y903892I-1114J1927D01*
G01X1360908Y903926D01*
G03X1359434I-737J-1277D01*
G02X1357208I-1113J1927D01*
G03X1355734I-737J-1277D01*
G02X1353566Y903892I-1114J1927D01*
G01X1353508Y903926D01*
G03X1352034I-737J-1277D01*
G02X1349848Y903902I-1114J1927D01*
G01X1349807Y903926D01*
G03X1348333I-737J-1277D01*
G02X1346149Y903902I-1113J1927D01*
G01X1346108Y903926D01*
G03X1344634I-737J-1277D01*
G02X1342466Y903892I-1114J1927D01*
G01X1342408Y903926D01*
G03X1340934I-737J-1277D01*
G02X1338766Y903892I-1114J1927D01*
G01X1338708Y903926D01*
G03X1337234I-737J-1277D01*
G02X1335066Y903892I-1114J1927D01*
G01X1335008Y903926D01*
G03X1333534I-737J-1277D01*
G02X1331308I-1113J1927D01*
G03X1329834I-737J-1277D01*
G02X1327666Y903892I-1114J1927D01*
G01X1327608Y903926D01*
G03X1326134I-737J-1277D01*
G02X1323966Y903892I-1114J1927D01*
G01X1323908Y903926D01*
G03X1323171Y904125I-740J-1276D01*
G01X1322267D01*
X1321261Y903119D01*
X1315577D01*
G01X1389771Y909057D02*
G02X1388309Y909454I0J2890D01*
G01X1386808Y910334D01*
G03X1385334I-737J-1277D01*
G01X1385299Y910314D01*
G03X1384596Y909057I772J-1257D01*
G02X1383507Y907144I-2225J0D01*
G01X1383483Y907130D01*
X1383448Y907110D01*
G03X1382745Y905853I772J-1257D01*
G01Y905792D01*
G02X1381634Y903926I-2225J61D01*
G01X1381599Y903906D01*
G03X1380896Y902649I772J-1257D01*
G02X1379807Y900736I-2225J0D01*
G01X1379783Y900722D01*
X1379725Y900688D01*
G02X1377557Y900722I-1054J1961D01*
G03X1376083I-737J-1277D01*
G02X1373857I-1113J1927D01*
G03X1372383I-737J-1277D01*
G01X1372325Y900688D01*
G02X1370157Y900722I-1054J1961D01*
G03X1368683I-737J-1277D01*
G01X1368625Y900688D01*
G02X1366457Y900722I-1054J1961D01*
G03X1364983I-737J-1277D01*
G01X1364942Y900698D01*
G02X1362758Y900722I-1071J1951D01*
G03X1361284I-737J-1277D01*
G01X1361243Y900698D01*
G02X1359057Y900722I-1072J1951D01*
G03X1357583I-737J-1277D01*
G01X1357525Y900688D01*
G02X1355357Y900722I-1054J1961D01*
G03X1353883I-737J-1277D01*
G01X1353825Y900688D01*
G02X1351657Y900722I-1054J1961D01*
G03X1350183I-737J-1277D01*
G02X1347957I-1113J1927D01*
G03X1346483I-737J-1277D01*
G01X1346425Y900688D01*
G02X1344257Y900722I-1054J1961D01*
G03X1342783I-737J-1277D01*
G01X1342725Y900688D01*
G02X1340557Y900722I-1054J1961D01*
G03X1339083I-737J-1277D01*
G01X1339042Y900698D01*
G02X1336858Y900722I-1071J1951D01*
G03X1335384I-737J-1277D01*
G01X1335343Y900698D01*
G02X1333157Y900722I-1072J1951D01*
G03X1331683I-737J-1277D01*
G01X1331625Y900688D01*
G02X1329457Y900722I-1054J1961D01*
G03X1327983I-737J-1277D01*
G01X1327925Y900688D01*
G02X1325757Y900722I-1054J1961D01*
G03X1324283I-737J-1277D01*
G01X1324242Y900698D01*
G02X1322058Y900722I-1071J1951D01*
G03X1321321Y900919I-736J-1277D01*
G01X1318829D01*
X1317989Y900079D01*
X1315857D01*
G01X1384220Y912262D02*
X1383604Y911195D01*
X1383254Y911102D01*
G03X1381257Y910985I-882J-2045D01*
G03X1380146Y909144I1114J-1928D01*
G01Y909057D01*
G02X1379443Y907800I-1475J0D01*
G01X1379408Y907780D01*
X1379384Y907766D01*
G03X1378295Y905853I1136J-1913D01*
G02X1377592Y904596I-1475J0D01*
G01X1377557Y904576D01*
G02X1376083I-737J1277D01*
G03X1373857I-1113J-1927D01*
G02X1372383I-737J1277D01*
G01X1372325Y904610D01*
G03X1370157Y904576I-1054J-1961D01*
G02X1368683I-737J1277D01*
G01X1368625Y904610D01*
G03X1366457Y904576I-1054J-1961D01*
G02X1364983I-737J1277D01*
G01X1364925Y904610D01*
G03X1362757Y904576I-1054J-1961D01*
G02X1361283I-737J1277D01*
G01X1361242Y904600D01*
G03X1359058Y904576I-1071J-1951D01*
G02X1357584I-737J1277D01*
G01X1357543Y904600D01*
G03X1355357Y904576I-1072J-1951D01*
G02X1353883I-737J1277D01*
G01X1353825Y904610D01*
G03X1351657Y904576I-1054J-1961D01*
G02X1350183I-737J1277D01*
G03X1347957I-1113J-1927D01*
G02X1346483I-737J1277D01*
G01X1346425Y904610D01*
G03X1344257Y904576I-1054J-1961D01*
G02X1342783I-737J1277D01*
G01X1342725Y904610D01*
G03X1340557Y904576I-1054J-1961D01*
G02X1339083I-737J1277D01*
G01X1339025Y904610D01*
G03X1336857Y904576I-1054J-1961D01*
G02X1335383I-737J1277D01*
G01X1335342Y904600D01*
G03X1333158Y904576I-1071J-1951D01*
G02X1331684I-737J1277D01*
G01X1331643Y904600D01*
G03X1329457Y904576I-1072J-1951D01*
G02X1327983I-737J1277D01*
G01X1327925Y904610D01*
G03X1325757Y904576I-1054J-1961D01*
G02X1324283I-737J1277D01*
G03X1323171Y904874I-1112J-1926D01*
G01X1321616D01*
X1320768Y904026D01*
X1316151D01*
X1315252Y904925D01*
G01X1376820Y905853D02*
X1374600Y906862D01*
G02X1373857Y907130I372J2195D01*
G03X1372383I-737J-1277D01*
G01X1372325Y907096D01*
G02X1370157Y907130I-1054J1961D01*
G03X1368683I-737J-1277D01*
G01X1368625Y907096D01*
G02X1366457Y907130I-1054J1961D01*
G03X1364983I-737J-1277D01*
G01X1364925Y907096D01*
G02X1362757Y907130I-1054J1961D01*
G03X1361283I-737J-1277D01*
G02X1359099Y907106I-1113J1927D01*
G01X1359058Y907130D01*
G03X1357584I-737J-1277D01*
G01X1357543Y907106D01*
G02X1355357Y907130I-1072J1951D01*
G03X1353883I-737J-1277D01*
G01X1353825Y907096D01*
G02X1351657Y907130I-1054J1961D01*
G03X1350183I-737J-1277D01*
G01X1350125Y907096D01*
G02X1347957Y907130I-1054J1961D01*
G03X1346483I-737J-1277D01*
G01X1346425Y907096D01*
G02X1344257Y907130I-1054J1961D01*
G03X1342783I-737J-1277D01*
G01X1342725Y907096D01*
G02X1340557Y907130I-1054J1961D01*
G03X1339083I-737J-1277D01*
G01X1339025Y907096D01*
G02X1336857Y907130I-1054J1961D01*
G03X1335383I-737J-1277D01*
G02X1333199Y907106I-1113J1927D01*
G01X1333158Y907130D01*
G03X1331684I-737J-1277D01*
G01X1331643Y907106D01*
G02X1329457Y907130I-1072J1951D01*
G03X1327983I-737J-1277D01*
G01X1327925Y907096D01*
G02X1325757Y907130I-1054J1961D01*
G03X1324283I-737J-1277D01*
G02X1323315Y906836I-1114J1926D01*
G02X1323172Y906832I-134J2221D01*
G01X1319946D01*
G01X1378671Y915466D02*
X1375140Y914017D01*
G02X1374268Y914208I-136J1467D01*
G01Y914209D01*
G03X1372041Y914208I-1113J-1928D01*
G01X1372008Y914189D01*
G02X1370534I-737J1277D01*
G03X1368366Y914223I-1114J-1927D01*
G01X1368308Y914189D01*
G02X1366834I-737J1277D01*
G03X1364648Y914213I-1114J-1927D01*
G01X1364607Y914189D01*
G02X1363133I-737J1277D01*
G03X1360949Y914213I-1113J-1927D01*
G01X1360908Y914189D01*
G02X1359434I-737J1277D01*
G03X1357266Y914223I-1114J-1927D01*
G01X1357208Y914189D01*
G02X1355734I-737J1277D01*
G03X1353566Y914223I-1114J-1927D01*
G01X1353508Y914189D01*
G02X1352034I-737J1277D01*
G03X1349866Y914223I-1114J-1927D01*
G01X1349808Y914189D01*
G02X1348334I-737J1277D01*
G03X1346108I-1113J-1927D01*
G02X1344634I-737J1277D01*
G03X1342466Y914223I-1114J-1927D01*
G01X1342408Y914189D01*
G02X1340934I-737J1277D01*
G03X1338748Y914213I-1114J-1927D01*
G01X1338707Y914189D01*
G02X1337233I-737J1277D01*
G03X1335049Y914213I-1113J-1927D01*
G01X1335008Y914189D01*
G02X1333534I-737J1277D01*
G03X1331366Y914223I-1114J-1927D01*
G01X1331308Y914189D01*
G02X1329834I-737J1277D01*
G03X1327666Y914223I-1114J-1927D01*
G01X1327608Y914189D01*
G02X1326134I-737J1277D01*
G03X1323966Y914223I-1114J-1927D01*
G01X1323908Y914189D01*
G02X1322434I-737J1277D01*
G03X1320208I-1113J-1927D01*
G02X1318734I-737J1277D01*
G03X1316508I-1113J-1927D01*
G02X1315771Y913992I-736J1277D01*
G01X1311217D01*
X1311215Y913990D01*
X1310341Y914864D01*
Y915964D01*
X1309341Y916964D01*
X1304388D01*
G01X1389771Y915466D02*
X1386866Y914223D01*
X1386808Y914189D01*
G02X1385334I-737J1277D01*
G03X1383166Y914223I-1114J-1927D01*
G01X1383108Y914189D01*
G02X1381634I-737J1277D01*
G03X1379466Y914223I-1114J-1927D01*
G01X1379408Y914189D01*
X1379384Y914175D01*
G03X1378295Y912262I1136J-1913D01*
G02X1377592Y911005I-1475J0D01*
G01X1377557Y910985D01*
G02X1376083I-737J1277D01*
G01X1376042Y911009D01*
G03X1373858Y910985I-1071J-1952D01*
G02X1372384I-737J1277D01*
G01X1372343Y911009D01*
G03X1370157Y910985I-1072J-1952D01*
G02X1368683I-737J1277D01*
G01X1368625Y911019D01*
G03X1366457Y910985I-1053J-1962D01*
G02X1364983I-737J1277D01*
G01X1364925Y911019D01*
G03X1362757Y910985I-1053J-1962D01*
G02X1361283I-737J1277D01*
G03X1359057I-1113J-1928D01*
G02X1357583I-737J1277D01*
G01X1357525Y911019D01*
G03X1355357Y910985I-1053J-1962D01*
G02X1353883I-737J1277D01*
G01X1353825Y911019D01*
G03X1351657Y910985I-1053J-1962D01*
G02X1350183I-737J1277D01*
G01X1350142Y911009D01*
G03X1347958Y910985I-1071J-1952D01*
G02X1346484I-737J1277D01*
G01X1346443Y911009D01*
G03X1344257Y910985I-1072J-1952D01*
G02X1342783I-737J1277D01*
G01X1342725Y911019D01*
G03X1340557Y910985I-1053J-1962D01*
G02X1339083I-737J1277D01*
G01X1339025Y911019D01*
G03X1336857Y910985I-1053J-1962D01*
G02X1335383I-737J1277D01*
G03X1333157I-1113J-1928D01*
G02X1331683I-737J1277D01*
G01X1331625Y911019D01*
G03X1329457Y910985I-1053J-1962D01*
G02X1327983I-737J1277D01*
G01X1327925Y911019D01*
G03X1325757Y910985I-1053J-1962D01*
G02X1324283I-737J1277D01*
G01X1324242Y911009D01*
G03X1322058Y910985I-1071J-1952D01*
G02X1321321Y910785I-742J1276D01*
G01X1316307D01*
X1315357Y911735D01*
X1313747D01*
G01X1397171Y915466D02*
X1393780Y917671D01*
G03X1392357Y917393I-308J-2205D01*
G02X1390883I-737J1277D01*
G01X1390825Y917427D01*
G03X1388657Y917393I-1054J-1961D01*
G02X1387183I-737J1277D01*
G01X1387125Y917427D01*
G03X1384957Y917393I-1054J-1961D01*
G02X1383483I-737J1277D01*
G01X1383425Y917427D01*
G03X1381257Y917393I-1054J-1961D01*
G02X1379783I-737J1277D01*
G01X1379725Y917427D01*
G03X1377557Y917393I-1054J-1961D01*
G02X1376083I-737J1277D01*
G01X1376025Y917427D01*
G03X1373857Y917393I-1054J-1961D01*
G02X1372383I-737J1277D01*
G01X1372325Y917427D01*
G03X1370157Y917393I-1054J-1961D01*
G02X1368683I-737J1277D01*
G01X1368625Y917427D01*
G03X1366457Y917393I-1054J-1961D01*
G02X1364983I-737J1277D01*
G03X1362799Y917417I-1113J-1927D01*
G01X1362758Y917393D01*
G02X1361284I-737J1277D01*
G01X1361243Y917417D01*
G03X1359057Y917393I-1072J-1951D01*
G02X1357583I-737J1277D01*
G01X1357525Y917427D01*
G03X1355357Y917393I-1054J-1961D01*
G02X1353883I-737J1277D01*
G01X1353825Y917427D01*
G03X1351657Y917393I-1054J-1961D01*
G02X1350183I-737J1277D01*
G01X1350125Y917427D01*
G03X1347957Y917393I-1054J-1961D01*
G02X1346483I-737J1277D01*
G01X1346425Y917427D01*
G03X1344257Y917393I-1054J-1961D01*
G02X1342783I-737J1277D01*
G01X1342725Y917427D01*
G03X1340557Y917393I-1054J-1961D01*
G02X1339083I-737J1277D01*
G03X1336899Y917417I-1113J-1927D01*
G01X1336858Y917393D01*
G02X1335384I-737J1277D01*
G01X1335343Y917417D01*
G03X1333157Y917393I-1072J-1951D01*
G02X1331683I-737J1277D01*
G01X1331625Y917427D01*
G03X1329457Y917393I-1054J-1961D01*
G02X1327983I-737J1277D01*
G01X1327925Y917427D01*
G03X1325757Y917393I-1054J-1961D01*
G02X1324283I-737J1277D01*
G01X1324242Y917417D01*
G03X1322058Y917393I-1071J-1951D01*
G02X1320584I-737J1277D01*
G03X1319471Y917691I-1112J-1927D01*
G01X1317998Y919164D01*
X1307089D01*
X1306318Y919935D01*
G01X1400871Y921875D02*
X1399398Y923348D01*
X1395539D01*
X1392158Y926729D01*
X1390486D01*
X1389826Y926267D01*
X1378780D01*
X1378394Y926653D01*
G03X1375766Y927040I-1574J-1574D01*
G01X1375708Y927006D01*
G02X1374234I-737J1277D01*
G03X1372066Y927040I-1114J-1927D01*
G01X1372008Y927006D01*
G02X1370534I-737J1277D01*
G03X1368366Y927040I-1114J-1927D01*
G01X1368308Y927006D01*
G02X1366834I-737J1277D01*
G03X1364666Y927040I-1114J-1927D01*
G01X1364608Y927006D01*
G02X1363134I-737J1277D01*
G03X1360948Y927030I-1114J-1927D01*
G01X1360907Y927006D01*
G02X1359433I-737J1277D01*
G01X1359392Y927030D01*
G03X1357208Y927006I-1071J-1951D01*
G02X1355734I-737J1277D01*
G03X1353566Y927040I-1114J-1927D01*
G01X1353508Y927006D01*
G02X1352034I-737J1277D01*
G03X1349866Y927040I-1114J-1927D01*
G01X1349808Y927006D01*
G02X1348334I-737J1277D01*
G03X1346166Y927040I-1114J-1927D01*
G01X1346108Y927006D01*
G02X1344634I-737J1277D01*
G03X1342466Y927040I-1114J-1927D01*
G01X1342408Y927006D01*
G02X1340934I-737J1277D01*
G03X1338766Y927040I-1114J-1927D01*
G01X1338708Y927006D01*
G02X1337234I-737J1277D01*
G03X1335048Y927030I-1114J-1927D01*
G01X1335007Y927006D01*
G02X1333533I-737J1277D01*
G01X1333492Y927030D01*
G03X1331308Y927006I-1071J-1951D01*
G02X1329834I-737J1277D01*
G03X1327666Y927040I-1114J-1927D01*
G01X1327608Y927006D01*
G02X1326134I-737J1277D01*
G03X1323966Y927040I-1114J-1927D01*
G01X1323908Y927006D01*
G03X1323447Y926652I1113J-1926D01*
G01X1322267D01*
X1321874Y927045D01*
X1320427D01*
X1320127Y927345D01*
G01X1397171Y921875D02*
X1395556D01*
X1394082Y923349D01*
X1393468Y923535D01*
X1388333D01*
X1387615Y924253D01*
X1379195D01*
X1379043Y924101D01*
X1378671D01*
G03X1377557Y923802I0J-2225D01*
G02X1376083I-737J1277D01*
G03X1373857I-1113J-1927D01*
G02X1372383I-737J1277D01*
G01X1372325Y923836D01*
G03X1370157Y923802I-1054J-1961D01*
G02X1368683I-737J1277D01*
G01X1368625Y923836D01*
G03X1366457Y923802I-1054J-1961D01*
G02X1364983I-737J1277D01*
G01X1364925Y923836D01*
G03X1362757Y923802I-1054J-1961D01*
G02X1361283I-737J1277D01*
G01X1361242Y923826D01*
G03X1359058Y923802I-1071J-1951D01*
G02X1357584I-737J1277D01*
G01X1357543Y923826D01*
G03X1355357Y923802I-1072J-1951D01*
G02X1353883I-737J1277D01*
G01X1353825Y923836D01*
G03X1351657Y923802I-1054J-1961D01*
G02X1350183I-737J1277D01*
G03X1347957I-1113J-1927D01*
G02X1346483I-737J1277D01*
G01X1346425Y923836D01*
G03X1344257Y923802I-1054J-1961D01*
G02X1342783I-737J1277D01*
G01X1342725Y923836D01*
G03X1340557Y923802I-1054J-1961D01*
G02X1339083I-737J1277D01*
G01X1339025Y923836D01*
G03X1336857Y923802I-1054J-1961D01*
G02X1335383I-737J1277D01*
G01X1335342Y923826D01*
G03X1333158Y923802I-1071J-1951D01*
G02X1331684I-737J1277D01*
G01X1331643Y923826D01*
G03X1329457Y923802I-1072J-1951D01*
G02X1327983I-737J1277D01*
G01X1327925Y923836D01*
G03X1325757Y923802I-1054J-1961D01*
G02X1324283I-737J1277D01*
G03X1323315Y924096I-1114J-1926D01*
G03X1323172Y924100I-134J-2221D01*
G01X1319782D01*
X1319327Y923645D01*
X1316807D01*
X1314238Y926214D01*
G01X1393471Y921875D02*
X1388402D01*
X1386924Y923353D01*
X1379361D01*
Y923352D01*
X1378671D01*
G03X1377934Y923152I5J-1476D01*
G02X1375748Y923128I-1114J1927D01*
G01X1375707Y923152D01*
G03X1374233I-737J-1277D01*
G02X1372049Y923128I-1113J1927D01*
G01X1372008Y923152D01*
G03X1370534I-737J-1277D01*
G02X1368366Y923118I-1114J1927D01*
G01X1368308Y923152D01*
G03X1366834I-737J-1277D01*
G02X1364666Y923118I-1114J1927D01*
G01X1364608Y923152D01*
G03X1363134I-737J-1277D01*
G02X1360966Y923118I-1114J1927D01*
G01X1360908Y923152D01*
G03X1359434I-737J-1277D01*
G02X1357208I-1113J1927D01*
G03X1355734I-737J-1277D01*
G02X1353566Y923118I-1114J1927D01*
G01X1353508Y923152D01*
G03X1352034I-737J-1277D01*
G02X1349848Y923128I-1114J1927D01*
G01X1349807Y923152D01*
G03X1348333I-737J-1277D01*
G02X1346149Y923128I-1113J1927D01*
G01X1346108Y923152D01*
G03X1344634I-737J-1277D01*
G02X1342466Y923118I-1114J1927D01*
G01X1342408Y923152D01*
G03X1340934I-737J-1277D01*
G02X1338766Y923118I-1114J1927D01*
G01X1338708Y923152D01*
G03X1337234I-737J-1277D01*
G02X1335066Y923118I-1114J1927D01*
G01X1335008Y923152D01*
G03X1333534I-737J-1277D01*
G02X1331308I-1113J1927D01*
G03X1329834I-737J-1277D01*
G02X1327666Y923118I-1114J1927D01*
G01X1327608Y923152D01*
G03X1326134I-737J-1277D01*
G02X1323966Y923118I-1114J1927D01*
G01X1323908Y923152D01*
G03X1323171Y923351I-740J-1276D01*
G01X1321301D01*
X1320515Y922565D01*
X1315463D01*
X1314505Y923523D01*
G01X1397604Y1044544D02*
X1395129Y1042681D01*
X1395016Y1042617D01*
X1395015D01*
G02X1392790I-1113J1927D01*
G03X1391316I-737J-1277D01*
G01X1391258Y1042583D01*
G02X1389090Y1042617I-1054J1961D01*
G03X1387616I-737J-1277D01*
G01X1386946D01*
X1386466Y1042137D01*
Y1040979D01*
X1379386Y1033899D01*
X1375669D01*
X1375127Y1033357D01*
G02X1374667Y1033004I-1574J1574D01*
G02X1372499Y1032970I-1114J1927D01*
G01X1372441Y1033004D01*
G03X1370967I-737J-1277D01*
G02X1368799Y1032970I-1114J1927D01*
G01X1368741Y1033004D01*
G03X1367267I-737J-1277D01*
G02X1365099Y1032970I-1114J1927D01*
G01X1365041Y1033004D01*
G03X1363567I-737J-1277D01*
G02X1361381Y1032980I-1114J1927D01*
G01X1361340Y1033004D01*
G03X1359866I-737J-1277D01*
G01X1359825Y1032980D01*
G02X1357641Y1033004I-1071J1951D01*
G03X1356167I-737J-1277D01*
G02X1353999Y1032970I-1114J1927D01*
G01X1353941Y1033004D01*
G03X1352467I-737J-1277D01*
G02X1350299Y1032970I-1114J1927D01*
G01X1350241Y1033004D01*
G03X1348767I-737J-1277D01*
G02X1346599Y1032970I-1114J1927D01*
G01X1346541Y1033004D01*
G03X1345067I-737J-1277D01*
G02X1342899Y1032970I-1114J1927D01*
G01X1342841Y1033004D01*
G03X1341367I-737J-1277D01*
G02X1339199Y1032970I-1114J1927D01*
G01X1339141Y1033004D01*
G03X1337667I-737J-1277D01*
G02X1335481Y1032980I-1114J1927D01*
G01X1335440Y1033004D01*
G03X1333966I-737J-1277D01*
G01X1333908Y1032970D01*
G02X1331740Y1033004I-1054J1961D01*
G03X1330266I-737J-1277D01*
G02X1328082Y1032980I-1113J1927D01*
G01X1328041Y1033004D01*
G03X1326567I-737J-1277D01*
G02X1324381Y1032980I-1114J1927D01*
G03X1323603Y1033203I-780J-1252D01*
G01X1317965D01*
X1317468Y1032706D01*
X1316947D01*
G01X1379104Y1038136D02*
X1377026Y1037146D01*
G03X1376141Y1036859I229J-2214D01*
G02X1374667I-737J1277D01*
G03X1372441I-1113J-1927D01*
G02X1370967I-737J1277D01*
G01X1370909Y1036893D01*
G03X1368741Y1036859I-1054J-1961D01*
G02X1367267I-737J1277D01*
G01X1367209Y1036893D01*
G03X1365041Y1036859I-1054J-1961D01*
G02X1363567I-737J1277D01*
G01X1363526Y1036883D01*
G03X1361342Y1036859I-1071J-1951D01*
G02X1359818Y1036864I-758J1313D01*
G01X1359703Y1036922D01*
G03X1357641Y1036859I-973J-1946D01*
G02X1356167I-737J1277D01*
G01X1356109Y1036893D01*
G03X1353941Y1036859I-1054J-1961D01*
G02X1352467I-737J1277D01*
G01X1352409Y1036893D01*
G03X1350241Y1036859I-1054J-1961D01*
G02X1348834Y1036822I-738J1277D01*
G03X1348668Y1036884I-339J-655D01*
G03X1346640I-1014J-4315D01*
G03X1346475Y1036822I175J-716D01*
G02X1345067Y1036859I-670J1313D01*
G01X1345009Y1036893D01*
G03X1342841Y1036859I-1054J-1961D01*
G02X1341367I-737J1277D01*
G01X1341309Y1036893D01*
G03X1339141Y1036859I-1054J-1961D01*
G02X1337667I-737J1277D01*
G01X1337626Y1036883D01*
G03X1335442Y1036859I-1071J-1951D01*
G02X1333968I-737J1277D01*
G03X1331602Y1036468I-945J-1637D01*
G01X1384653Y1073383D02*
X1383422D01*
X1383165Y1073126D01*
G02X1379899Y1071421I-2212J257D01*
G01X1379841Y1071455D01*
G03X1378367I-737J-1277D01*
G02X1376199Y1071421I-1115J1928D01*
G01X1376141Y1071455D01*
G03X1374667I-737J-1277D01*
G02X1372499Y1071421I-1115J1928D01*
G01X1372441Y1071455D01*
G03X1370967I-737J-1277D01*
G02X1368799Y1071421I-1115J1928D01*
G01X1368741Y1071455D01*
G03X1367267I-737J-1277D01*
G02X1365099Y1071421I-1115J1928D01*
G01X1365041Y1071455D01*
G03X1363567I-737J-1277D01*
G02X1361381Y1071431I-1114J1928D01*
G01X1361340Y1071455D01*
G03X1359866I-737J-1277D01*
G01X1359825Y1071431D01*
G02X1357641Y1071455I-1071J1952D01*
G03X1356167I-737J-1277D01*
G02X1353999Y1071421I-1115J1928D01*
G01X1353941Y1071455D01*
G03X1352467I-737J-1277D01*
G02X1350299Y1071421I-1115J1928D01*
G01X1350241Y1071455D01*
G03X1348767I-737J-1277D01*
G02X1346599Y1071421I-1115J1928D01*
G01X1346541Y1071455D01*
G03X1345067I-737J-1277D01*
G02X1342899Y1071421I-1115J1928D01*
G01X1342841Y1071455D01*
G03X1341367I-737J-1277D01*
G02X1339199Y1071421I-1115J1928D01*
G01X1339141Y1071455D01*
G03X1337667I-737J-1277D01*
G02X1335481Y1071431I-1114J1928D01*
G01X1335440Y1071455D01*
G03X1333966I-737J-1277D01*
G01X1333908Y1071421D01*
G02X1331740Y1071455I-1053J1962D01*
G03X1330266I-737J-1277D01*
G02X1328082Y1071431I-1113J1928D01*
G01X1328041Y1071455D01*
G03X1326567I-737J-1277D01*
G01X1326526Y1071431D01*
G02X1324340Y1071455I-1072J1952D01*
G03X1323602Y1071656I-744J-1275D01*
G01X1320820D01*
G01X1382804Y1070178D02*
X1381573D01*
X1381314Y1069919D01*
G02X1377991Y1068251I-2210J259D01*
G03X1376517I-737J-1277D01*
G02X1374291I-1113J1927D01*
G03X1372817I-737J-1277D01*
G01X1372776Y1068227D01*
G02X1370590Y1068251I-1072J1951D01*
G03X1369116I-737J-1277D01*
G01X1369058Y1068217D01*
G02X1366890Y1068251I-1054J1961D01*
G03X1365416I-737J-1277D01*
G01X1365358Y1068217D01*
G02X1363190Y1068251I-1054J1961D01*
G03X1361716I-737J-1277D01*
G02X1359490I-1113J1927D01*
G03X1358016I-737J-1277D01*
G01X1357958Y1068217D01*
G02X1355790Y1068251I-1054J1961D01*
G03X1354316I-737J-1277D01*
G01X1354258Y1068217D01*
G02X1352090Y1068251I-1054J1961D01*
G03X1350616I-737J-1277D01*
G01X1350575Y1068227D01*
G02X1348391Y1068251I-1071J1951D01*
G03X1346917I-737J-1277D01*
G01X1346876Y1068227D01*
G02X1344690Y1068251I-1072J1951D01*
G03X1343216I-737J-1277D01*
G01X1343158Y1068217D01*
G02X1340990Y1068251I-1054J1961D01*
G03X1339516I-737J-1277D01*
G01X1339458Y1068217D01*
G02X1337290Y1068251I-1054J1961D01*
G03X1335816I-737J-1277D01*
G02X1333590I-1113J1927D01*
G03X1332116I-737J-1277D01*
G02X1329890I-1113J1927D01*
G03X1328416I-737J-1277D01*
G01X1328358Y1068217D01*
G02X1326190Y1068251I-1054J1961D01*
G03X1324716I-737J-1277D01*
G02X1322490I-1113J1927D01*
G03X1321016I-737J-1277D01*
G03X1320710Y1068017I735J-1278D01*
G01X1319973Y1067280D01*
G01X1380953Y1073383D02*
X1382184D01*
X1382410Y1073157D01*
G02X1380216Y1072106I-1457J226D01*
G01X1380158Y1072140D01*
G03X1377990Y1072106I-1053J-1962D01*
G02X1376516I-737J1277D01*
G01X1376458Y1072140D01*
G03X1374290Y1072106I-1053J-1962D01*
G02X1372816I-737J1277D01*
G01X1372758Y1072140D01*
G03X1370590Y1072106I-1053J-1962D01*
G02X1369116I-737J1277D01*
G01X1369058Y1072140D01*
G03X1366890Y1072106I-1053J-1962D01*
G02X1365416I-737J1277D01*
G01X1365358Y1072140D01*
G03X1363190Y1072106I-1053J-1962D01*
G02X1361716I-737J1277D01*
G03X1359532Y1072130I-1113J-1928D01*
G01X1359491Y1072106D01*
G02X1358017I-737J1277D01*
G01X1357976Y1072130D01*
G03X1355790Y1072106I-1072J-1952D01*
G02X1354316I-737J1277D01*
G01X1354258Y1072140D01*
G03X1352090Y1072106I-1053J-1962D01*
G02X1350616I-737J1277D01*
G01X1350558Y1072140D01*
G03X1348390Y1072106I-1053J-1962D01*
G02X1346916I-737J1277D01*
G01X1346858Y1072140D01*
G03X1344690Y1072106I-1053J-1962D01*
G02X1343216I-737J1277D01*
G01X1343158Y1072140D01*
G03X1340990Y1072106I-1053J-1962D01*
G02X1339516I-737J1277D01*
G01X1339458Y1072140D01*
G03X1337290Y1072106I-1053J-1962D01*
G02X1335816I-737J1277D01*
G03X1333632Y1072130I-1113J-1928D01*
G01X1333591Y1072106D01*
G02X1332117I-737J1277D01*
G03X1329931Y1072130I-1114J-1928D01*
G01X1329890Y1072106D01*
G02X1328416I-737J1277D01*
G01X1328375Y1072130D01*
G03X1326191Y1072106I-1071J-1952D01*
G02X1324717I-737J1277D01*
G03X1321906Y1072860I-2811J-4862D01*
G01X1403153Y1054157D02*
X1401823D01*
X1399761Y1056219D01*
Y1058319D01*
X1400994Y1059552D01*
Y1060027D01*
G02X1400928Y1060565I2160J538D01*
G03X1400225Y1061822I-1475J0D01*
G01X1400190Y1061842D01*
G02X1399079Y1063683I1114J1928D01*
G01Y1063770D01*
G03X1398376Y1065027I-1475J0D01*
G01X1398341Y1065047D01*
X1398317Y1065061D01*
G02X1397228Y1066974I1136J1913D01*
G03X1396525Y1068231I-1475J0D01*
G01X1396490Y1068251D01*
G02X1395379Y1070117I1114J1927D01*
G01Y1070178D01*
G03X1394676Y1071435I-1475J0D01*
G01X1394641Y1071455D01*
G02X1393528Y1073327I1112J1928D01*
G01Y1073383D01*
G03X1392825Y1074640I-1475J0D01*
G01X1392790Y1074660D01*
G03X1391316I-737J-1277D01*
G01X1391258Y1074626D01*
G02X1389090Y1074660I-1054J1961D01*
G03X1387616I-737J-1277D01*
G01X1387558Y1074626D01*
G02X1385390Y1074660I-1054J1961D01*
G03X1383916I-737J-1277D01*
G02X1381690I-1113J1927D01*
G02X1380578Y1076548I1113J1927D01*
G01Y1076621D01*
G03X1379841Y1077864I-1474J-34D01*
G03X1378367I-737J-1277D01*
G02X1376181Y1077840I-1114J1927D01*
G01X1376140Y1077864D01*
G03X1374666I-737J-1277D01*
G02X1372482Y1077840I-1113J1927D01*
G01X1372441Y1077864D01*
G03X1370967I-737J-1277D01*
G02X1368799Y1077830I-1114J1927D01*
G01X1368741Y1077864D01*
G03X1367267I-737J-1277D01*
G02X1365099Y1077830I-1114J1927D01*
G01X1365041Y1077864D01*
G03X1363567I-737J-1277D01*
G02X1361399Y1077830I-1114J1927D01*
G01X1361341Y1077864D01*
G03X1359867I-737J-1277D01*
G02X1357699Y1077830I-1114J1927D01*
G01X1357641Y1077864D01*
G03X1356167I-737J-1277D01*
G02X1353999Y1077830I-1114J1927D01*
G01X1353941Y1077864D01*
G03X1352467I-737J-1277D01*
G02X1350281Y1077840I-1114J1927D01*
G01X1350240Y1077864D01*
G03X1348766I-737J-1277D01*
G02X1346582Y1077840I-1113J1927D01*
G01X1346541Y1077864D01*
G03X1345067I-737J-1277D01*
G02X1342899Y1077830I-1114J1927D01*
G01X1342841Y1077864D01*
G03X1341367I-737J-1277D01*
G02X1339199Y1077830I-1114J1927D01*
G01X1339141Y1077864D01*
G03X1337667I-737J-1277D01*
G02X1335441I-1113J1927D01*
G03X1333967I-737J-1277D01*
G02X1331781Y1077840I-1114J1927D01*
G01X1331740Y1077864D01*
G03X1330266I-737J-1277D01*
G02X1328040I-1113J1927D01*
G03X1326566I-737J-1277D01*
G02X1324340I-1113J1927D01*
G03X1322866I-737J-1277D01*
G02X1320640I-1113J1927D01*
G03X1319166I-737J-1277D01*
G02X1316982Y1077840I-1113J1927D01*
G03X1316204Y1078062I-778J-1252D01*
G01X1315448D01*
G01X1406853Y1054157D02*
X1405691Y1055319D01*
X1404361D01*
X1403076Y1056604D01*
Y1058706D01*
G03X1402440Y1059274I-1772J-1344D01*
G01X1402416Y1059288D01*
X1402381Y1059308D01*
G02X1401678Y1060565I772J1257D01*
G01Y1060652D01*
G03X1400567Y1062493I-2225J-87D01*
G01X1400532Y1062513D01*
G02X1399829Y1063770I772J1257D01*
G03X1398740Y1065683I-2225J0D01*
G01X1398716Y1065697D01*
X1398681Y1065717D01*
G02X1397978Y1066974I772J1257D01*
G01Y1067035D01*
G03X1396867Y1068901I-2225J-61D01*
G01X1396832Y1068921D01*
G02X1396129Y1070178I772J1257D01*
G01Y1070234D01*
G03X1395016Y1072106I-2225J-56D01*
G01X1394981Y1072126D01*
G02X1394278Y1073383I772J1257D01*
G01Y1073444D01*
G03X1393167Y1075310I-2225J-61D01*
G03X1390999Y1075344I-1114J-1927D01*
G01X1390941Y1075310D01*
G02X1389467I-737J1277D01*
G03X1387299Y1075344I-1114J-1927D01*
G01X1387241Y1075310D01*
G02X1385767I-737J1277D01*
G03X1383581Y1075334I-1114J-1927D01*
G01X1383540Y1075310D01*
G02X1382066I-737J1277D01*
G02X1381329Y1076553I737J1277D01*
G01Y1076587D01*
G03X1380240Y1078500I-2225J0D01*
G01X1380216Y1078514D01*
X1380158Y1078548D01*
G03X1377990Y1078514I-1054J-1961D01*
G02X1376516I-737J1277D01*
G03X1374290I-1113J-1927D01*
G02X1372816I-737J1277D01*
G01X1372758Y1078548D01*
G03X1370590Y1078514I-1054J-1961D01*
G02X1369116I-737J1277D01*
G01X1369058Y1078548D01*
G03X1366890Y1078514I-1054J-1961D01*
G02X1365416I-737J1277D01*
G01X1365358Y1078548D01*
G03X1363190Y1078514I-1054J-1961D01*
G02X1361716I-737J1277D01*
G01X1361658Y1078548D01*
G03X1359490Y1078514I-1054J-1961D01*
G02X1358016I-737J1277D01*
G01X1357958Y1078548D01*
G03X1355790Y1078514I-1054J-1961D01*
G02X1354316I-737J1277D01*
G01X1354258Y1078548D01*
G03X1352090Y1078514I-1054J-1961D01*
G02X1350616I-737J1277D01*
G03X1348390I-1113J-1927D01*
G02X1346916I-737J1277D01*
G01X1346858Y1078548D01*
G03X1344690Y1078514I-1054J-1961D01*
G02X1343216I-737J1277D01*
G01X1343158Y1078548D01*
G03X1340990Y1078514I-1054J-1961D01*
G02X1339516I-737J1277D01*
G01X1339475Y1078538D01*
G03X1337291Y1078514I-1071J-1951D01*
G02X1335817I-737J1277D01*
G01X1335776Y1078538D01*
G03X1333590Y1078514I-1072J-1951D01*
G02X1332116I-737J1277D01*
G03X1329890I-1113J-1927D01*
G02X1328416I-737J1277D01*
G03X1326190I-1113J-1927D01*
G02X1324716I-737J1277D01*
G03X1322490I-1113J-1927D01*
G02X1321016I-737J1277D01*
G03X1318790I-1113J-1927D01*
G02X1317316I-737J1277D01*
G02X1317010Y1078748I735J1278D01*
G01X1316345Y1079413D01*
X1314261D01*
G01X1374440Y1143023D02*
X1375142D01*
X1375517Y1143398D01*
X1378844D01*
X1380578Y1141664D01*
Y1140335D01*
G02X1379853Y1139553I-1474J639D01*
G03X1378729Y1138247I1101J-2084D01*
G01Y1137396D01*
G03X1382067Y1135541I2225J73D01*
G02X1384279Y1134264I737J-1277D01*
G01Y1134203D01*
G03X1385390Y1132337I2225J61D01*
G01X1385394Y1132335D01*
X1385425Y1132317D01*
G02Y1129803I-772J-1257D01*
G01X1385390Y1129783D01*
G03X1384278Y1127895I1113J-1927D01*
G01Y1127822D01*
G02X1383541Y1126579I-1474J34D01*
G03X1382428Y1124707I1112J-1928D01*
G01Y1124651D01*
G02X1381725Y1123394I-1475J0D01*
G01X1381690Y1123374D01*
G03X1380619Y1121875I1111J-1926D01*
G03X1380578Y1121448I2183J-425D01*
G01Y1120796D01*
G02X1380029Y1119845I-1098J0D01*
G01X1380028D01*
X1379975Y1119814D01*
G02X1378178Y1119845I-871J1633D01*
G01X1375404Y1121447D01*
G01X1382803D02*
X1381641D01*
X1381357Y1121731D01*
G02X1382066Y1122724I1447J-283D01*
G03X1383178Y1124612I-1113J1927D01*
G01Y1124651D01*
G02X1383881Y1125908I1475J0D01*
G01X1383916Y1125928D01*
G03X1385029Y1127800I-1112J1928D01*
G01Y1127890D01*
G02X1385766Y1129133I1474J-34D01*
G01X1385803Y1129155D01*
X1385814Y1129161D01*
G03X1386879Y1131060I-1161J1899D01*
G03X1385791Y1132973I-2226J0D01*
G01X1385767Y1132987D01*
X1385732Y1133007D01*
G02X1385029Y1134264I772J1257D01*
G01Y1134337D01*
G03X1381691Y1136192I-2225J-73D01*
G02X1379479Y1137469I-737J1277D01*
G01Y1138104D01*
G02X1380204Y1138889I1475J-635D01*
G03X1381328Y1140195I-1101J2084D01*
G01Y1141975D01*
X1379155Y1144148D01*
X1375485D01*
X1375110Y1144523D01*
X1374440D01*
G01X1297007Y172249D02*
X1295891D01*
X1295604Y171962D01*
X1292384D01*
X1292154Y171732D01*
X1291084D01*
G01X1296999Y175949D02*
X1295107Y174057D01*
X1291834D01*
G01X1303407Y179649D02*
X1299556D01*
X1297807Y177900D01*
X1296207D01*
X1295133Y178974D01*
Y179637D01*
X1294090Y180680D01*
X1292967D01*
X1290759Y178472D01*
G01X1408271Y921875D02*
G03X1406809Y921478I0J-2890D01*
G01X1405308Y920598D01*
G03X1404195Y918726I1112J-1928D01*
G01Y918670D01*
G02X1403492Y917413I-1475J0D01*
G01X1403457Y917393D01*
G03X1402346Y915527I1114J-1927D01*
G01Y915466D01*
G02X1401643Y914209I-1475J0D01*
G01X1401584Y914175D01*
G02X1400315Y913832I-1269J2175D01*
G01X1398942D01*
G03X1397559Y913259I0J-1956D01*
G01X1397144Y912844D01*
G03X1396856Y912149I695J-695D01*
G02X1395871Y910524I-1833J0D01*
G03X1394946Y909057I701J-1467D01*
G02X1394243Y907800I-1475J0D01*
G01X1394160Y907752D01*
G03X1393095Y905853I1161J-1899D01*
G02X1390883Y904576I-1475J0D01*
G01X1390825Y904610D01*
G03X1387546Y902710I-1054J-1961D01*
G01Y902649D01*
G02X1386843Y901392I-1475J0D01*
G01X1386784Y901358D01*
G03X1385695Y899445I1136J-1913D01*
G02X1384992Y898188I-1475J0D01*
G01X1384957Y898168D01*
G03X1383846Y896327I1114J-1928D01*
G01Y896240D01*
G02X1383143Y894983I-1475J0D01*
G01X1383060Y894935D01*
G03X1381995Y893036I1161J-1899D01*
G02X1381292Y891779I-1475J0D01*
G01X1381257Y891759D01*
G03X1380146Y889893I1114J-1927D01*
G01Y889832D01*
G02X1377934Y888555I-1475J0D01*
G03X1375766Y888589I-1115J-1928D01*
G01X1375708Y888555D01*
G02X1374234I-737J1277D01*
G03X1372066Y888589I-1115J-1928D01*
G01X1372008Y888555D01*
G02X1370534I-737J1277D01*
G03X1368366Y888589I-1115J-1928D01*
G01X1368308Y888555D01*
G02X1366834I-737J1277D01*
G03X1364666Y888589I-1115J-1928D01*
G01X1364608Y888555D01*
G02X1363134I-737J1277D01*
G03X1360966Y888589I-1115J-1928D01*
G01X1360908Y888555D01*
G02X1359434I-737J1277D01*
G03X1357266Y888589I-1115J-1928D01*
G01X1357208Y888555D01*
G02X1355734I-737J1277D01*
G03X1353566Y888589I-1115J-1928D01*
G01X1353508Y888555D01*
G02X1352034I-737J1277D01*
G03X1349866Y888589I-1115J-1928D01*
G01X1349808Y888555D01*
G02X1348334I-737J1277D01*
G03X1346166Y888589I-1115J-1928D01*
G01X1346108Y888555D01*
G02X1344634I-737J1277D01*
G03X1342466Y888589I-1115J-1928D01*
G01X1342408Y888555D01*
G02X1340934I-737J1277D01*
G03X1338766Y888589I-1115J-1928D01*
G01X1338708Y888555D01*
G02X1337234I-737J1277D01*
G03X1335048Y888579I-1114J-1928D01*
G01X1335007Y888555D01*
G02X1333533I-737J1277D01*
G03X1331349Y888579I-1113J-1928D01*
G01X1331308Y888555D01*
G02X1329834I-737J1277D01*
G03X1327666Y888589I-1115J-1928D01*
G01X1327608Y888555D01*
G02X1326134I-737J1277D01*
G03X1323908I-1113J-1928D01*
G03X1322796Y886700I1113J-1928D01*
G01Y886627D01*
G02X1322093Y885370I-1475J0D01*
G01X1322058Y885350D01*
G02X1320584I-737J1277D01*
G03X1318358I-1113J-1927D01*
G02X1316884I-737J1277D01*
G03X1314658I-1113J-1927D01*
G02X1313184I-737J1277D01*
G03X1311016Y885384I-1114J-1927D01*
G01X1310958Y885350D01*
G02X1310221Y885151I-740J1276D01*
G01X1308417D01*
G01X1376820Y893036D02*
X1376204Y894103D01*
X1375854Y894196D01*
G02X1373857Y894313I-882J2044D01*
G03X1372383I-737J-1277D01*
G01X1372325Y894279D01*
G02X1370157Y894313I-1054J1961D01*
G03X1368683I-737J-1277D01*
G02X1366499Y894289I-1113J1927D01*
G01X1366458Y894313D01*
G03X1364984I-737J-1277D01*
G01X1364943Y894289D01*
G02X1362757Y894313I-1072J1951D01*
G03X1361283I-737J-1277D01*
G01X1361225Y894279D01*
G02X1359057Y894313I-1054J1961D01*
G03X1357583I-737J-1277D01*
G01X1357542Y894289D01*
G02X1355358Y894313I-1071J1951D01*
G03X1353884I-737J-1277D01*
G01X1353843Y894289D01*
G02X1351657Y894313I-1072J1951D01*
G03X1350183I-737J-1277D01*
G01X1350125Y894279D01*
G02X1347957Y894313I-1054J1961D01*
G03X1346483I-737J-1277D01*
G01X1346425Y894279D01*
G02X1344257Y894313I-1054J1961D01*
G03X1342783I-737J-1277D01*
G01X1342725Y894279D01*
G02X1340557Y894313I-1054J1961D01*
G03X1339083I-737J-1277D01*
G02X1336899Y894289I-1113J1927D01*
G01X1336858Y894313D01*
G03X1335384I-737J-1277D01*
G01X1335343Y894289D01*
G02X1333157Y894313I-1072J1951D01*
G03X1331683I-737J-1277D01*
G01X1331625Y894279D01*
G02X1329457Y894313I-1054J1961D01*
G03X1327983I-737J-1277D01*
G01X1327925Y894279D01*
G02X1325757Y894313I-1054J1961D01*
G03X1324283I-737J-1277D01*
G01X1324242Y894289D01*
G02X1322058Y894313I-1071J1951D01*
G03X1320584I-737J-1277D01*
G02X1318398Y894289I-1114J1927D01*
G01X1318357Y894313D01*
G03X1316883I-737J-1277D01*
G01X1316842Y894289D01*
G02X1314658Y894313I-1071J1951D01*
G03X1313184I-737J-1277D01*
G02X1310998Y894289I-1114J1927D01*
G01X1310957Y894313D01*
G03X1310220Y894510I-736J-1277D01*
G01X1309317D01*
G01X1393471Y909057D02*
X1392855Y907990D01*
X1392504Y907896D01*
G03X1390566Y907814I-884J-2043D01*
G01X1390508Y907780D01*
G02X1389034I-737J1277D01*
G03X1386866Y907814I-1114J-1927D01*
G01X1386808Y907780D01*
X1386784Y907766D01*
G03X1385695Y905853I1136J-1913D01*
G02X1384992Y904596I-1475J0D01*
G01X1384957Y904576D01*
G03X1383846Y902710I1114J-1927D01*
G01Y902649D01*
G02X1383143Y901392I-1475J0D01*
G01X1383108Y901372D01*
X1383084Y901358D01*
G03X1381995Y899445I1136J-1913D01*
G02X1381292Y898188I-1475J0D01*
G01X1381257Y898168D01*
G03X1380146Y896327I1114J-1928D01*
G01Y896240D01*
G02X1379443Y894983I-1475J0D01*
G01X1379408Y894963D01*
X1379384Y894949D01*
G03X1378295Y893036I1136J-1913D01*
G02X1377592Y891779I-1475J0D01*
G01X1377557Y891759D01*
G02X1376083I-737J1277D01*
G01X1376042Y891783D01*
G03X1373858Y891759I-1071J-1951D01*
G02X1372384I-737J1277D01*
G03X1370158I-1113J-1927D01*
G02X1368684I-737J1277D01*
G03X1366458I-1113J-1927D01*
G02X1364984I-737J1277D01*
G01X1364943Y891783D01*
G03X1362757Y891759I-1072J-1951D01*
G02X1361283I-737J1277D01*
G01X1361225Y891793D01*
G03X1359057Y891759I-1054J-1961D01*
G02X1357583I-737J1277D01*
G01X1357542Y891783D01*
G03X1355358Y891759I-1071J-1951D01*
G02X1353884I-737J1277D01*
G01X1353843Y891783D01*
G03X1351657Y891759I-1072J-1951D01*
G02X1350183I-737J1277D01*
G01X1350125Y891793D01*
G03X1347957Y891759I-1054J-1961D01*
G02X1346483I-737J1277D01*
G01X1346442Y891783D01*
G03X1344258Y891759I-1071J-1951D01*
G02X1342784I-737J1277D01*
G03X1340558I-1113J-1927D01*
G02X1339084I-737J1277D01*
G03X1336858I-1113J-1927D01*
G02X1335384I-737J1277D01*
G03X1333198Y891783I-1114J-1927D01*
G01X1333157Y891759D01*
G02X1331683I-737J1277D01*
G01X1331625Y891793D01*
G03X1329457Y891759I-1054J-1961D01*
G02X1327983I-737J1277D01*
G01X1327925Y891793D01*
G03X1325757Y891759I-1054J-1961D01*
G02X1324283I-737J1277D01*
G01X1324242Y891783D01*
G03X1322058Y891759I-1071J-1951D01*
G02X1320584I-737J1277D01*
G03X1318398Y891783I-1114J-1927D01*
G01X1318357Y891759D01*
G02X1316883I-737J1277D01*
G01X1316842Y891783D01*
G03X1314658Y891759I-1071J-1951D01*
G02X1313184I-737J1277D01*
G03X1310998Y891783I-1114J-1927D01*
G01X1310957Y891759D01*
G02X1310220Y891562I-736J1277D01*
G01X1308997D01*
G01X1376820Y899445D02*
X1374845Y898463D01*
G03X1373857Y898168I126J-2223D01*
G02X1372383I-737J1277D01*
G01X1372325Y898202D01*
G03X1370157Y898168I-1053J-1962D01*
G02X1368683I-737J1277D01*
G03X1366457I-1113J-1928D01*
G02X1364983I-737J1277D01*
G01X1364942Y898192D01*
G03X1362758Y898168I-1071J-1952D01*
G02X1361284I-737J1277D01*
G01X1361243Y898192D01*
G03X1359057Y898168I-1072J-1952D01*
G02X1357583I-737J1277D01*
G01X1357525Y898202D01*
G03X1355357Y898168I-1053J-1962D01*
G02X1353883I-737J1277D01*
G01X1353825Y898202D01*
G03X1351657Y898168I-1053J-1962D01*
G02X1350183I-737J1277D01*
G01X1350125Y898202D01*
G03X1347957Y898168I-1053J-1962D01*
G02X1346483I-737J1277D01*
G01X1346425Y898202D01*
G03X1344257Y898168I-1053J-1962D01*
G02X1342783I-737J1277D01*
G01X1342725Y898202D01*
G03X1340557Y898168I-1053J-1962D01*
G02X1339083I-737J1277D01*
G03X1336899Y898192I-1113J-1928D01*
G01X1336858Y898168D01*
G02X1335384I-737J1277D01*
G01X1335343Y898192D01*
G03X1333157Y898168I-1072J-1952D01*
G02X1331683I-737J1277D01*
G01X1331625Y898202D01*
G03X1329457Y898168I-1053J-1962D01*
G02X1327983I-737J1277D01*
G01X1327925Y898202D01*
G03X1325757Y898168I-1053J-1962D01*
G02X1324283I-737J1277D01*
G01X1324242Y898192D01*
G03X1322058Y898168I-1071J-1952D01*
G02X1320584I-737J1277D01*
G01X1320535Y898195D01*
X1320526Y898200D01*
X1319225Y898957D01*
X1315087D01*
G01X1391620Y912262D02*
X1391004Y911195D01*
X1390654Y911102D01*
G03X1388657Y910985I-882J-2045D01*
G02X1387183I-737J1277D01*
G01X1387125Y911019D01*
G03X1384957Y910985I-1053J-1962D01*
G03X1383846Y909144I1114J-1928D01*
G01Y909057D01*
G02X1383143Y907800I-1475J0D01*
G01X1383108Y907780D01*
X1383084Y907766D01*
G03X1381995Y905853I1136J-1913D01*
G02X1381292Y904596I-1475J0D01*
G01X1381257Y904576D01*
G03X1380146Y902710I1114J-1927D01*
G01Y902649D01*
G02X1379443Y901392I-1475J0D01*
G01X1379408Y901372D01*
G02X1377934I-737J1277D01*
G03X1375748Y901396I-1114J-1927D01*
G01X1375707Y901372D01*
G02X1374233I-737J1277D01*
G03X1372049Y901396I-1113J-1927D01*
G01X1372008Y901372D01*
G02X1370534I-737J1277D01*
G03X1368366Y901406I-1114J-1927D01*
G01X1368308Y901372D01*
G02X1366834I-737J1277D01*
G03X1364666Y901406I-1114J-1927D01*
G01X1364608Y901372D01*
G02X1363134I-737J1277D01*
G03X1360908I-1113J-1927D01*
G02X1359434I-737J1277D01*
G03X1357266Y901406I-1114J-1927D01*
G01X1357208Y901372D01*
G02X1355734I-737J1277D01*
G03X1353566Y901406I-1114J-1927D01*
G01X1353508Y901372D01*
G02X1352034I-737J1277D01*
G03X1349848Y901396I-1114J-1927D01*
G01X1349807Y901372D01*
G02X1348333I-737J1277D01*
G03X1346149Y901396I-1113J-1927D01*
G01X1346108Y901372D01*
G02X1344634I-737J1277D01*
G03X1342466Y901406I-1114J-1927D01*
G01X1342408Y901372D01*
G02X1340934I-737J1277D01*
G03X1338766Y901406I-1114J-1927D01*
G01X1338708Y901372D01*
G02X1337234I-737J1277D01*
G03X1335008I-1113J-1927D01*
G02X1333534I-737J1277D01*
G03X1331366Y901406I-1114J-1927D01*
G01X1331308Y901372D01*
G02X1329834I-737J1277D01*
G03X1327666Y901406I-1114J-1927D01*
G01X1327608Y901372D01*
G02X1326134I-737J1277D01*
G03X1323966Y901406I-1114J-1927D01*
G01X1323908Y901372D01*
G02X1322434I-737J1277D01*
G02X1322128Y901606I735J1278D01*
G01X1321675Y902059D01*
X1318430D01*
X1317506Y901135D01*
X1307657D01*
G01X1376820Y912262D02*
X1373858Y913539D01*
G03X1372384I-737J-1277D01*
G01X1372343Y913515D01*
G02X1370157Y913539I-1072J1951D01*
G03X1368683I-737J-1277D01*
G01X1368625Y913505D01*
G02X1366457Y913539I-1054J1961D01*
G03X1364983I-737J-1277D01*
G02X1362757I-1113J1927D01*
G03X1361283I-737J-1277D01*
G01X1361225Y913505D01*
G02X1359057Y913539I-1054J1961D01*
G03X1357583I-737J-1277D01*
G01X1357525Y913505D01*
G02X1355357Y913539I-1054J1961D01*
G03X1353883I-737J-1277D01*
G01X1353825Y913505D01*
G02X1351657Y913539I-1054J1961D01*
G03X1350183I-737J-1277D01*
G01X1350142Y913515D01*
G02X1347958Y913539I-1071J1951D01*
G03X1346484I-737J-1277D01*
G01X1346443Y913515D01*
G02X1344257Y913539I-1072J1951D01*
G03X1342783I-737J-1277D01*
G01X1342725Y913505D01*
G02X1340557Y913539I-1054J1961D01*
G03X1339083I-737J-1277D01*
G02X1336857I-1113J1927D01*
G03X1335383I-737J-1277D01*
G01X1335325Y913505D01*
G02X1333157Y913539I-1054J1961D01*
G03X1331683I-737J-1277D01*
G01X1331625Y913505D01*
G02X1329457Y913539I-1054J1961D01*
G03X1327983I-737J-1277D01*
G01X1327925Y913505D01*
G02X1325757Y913539I-1054J1961D01*
G03X1324283I-737J-1277D01*
G01X1324242Y913515D01*
G02X1322058Y913539I-1071J1951D01*
G03X1320584I-737J-1277D01*
G02X1318358I-1113J1927D01*
G03X1316884I-737J-1277D01*
G03X1316578Y913305I735J-1278D01*
G01X1316237Y912964D01*
X1313617D01*
G01X1387920Y912262D02*
X1385834Y913253D01*
G02X1384957Y913539I237J2213D01*
G03X1383483I-737J-1277D01*
G01X1383425Y913505D01*
G02X1381257Y913539I-1054J1961D01*
G03X1379045Y912262I-737J-1277D01*
G01Y912175D01*
G02X1375766Y910300I-2225J87D01*
G01X1375708Y910334D01*
G03X1374234I-737J-1277D01*
G02X1372008I-1113J1928D01*
G03X1370534I-737J-1277D01*
G02X1368366Y910300I-1115J1928D01*
G01X1368308Y910334D01*
G03X1366834I-737J-1277D01*
G02X1364666Y910300I-1115J1928D01*
G01X1364608Y910334D01*
G03X1363134I-737J-1277D01*
G02X1360948Y910310I-1114J1928D01*
G01X1360907Y910334D01*
G03X1359433I-737J-1277D01*
G02X1357249Y910310I-1113J1928D01*
G01X1357208Y910334D01*
G03X1355734I-737J-1277D01*
G02X1353566Y910300I-1115J1928D01*
G01X1353508Y910334D01*
G03X1352034I-737J-1277D01*
G02X1349866Y910300I-1115J1928D01*
G01X1349808Y910334D01*
G03X1348334I-737J-1277D01*
G02X1346108I-1113J1928D01*
G03X1344634I-737J-1277D01*
G02X1342466Y910300I-1115J1928D01*
G01X1342408Y910334D01*
G03X1340934I-737J-1277D01*
G02X1338766Y910300I-1115J1928D01*
G01X1338708Y910334D01*
G03X1337234I-737J-1277D01*
G02X1335048Y910310I-1114J1928D01*
G01X1335007Y910334D01*
G03X1333533I-737J-1277D01*
G02X1331349Y910310I-1113J1928D01*
G01X1331308Y910334D01*
G03X1329834I-737J-1277D01*
G02X1327666Y910300I-1115J1928D01*
G01X1327608Y910334D01*
G03X1326134I-737J-1277D01*
G02X1323966Y910300I-1115J1928D01*
G01X1323908Y910334D01*
G03X1322434I-737J-1277D01*
G02X1321321Y910036I-1113J1928D01*
G01X1315586D01*
X1315187Y910435D01*
X1313837D01*
G01X1379104Y1031727D02*
X1376947Y1030728D01*
G03X1376141Y1030450I309J-2205D01*
G02X1374667I-737J1277D01*
G03X1372441I-1113J-1927D01*
G02X1370967I-737J1277D01*
G01X1370909Y1030484D01*
G03X1368741Y1030450I-1054J-1961D01*
G02X1367267I-737J1277D01*
G01X1367209Y1030484D01*
G03X1365041Y1030450I-1054J-1961D01*
G02X1363567I-737J1277D01*
G01X1363526Y1030474D01*
G03X1361342Y1030450I-1071J-1951D01*
G02X1359868I-737J1277D01*
G01X1359827Y1030474D01*
G03X1357641Y1030450I-1072J-1951D01*
G02X1356167I-737J1277D01*
G01X1356109Y1030484D01*
G03X1353941Y1030450I-1054J-1961D01*
G02X1352467I-737J1277D01*
G01X1352409Y1030484D01*
G03X1350241Y1030450I-1054J-1961D01*
G02X1348767I-737J1277D01*
G03X1346541I-1113J-1927D01*
G02X1345067I-737J1277D01*
G01X1345009Y1030484D01*
G03X1342841Y1030450I-1054J-1961D01*
G02X1341367I-737J1277D01*
G01X1341309Y1030484D01*
G03X1339141Y1030450I-1054J-1961D01*
G02X1337667I-737J1277D01*
G01X1337626Y1030474D01*
G03X1335442Y1030450I-1071J-1951D01*
G02X1333968I-737J1277D01*
G03X1331741I-1114J-1929D01*
G01X1331391Y1030248D01*
G02X1330617I-387J670D01*
G01X1330268Y1030449D01*
G03X1328149Y1030448I-1059J-1837D01*
G01X1328048Y1030390D01*
G02X1326574I-737J1277D01*
G03X1324348I-1113J-1927D01*
G01X1324333Y1030382D01*
G02X1323581Y1030177I-765J1324D01*
G01X1320668Y1030155D01*
X1316878D01*
G01X1382804Y1050952D02*
X1380358Y1052011D01*
G02X1379899Y1052195I594J2146D01*
G01X1379841Y1052229D01*
G03X1378367I-737J-1277D01*
G01X1378253Y1052163D01*
X1378137Y1052113D01*
G02X1376199Y1052195I-884J2044D01*
G01X1376141Y1052229D01*
G03X1374667I-737J-1277D01*
G02X1372499Y1052195I-1115J1928D01*
G01X1372441Y1052229D01*
G03X1370967I-737J-1277D01*
G02X1368799Y1052195I-1115J1928D01*
G01X1368741Y1052229D01*
G03X1367267I-737J-1277D01*
G02X1365099Y1052195I-1115J1928D01*
G01X1365041Y1052229D01*
G03X1363567I-737J-1277D01*
G02X1361381Y1052205I-1114J1928D01*
G01X1361340Y1052229D01*
G03X1359866I-737J-1277D01*
G01X1359825Y1052205D01*
G02X1357641Y1052229I-1071J1952D01*
G03X1356167I-737J-1277D01*
G02X1353999Y1052195I-1115J1928D01*
G01X1353941Y1052229D01*
G03X1352467I-737J-1277D01*
G02X1350299Y1052195I-1115J1928D01*
G01X1350241Y1052229D01*
G03X1348767I-737J-1277D01*
G02X1346599Y1052195I-1115J1928D01*
G01X1346541Y1052229D01*
G03X1345067I-737J-1277D01*
G02X1342899Y1052195I-1115J1928D01*
G01X1342841Y1052229D01*
G03X1341367I-737J-1277D01*
G02X1339199Y1052195I-1115J1928D01*
G01X1339141Y1052229D01*
G03X1337667I-737J-1277D01*
G02X1335481Y1052205I-1114J1928D01*
G01X1335440Y1052229D01*
G03X1333966I-737J-1277D01*
G01X1333908Y1052195D01*
G02X1331740Y1052229I-1053J1962D01*
G03X1330266I-737J-1277D01*
G02X1328040I-1113J1928D01*
G03X1326566I-737J-1277D01*
G02X1324340I-1113J1928D01*
G03X1323603Y1052429I-742J-1276D01*
G01X1318858D01*
X1316827Y1050398D01*
X1311268D01*
G01X1386504Y1057361D02*
X1383541Y1056084D01*
X1383517Y1056070D01*
G03X1382428Y1054157I1136J-1913D01*
G02X1381725Y1052900I-1475J0D01*
G01X1381690Y1052880D01*
G02X1380216I-737J1277D01*
G01X1380158Y1052914D01*
G03X1377990Y1052880I-1053J-1962D01*
G01X1377896Y1052826D01*
X1377786Y1052783D01*
G02X1376516Y1052880I-534J1374D01*
G01X1376458Y1052914D01*
G03X1374290Y1052880I-1053J-1962D01*
G02X1372816I-737J1277D01*
G01X1372758Y1052914D01*
G03X1370590Y1052880I-1053J-1962D01*
G02X1369116I-737J1277D01*
G01X1369058Y1052914D01*
G03X1366890Y1052880I-1053J-1962D01*
G02X1365416I-737J1277D01*
G01X1365358Y1052914D01*
G03X1363190Y1052880I-1053J-1962D01*
G02X1361716I-737J1277D01*
G03X1359532Y1052904I-1113J-1928D01*
G01X1359491Y1052880D01*
G02X1358017I-737J1277D01*
G01X1357976Y1052904D01*
G03X1355790Y1052880I-1072J-1952D01*
G02X1354316I-737J1277D01*
G01X1354258Y1052914D01*
G03X1352090Y1052880I-1053J-1962D01*
G02X1350616I-737J1277D01*
G01X1350558Y1052914D01*
G03X1348390Y1052880I-1053J-1962D01*
G02X1346916I-737J1277D01*
G01X1346858Y1052914D01*
G03X1344690Y1052880I-1053J-1962D01*
G02X1343216I-737J1277D01*
G01X1343158Y1052914D01*
G03X1340990Y1052880I-1053J-1962D01*
G02X1339516I-737J1277D01*
G01X1339458Y1052914D01*
G03X1337290Y1052880I-1053J-1962D01*
G02X1335816I-737J1277D01*
G03X1333632Y1052904I-1113J-1928D01*
G01X1333591Y1052880D01*
G02X1332117I-737J1277D01*
G03X1329931Y1052904I-1114J-1928D01*
G01X1329890Y1052880D01*
G02X1328416I-737J1277D01*
G03X1326190I-1113J-1928D01*
G02X1324716I-737J1277D01*
G03X1323603Y1053178I-1113J-1928D01*
G01X1318547D01*
X1316516Y1051147D01*
X1311932D01*
X1311278Y1051801D01*
G01X1390204Y1044544D02*
X1388973D01*
X1388715Y1044802D01*
G03X1387616Y1046472I-2211J-258D01*
G01X1387558Y1046506D01*
G03X1385390Y1046472I-1053J-1962D01*
G03X1384279Y1044631I1114J-1928D01*
G01Y1044544D01*
G02X1383576Y1043287I-1475J0D01*
G01X1383541Y1043267D01*
X1383517Y1043253D01*
G03X1382428Y1041340I1136J-1913D01*
G01Y1040586D01*
X1381706Y1039864D01*
X1380953D01*
G02X1380216Y1040063I3J1475D01*
G01X1380158Y1040097D01*
G03X1377990Y1040063I-1054J-1961D01*
G02X1376516I-737J1277D01*
G03X1374290I-1113J-1927D01*
G02X1372816I-737J1277D01*
G01X1372758Y1040097D01*
G03X1370590Y1040063I-1054J-1961D01*
G02X1369116I-737J1277D01*
G01X1369058Y1040097D01*
G03X1366890Y1040063I-1054J-1961D01*
G02X1365416I-737J1277D01*
G01X1365375Y1040087D01*
G03X1363191Y1040063I-1071J-1951D01*
G02X1361717I-737J1277D01*
G01X1361676Y1040087D01*
G03X1359490Y1040063I-1072J-1951D01*
G02X1358016I-737J1277D01*
G01X1357958Y1040097D01*
G03X1355790Y1040063I-1054J-1961D01*
G02X1354316I-737J1277D01*
G01X1354258Y1040097D01*
G03X1352090Y1040063I-1054J-1961D01*
G02X1350616I-737J1277D01*
G03X1348390I-1113J-1927D01*
G02X1346916I-737J1277D01*
G01X1346858Y1040097D01*
G03X1344690Y1040063I-1054J-1961D01*
G02X1343216I-737J1277D01*
G01X1343158Y1040097D01*
G03X1340990Y1040063I-1054J-1961D01*
G02X1339516I-737J1277D01*
G01X1339475Y1040087D01*
G03X1337291Y1040063I-1071J-1951D01*
G02X1335817I-737J1277D01*
G01X1335776Y1040087D01*
G03X1333590Y1040063I-1072J-1951D01*
G02X1332116I-737J1277D01*
G03X1329890I-1113J-1927D01*
G02X1328416I-737J1277D01*
G03X1326190I-1113J-1927D01*
G02X1324716I-737J1277D01*
G03X1322490I-1113J-1927D01*
G02X1321753Y1039864I-740J1276D01*
G01X1320714D01*
X1320360Y1040218D01*
G01X1379104Y1076587D02*
G03X1377646Y1076192I-1J-2886D01*
G01X1376140Y1075310D01*
G02X1374666I-737J1277D01*
G03X1372482Y1075334I-1113J-1927D01*
G01X1372441Y1075310D01*
G02X1370967I-737J1277D01*
G03X1368799Y1075344I-1114J-1927D01*
G01X1368741Y1075310D01*
G02X1367267I-737J1277D01*
G03X1365099Y1075344I-1114J-1927D01*
G01X1365041Y1075310D01*
G02X1363567I-737J1277D01*
G03X1361399Y1075344I-1114J-1927D01*
G01X1361341Y1075310D01*
G02X1359867I-737J1277D01*
G03X1357641I-1113J-1927D01*
G02X1356167I-737J1277D01*
G03X1353999Y1075344I-1114J-1927D01*
G01X1353941Y1075310D01*
G02X1352467I-737J1277D01*
G03X1350281Y1075334I-1114J-1927D01*
G01X1350240Y1075310D01*
G02X1348766I-737J1277D01*
G03X1346582Y1075334I-1113J-1927D01*
G01X1346541Y1075310D01*
G02X1345067I-737J1277D01*
G03X1342899Y1075344I-1114J-1927D01*
G01X1342841Y1075310D01*
G02X1341367I-737J1277D01*
G03X1339199Y1075344I-1114J-1927D01*
G01X1339141Y1075310D01*
G02X1337667I-737J1277D01*
G03X1335499Y1075344I-1114J-1927D01*
G01X1335441Y1075310D01*
G02X1333967I-737J1277D01*
G01X1333926Y1075334D01*
G03X1331740Y1075310I-1072J-1951D01*
G02X1330266I-737J1277D01*
G03X1328040I-1113J-1927D01*
G02X1326566I-737J1277D01*
G01X1326508Y1075344D01*
G03X1324340Y1075310I-1054J-1961D01*
G02X1321777Y1074619I-2563J4407D01*
G01X1395753Y1079791D02*
X1396369Y1078724D01*
X1396286Y1078417D01*
G02X1395016Y1078514I-534J1374D01*
G01X1394958Y1078548D01*
G03X1392790Y1078514I-1054J-1961D01*
G02X1391316I-737J1277D01*
G01X1391258Y1078548D01*
G03X1389090Y1078514I-1054J-1961D01*
G02X1387616I-737J1277D01*
G01X1387558Y1078548D01*
G03X1385390Y1078514I-1054J-1961D01*
G02X1383916I-737J1277D01*
G01X1383881Y1078534D01*
G02X1383178Y1079791I772J1257D01*
G01Y1079852D01*
G03X1382067Y1081718I-2225J-61D01*
G03X1379899Y1081752I-1114J-1927D01*
G01X1379841Y1081718D01*
G02X1378367I-737J1277D01*
G03X1376199Y1081752I-1114J-1927D01*
G01X1376141Y1081718D01*
G02X1374667I-737J1277D01*
G03X1372499Y1081752I-1114J-1927D01*
G01X1372441Y1081718D01*
G02X1370967I-737J1277D01*
G03X1368799Y1081752I-1114J-1927D01*
G01X1368741Y1081718D01*
G02X1367267I-737J1277D01*
G03X1365081Y1081742I-1114J-1927D01*
G01X1365040Y1081718D01*
G02X1363566I-737J1277D01*
G03X1361382Y1081742I-1113J-1927D01*
G01X1361341Y1081718D01*
G02X1359867I-737J1277D01*
G03X1357699Y1081752I-1114J-1927D01*
G01X1357641Y1081718D01*
G02X1356167I-737J1277D01*
G03X1353999Y1081752I-1114J-1927D01*
G01X1353941Y1081718D01*
G02X1352467I-737J1277D01*
G03X1350299Y1081752I-1114J-1927D01*
G01X1350241Y1081718D01*
G02X1348767I-737J1277D01*
G03X1346599Y1081752I-1114J-1927D01*
G01X1346541Y1081718D01*
G02X1345067I-737J1277D01*
G03X1342899Y1081752I-1114J-1927D01*
G01X1342841Y1081718D01*
G02X1341367I-737J1277D01*
G03X1339181Y1081742I-1114J-1927D01*
G01X1339140Y1081718D01*
G02X1337666I-737J1277D01*
G01X1337625Y1081742D01*
G03X1335441Y1081718I-1071J-1951D01*
G02X1333967I-737J1277D01*
G03X1331781Y1081742I-1114J-1927D01*
G01X1331740Y1081718D01*
G02X1330266I-737J1277D01*
G03X1328040I-1113J-1927D01*
G02X1326566I-737J1277D01*
G03X1324340I-1113J-1927D01*
G02X1322866I-737J1277D01*
G03X1320640I-1113J-1927D01*
G01X1320639D01*
G02X1319165I-737J1277D01*
G01X1319107Y1081752D01*
G03X1316939Y1081718I-1054J-1961D01*
G01X1316904Y1081698D01*
G02X1314727Y1082995I-702J1297D01*
G01Y1085938D01*
X1314070Y1086595D01*
G01X1397604Y1070178D02*
X1398835D01*
X1399092Y1070435D01*
G02X1400190Y1072106I2212J-257D01*
G01X1400225Y1072126D01*
G03Y1074640I-772J1257D01*
G01X1400190Y1074660D01*
G02X1399079Y1076526I1114J1927D01*
G01Y1076587D01*
G03X1398376Y1077844I-1475J0D01*
G01X1398341Y1077864D01*
X1398317Y1077878D01*
G02X1397228Y1079791I1136J1913D01*
G03X1396525Y1081048I-1475J0D01*
G01X1396490Y1081068D01*
G03X1395016I-737J-1277D01*
G02X1392790I-1113J1927D01*
G03X1391316I-737J-1277D01*
G01X1391258Y1081034D01*
G02X1389090Y1081068I-1054J1961D01*
G02X1387979Y1082934I1114J1927D01*
G01Y1082995D01*
G03X1387276Y1084252I-1475J0D01*
G01X1387241Y1084272D01*
G03X1385767I-737J-1277D01*
G02X1383599Y1084238I-1115J1928D01*
G01X1383541Y1084272D01*
G03X1382067I-737J-1277D01*
G02X1379899Y1084238I-1115J1928D01*
G01X1379841Y1084272D01*
G03X1378367I-737J-1277D01*
G02X1376199Y1084238I-1115J1928D01*
G01X1376141Y1084272D01*
G03X1374667I-737J-1277D01*
G02X1372441I-1113J1928D01*
G03X1370967I-737J-1277D01*
G02X1368799Y1084238I-1115J1928D01*
G01X1368741Y1084272D01*
G03X1367267I-737J-1277D01*
G02X1365081Y1084248I-1114J1928D01*
G01X1365040Y1084272D01*
G03X1363566I-737J-1277D01*
G02X1361382Y1084248I-1113J1928D01*
G01X1361341Y1084272D01*
G03X1359867I-737J-1277D01*
G02X1357699Y1084238I-1115J1928D01*
G01X1357641Y1084272D01*
G03X1356167I-737J-1277D01*
G02X1353999Y1084238I-1115J1928D01*
G01X1353941Y1084272D01*
G03X1352467I-737J-1277D01*
G02X1350299Y1084238I-1115J1928D01*
G01X1350241Y1084272D01*
G03X1348767I-737J-1277D01*
G02X1346541I-1113J1928D01*
G03X1345067I-737J-1277D01*
G02X1342899Y1084238I-1115J1928D01*
G01X1342841Y1084272D01*
G03X1341367I-737J-1277D01*
G02X1339181Y1084248I-1114J1928D01*
G01X1339140Y1084272D01*
G03X1337666I-737J-1277D01*
G02X1335482Y1084248I-1113J1928D01*
G01X1335441Y1084272D01*
G03X1333967I-737J-1277D01*
G02X1331781Y1084248I-1114J1928D01*
G01X1331740Y1084272D01*
G03X1330266I-737J-1277D01*
G02X1328040I-1113J1928D01*
G03X1326566I-737J-1277D01*
G02X1324340I-1113J1928D01*
G03X1322866I-737J-1277D01*
G02X1320177Y1084625I-1115J1928D01*
G01X1314103Y1090699D01*
X1310353D01*
X1309466Y1091586D01*
G01X1401304Y1070178D02*
X1400073D01*
X1399847Y1070404D01*
G02X1400532Y1071435I1458J-225D01*
G01X1400567Y1071455D01*
G03X1401678Y1073296I-1114J1928D01*
G01Y1073444D01*
G03X1400567Y1075310I-2225J-61D01*
G01X1400532Y1075330D01*
G02X1399829Y1076587I772J1257D01*
G03X1398740Y1078500I-2225J0D01*
G01X1398716Y1078514D01*
X1398681Y1078534D01*
G02X1397978Y1079791I772J1257D01*
G01Y1079852D01*
G03X1396867Y1081718I-2225J-61D01*
G03X1394681Y1081742I-1114J-1927D01*
G01X1394640Y1081718D01*
G02X1393166I-737J1277D01*
G03X1390982Y1081742I-1113J-1927D01*
G01X1390941Y1081718D01*
G02X1389467I-737J1277D01*
G01X1389432Y1081738D01*
G02X1388729Y1082995I772J1257D01*
G01Y1083051D01*
G03X1387616Y1084923I-2225J-56D01*
G01X1387558Y1084957D01*
G03X1385390Y1084923I-1053J-1962D01*
G02X1383916I-737J1277D01*
G01X1383858Y1084957D01*
G03X1381690Y1084923I-1053J-1962D01*
G02X1380216I-737J1277D01*
G01X1380158Y1084957D01*
G03X1377990Y1084923I-1053J-1962D01*
G02X1376516I-737J1277D01*
G01X1376475Y1084947D01*
G03X1374291Y1084923I-1071J-1952D01*
G02X1372817I-737J1277D01*
G01X1372776Y1084947D01*
G03X1370590Y1084923I-1072J-1952D01*
G02X1369116I-737J1277D01*
G01X1369058Y1084957D01*
G03X1366890Y1084923I-1053J-1962D01*
G02X1365416I-737J1277D01*
G03X1363190I-1113J-1928D01*
G02X1361716I-737J1277D01*
G01X1361658Y1084957D01*
G03X1359490Y1084923I-1053J-1962D01*
G02X1358016I-737J1277D01*
G01X1357958Y1084957D01*
G03X1355790Y1084923I-1053J-1962D01*
G02X1354316I-737J1277D01*
G01X1354258Y1084957D01*
G03X1352090Y1084923I-1053J-1962D01*
G02X1350616I-737J1277D01*
G01X1350575Y1084947D01*
G03X1348391Y1084923I-1071J-1952D01*
G02X1346917I-737J1277D01*
G01X1346876Y1084947D01*
G03X1344690Y1084923I-1072J-1952D01*
G02X1343216I-737J1277D01*
G01X1343158Y1084957D01*
G03X1340990Y1084923I-1053J-1962D01*
G02X1339516I-737J1277D01*
G03X1337290I-1113J-1928D01*
G02X1335816I-737J1277D01*
G01X1335758Y1084957D01*
G03X1333590Y1084923I-1053J-1962D01*
G02X1332116I-737J1277D01*
G03X1329890I-1113J-1928D01*
G02X1328416I-737J1277D01*
G03X1326190I-1113J-1928D01*
G02X1324716I-737J1277D01*
G01X1324675Y1084947D01*
G03X1322489Y1084923I-1072J-1952D01*
G02X1321015I-737J1277D01*
G02X1320707Y1085155I726J1285D01*
G01X1314414Y1091448D01*
X1311701D01*
X1309985Y1093164D01*
G01X1309832Y172249D02*
X1307969Y169777D01*
X1307904Y169662D01*
G02X1306653Y168924I-1278J737D01*
G01X1306622D01*
G03X1304694Y167812I-2J-2223D01*
G03Y165586I1928J-1113D01*
G01X1304729Y165525D01*
G02X1304696Y164112I-1312J-676D01*
G02X1303419Y163374I-1277J736D01*
G01X1303416D01*
G03X1301490Y162262I0J-2224D01*
G01X1301051Y161492D01*
X1300315Y160941D01*
X1299610Y160739D01*
X1299311Y160537D01*
X1299029Y160197D01*
X1298867Y159914D01*
X1298664Y159396D01*
X1298592Y157534D01*
X1298270Y156522D01*
X1298252Y156465D01*
X1297086Y153810D01*
G01X1300213Y162999D02*
X1298770Y161613D01*
X1298352Y160527D01*
X1298287Y160412D01*
G02X1297011Y159675I-1277J737D01*
G01X1297009Y159674D01*
G02X1295922Y160151I-1J1474D01*
G01X1295661Y160412D01*
X1295614D01*
X1295252Y160774D01*
X1293005D01*
X1292304Y160073D01*
Y157842D01*
G01X1300212Y170399D02*
X1298402Y167998D01*
X1298350Y167912D01*
X1298288Y167811D01*
Y167810D01*
G02X1297011Y167074I-1276J737D01*
G01X1296938Y167075D01*
G03X1295079Y165962I70J-2225D01*
G01X1295059Y165927D01*
G02X1293802Y165224I-1257J772D01*
G01X1292684D01*
X1292056Y165852D01*
X1290882D01*
X1288758Y163728D01*
G01X1397171Y909057D02*
X1395166Y907616D01*
G02X1394584Y907130I-1696J1440D01*
G01X1394549Y907110D01*
G03X1393846Y905853I772J-1257D01*
G02X1390566Y903892I-2226J0D01*
G01X1390508Y903926D01*
G03X1388296Y902649I-737J-1277D01*
G02X1387207Y900736I-2225J0D01*
G01X1387148Y900702D01*
G03X1386445Y899445I772J-1257D01*
G01Y899358D01*
G02X1385334Y897517I-2225J87D01*
G01X1385299Y897497D01*
G03X1384596Y896240I772J-1257D01*
G01Y896201D01*
G02X1383484Y894313I-2225J39D01*
G01X1383449Y894293D01*
G03X1382746Y893036I772J-1257D01*
G02X1381658Y891123I-2226J0D01*
G01X1381599Y891089D01*
G03X1380896Y889832I772J-1257D01*
G01Y889776D01*
G02X1377557Y887904I-2226J56D01*
G03X1376083I-737J-1277D01*
G01X1376025Y887870D01*
G02X1373857Y887904I-1053J1962D01*
G03X1372383I-737J-1277D01*
G01X1372325Y887870D01*
G02X1370157Y887904I-1053J1962D01*
G03X1368683I-737J-1277D01*
G01X1368625Y887870D01*
G02X1366457Y887904I-1053J1962D01*
G03X1364983I-737J-1277D01*
G01X1364925Y887870D01*
G02X1362757Y887904I-1053J1962D01*
G03X1361283I-737J-1277D01*
G01X1361225Y887870D01*
G02X1359057Y887904I-1053J1962D01*
G03X1357583I-737J-1277D01*
G01X1357525Y887870D01*
G02X1355357Y887904I-1053J1962D01*
G03X1353883I-737J-1277D01*
G01X1353825Y887870D01*
G02X1351657Y887904I-1053J1962D01*
G03X1350183I-737J-1277D01*
G01X1350125Y887870D01*
G02X1347957Y887904I-1053J1962D01*
G03X1346483I-737J-1277D01*
G01X1346425Y887870D01*
G02X1344257Y887904I-1053J1962D01*
G03X1342783I-737J-1277D01*
G01X1342725Y887870D01*
G02X1340557Y887904I-1053J1962D01*
G03X1339083I-737J-1277D01*
G01X1339025Y887870D01*
G02X1336857Y887904I-1053J1962D01*
G03X1335383I-737J-1277D01*
G02X1333157I-1113J1928D01*
G03X1331683I-737J-1277D01*
G01X1331625Y887870D01*
G02X1329457Y887904I-1053J1962D01*
G03X1327983I-737J-1277D01*
G01X1327942Y887880D01*
G02X1325758Y887904I-1071J1952D01*
G03X1324284I-737J-1277D01*
G01X1324249Y887884D01*
G03X1323546Y886627I772J-1257D01*
G01Y886588D01*
G02X1322434Y884700I-2225J39D01*
G02X1320208I-1113J1927D01*
G03X1318734I-737J-1277D01*
G02X1316508I-1113J1927D01*
G03X1315034I-737J-1277D01*
G01X1314993Y884676D01*
G02X1312807Y884700I-1072J1951D01*
G03X1311333I-737J-1277D01*
G02X1310221Y884402I-1112J1926D01*
G01X1308826D01*
X1307538Y883114D01*
G01X1308414Y879764D02*
Y880564D01*
X1309545Y881695D01*
X1310221D01*
G02X1310958Y881496I-3J-1475D01*
G01X1311016Y881462D01*
G03X1313184Y881496I1054J1961D01*
G02X1314658I737J-1277D01*
G03X1316884I1113J1927D01*
G02X1318358I737J-1277D01*
G03X1320584I1113J1927D01*
G02X1322058I737J-1277D01*
G03X1324242Y881472I1113J1927D01*
G01X1324283Y881496D01*
G02X1325757I737J-1277D01*
G03X1327985I1114J1927D01*
G03X1329096Y883362I-1114J1927D01*
G01Y883423D01*
G02X1329799Y884680I1475J0D01*
G01X1329834Y884700D01*
G02X1331308I737J-1277D01*
G01X1331343Y884680D01*
G02X1332046Y883423I-772J-1257D01*
G01Y883362D01*
G03X1333157Y881496I2225J61D01*
G03X1335343Y881472I1114J1927D01*
G01X1335384Y881496D01*
G03X1336496Y883384I-1113J1927D01*
G01Y883423D01*
G02X1337199Y884680I1475J0D01*
G01X1337234Y884700D01*
G02X1338708I737J-1277D01*
G01X1338743Y884680D01*
G02X1339446Y883423I-772J-1257D01*
G01Y883362D01*
G03X1340557Y881496I2225J61D01*
G03X1342743Y881472I1114J1927D01*
G01X1342784Y881496D01*
G03X1343896Y883384I-1113J1927D01*
G01Y883423D01*
G02X1344599Y884680I1475J0D01*
G01X1344634Y884700D01*
G02X1346108I737J-1277D01*
G01X1346143Y884680D01*
G02X1346846Y883423I-772J-1257D01*
G01Y883362D01*
G03X1347957Y881496I2225J61D01*
G03X1350143Y881472I1114J1927D01*
G01X1350184Y881496D01*
G03X1351296Y883384I-1113J1927D01*
G01Y883423D01*
G02X1351999Y884680I1475J0D01*
G01X1352034Y884700D01*
G02X1353508I737J-1277D01*
G01X1353543Y884680D01*
G02X1354246Y883423I-772J-1257D01*
G01Y883362D01*
G03X1355357Y881496I2225J61D01*
G03X1357543Y881472I1114J1927D01*
G01X1357584Y881496D01*
G03X1358696Y883384I-1113J1927D01*
G01Y883423D01*
G02X1359399Y884680I1475J0D01*
G01X1359434Y884700D01*
G02X1360908I737J-1277D01*
G01X1360943Y884680D01*
G02X1361646Y883423I-772J-1257D01*
G01Y883362D01*
G03X1362757Y881496I2225J61D01*
G03X1364943Y881472I1114J1927D01*
G01X1364984Y881496D01*
G03X1366096Y883384I-1113J1927D01*
G01Y883423D01*
G02X1366799Y884680I1475J0D01*
G01X1366834Y884700D01*
G02X1368308I737J-1277D01*
G01X1368343Y884680D01*
G02X1369046Y883423I-772J-1257D01*
G01Y883362D01*
G03X1370157Y881496I2225J61D01*
G03X1372343Y881472I1114J1927D01*
G01X1372384Y881496D01*
G03X1373496Y883384I-1113J1927D01*
G01Y883423D01*
G02X1374199Y884680I1475J0D01*
G01X1374234Y884700D01*
G02X1375708I737J-1277D01*
G01X1375743Y884680D01*
G02X1376446Y883423I-772J-1257D01*
G01Y883362D01*
G03X1377557Y881496I2225J61D01*
G03X1379743Y881472I1114J1927D01*
G01X1379784Y881496D01*
G03X1380896Y883384I-1113J1927D01*
G01Y883423D01*
G02X1381599Y884680I1475J0D01*
G01X1381634Y884700D01*
G03X1382745Y886566I-1114J1927D01*
G01Y886627D01*
G02X1383448Y887884I1475J0D01*
G01X1383483Y887904D01*
G03X1384596Y889776I-1112J1928D01*
G01Y889832D01*
G02X1385299Y891089I1475J0D01*
G01X1385334Y891109D01*
G03X1386446Y892997I-1113J1927D01*
G01Y893036D01*
G02X1387149Y894293I1475J0D01*
G01X1387184Y894313D01*
G03X1388296Y896201I-1113J1927D01*
G01Y896240D01*
G02X1388999Y897497I1475J0D01*
G01X1389034Y897517D01*
G02X1390508I737J-1277D01*
G01X1390566Y897483D01*
G03X1392734Y897517I1053J1962D01*
G03X1393845Y899358I-1114J1928D01*
G01Y899445D01*
G02X1394548Y900702I1475J0D01*
G01X1394583Y900722D01*
X1394607Y900736D01*
G03X1395696Y902649I-1136J1913D01*
G02X1396399Y903906I1475J0D01*
G01X1396434Y903926D01*
G03X1397546Y905814I-1113J1927D01*
G01Y905887D01*
G02X1398283Y907130I1474J-34D01*
G03X1399395Y908996I-1112J1927D01*
G01Y909091D01*
G02X1401606Y910334I1474J-34D01*
G03X1404945Y912175I1114J1928D01*
G01Y912262D01*
G02X1405648Y913519I1475J0D01*
G01X1405707Y913553D01*
G03X1406796Y915466I-1136J1913D01*
G02X1407499Y916723I1475J0D01*
G01X1407558Y916757D01*
G03X1408646Y918670I-1138J1913D01*
G02X1410654Y920044I1474J0D01*
G01X1411467Y919725D01*
X1411967Y919225D01*
Y915470D01*
X1411971Y915466D01*
G01X1310512Y877915D02*
X1311840Y879243D01*
X1312167D01*
G02X1313066Y879011I-96J-2229D01*
G01X1313184Y878942D01*
G03X1314658I737J1277D01*
G02X1316884I1113J-1928D01*
G03X1318358I737J1277D01*
G02X1320584I1113J-1928D01*
G03X1322058I737J1277D01*
G02X1324226Y878976I1115J-1928D01*
G01X1324317Y878923D01*
G03X1325757Y878942I703J1296D01*
G02X1327943Y878966I1114J-1928D01*
G01X1327984Y878942D01*
G03X1329458I737J1277D01*
G02X1331642Y878966I1113J-1928D01*
G01X1331683Y878942D01*
G03X1333157I737J1277D01*
G02X1335343Y878966I1114J-1928D01*
G01X1335384Y878942D01*
G03X1336858I737J1277D01*
G02X1339042Y878966I1113J-1928D01*
G01X1339083Y878942D01*
G03X1340557I737J1277D01*
G02X1342743Y878966I1114J-1928D01*
G01X1342784Y878942D01*
G03X1344258I737J1277D01*
G02X1346442Y878966I1113J-1928D01*
G01X1346483Y878942D01*
G03X1347957I737J1277D01*
G02X1350143Y878966I1114J-1928D01*
G01X1350184Y878942D01*
G03X1351658I737J1277D01*
G02X1353842Y878966I1113J-1928D01*
G01X1353883Y878942D01*
G03X1355357I737J1277D01*
G02X1357543Y878966I1114J-1928D01*
G01X1357584Y878942D01*
G03X1359058I737J1277D01*
G02X1361242Y878966I1113J-1928D01*
G01X1361283Y878942D01*
G03X1362757I737J1277D01*
G02X1364943Y878966I1114J-1928D01*
G01X1364984Y878942D01*
G03X1366458I737J1277D01*
G02X1368642Y878966I1113J-1928D01*
G01X1368683Y878942D01*
G03X1370157I737J1277D01*
G02X1372343Y878966I1114J-1928D01*
G01X1372384Y878942D01*
G03X1373858I737J1277D01*
G02X1376042Y878966I1113J-1928D01*
G01X1376083Y878942D01*
G03X1377557I737J1277D01*
G02X1379743Y878966I1114J-1928D01*
G01X1379784Y878942D01*
G03X1381258I737J1277D01*
G02X1383442Y878966I1113J-1928D01*
G01X1383483Y878942D01*
G03X1385695Y880219I737J1277D01*
G02X1386760Y882118I2226J0D01*
G01X1386843Y882166D01*
G03X1387546Y883423I-772J1257D01*
G01Y883484D01*
G02X1388657Y885350I2225J-61D01*
G01X1388692Y885370D01*
G03X1389395Y886627I-772J1257D01*
G01Y886683D01*
G02X1390508Y888555I2225J-56D01*
G01X1390543Y888575D01*
G03X1391246Y889832I-772J1257D01*
G01Y889893D01*
G02X1392357Y891759I2225J-61D01*
G01X1392392Y891779D01*
G03X1393095Y893036I-772J1257D01*
G02X1394160Y894935I2226J0D01*
G01X1394243Y894983D01*
G03X1394946Y896240I-772J1257D01*
G01Y896327D01*
G02X1396057Y898168I2225J-87D01*
G01X1396092Y898188D01*
G03X1396795Y899445I-772J1257D01*
G02X1397884Y901358I2225J0D01*
G01X1397943Y901392D01*
G03X1398646Y902649I-772J1257D01*
G01Y902710D01*
G02X1399757Y904576I2225J-61D01*
G01X1399792Y904596D01*
G03X1400495Y905853I-772J1257D01*
G01Y905914D01*
G02X1403834Y907780I2225J-61D01*
G03X1406045Y909023I737J1277D01*
G01Y909144D01*
G02X1407157Y910985I2224J-87D01*
G01X1407192Y911005D01*
G03X1407895Y912262I-772J1257D01*
G01Y912503D01*
X1410121Y914729D01*
Y918670D01*
G01X1411971Y921875D02*
X1411355Y920808D01*
X1411004Y920714D01*
G03X1407895Y918700I-883J-2044D01*
G01Y918670D01*
G02X1407192Y917413I-1475J0D01*
G01X1407157Y917393D01*
G03X1406046Y915527I1114J-1927D01*
G01Y915466D01*
G02X1405343Y914209I-1475J0D01*
G01X1405284Y914175D01*
G03X1404195Y912262I1136J-1913D01*
G02X1401983Y910985I-1475J0D01*
G03X1398645Y909144I-1114J-1927D01*
G01Y909023D01*
G02X1397908Y907780I-1474J34D01*
G01X1397884Y907766D01*
G03X1396795Y905853I1136J-1913D01*
G01Y905819D01*
G02X1396058Y904576I-1474J34D01*
G03X1394946Y902688I1113J-1927D01*
G01Y902649D01*
G02X1394243Y901392I-1475J0D01*
G01X1394208Y901372D01*
X1394184Y901358D01*
G03X1393095Y899445I1136J-1913D01*
G02X1392392Y898188I-1475J0D01*
G01X1392357Y898168D01*
G02X1390883I-737J1277D01*
G01X1390825Y898202D01*
G03X1388657Y898168I-1053J-1962D01*
G03X1387546Y896327I1114J-1928D01*
G01Y896240D01*
G02X1386843Y894983I-1475J0D01*
G01X1386808Y894963D01*
G03X1385696Y893075I1113J-1927D01*
G01Y893036D01*
G02X1384993Y891779I-1475J0D01*
G01X1384958Y891759D01*
G03X1383846Y889871I1113J-1927D01*
G01Y889832D01*
G02X1383143Y888575I-1475J0D01*
G01X1383108Y888555D01*
G03X1381995Y886683I1112J-1928D01*
G01Y886627D01*
G02X1381292Y885370I-1475J0D01*
G01X1381257Y885350D01*
G03X1380146Y883484I1114J-1927D01*
G01Y883423D01*
G02X1379443Y882166I-1475J0D01*
G01X1379408Y882146D01*
G02X1377934I-737J1277D01*
G01X1377899Y882166D01*
G02X1377196Y883423I772J1257D01*
G03X1376107Y885336I-2225J0D01*
G01X1376083Y885350D01*
X1376025Y885384D01*
G03X1373857Y885350I-1054J-1961D01*
G03X1372746Y883484I1114J-1927D01*
G01Y883423D01*
G02X1372043Y882166I-1475J0D01*
G01X1372008Y882146D01*
G02X1370534I-737J1277D01*
G01X1370499Y882166D01*
G02X1369796Y883423I772J1257D01*
G03X1368707Y885336I-2225J0D01*
G01X1368683Y885350D01*
X1368625Y885384D01*
G03X1366457Y885350I-1054J-1961D01*
G03X1365346Y883484I1114J-1927D01*
G01Y883423D01*
G02X1364643Y882166I-1475J0D01*
G01X1364608Y882146D01*
G02X1363134I-737J1277D01*
G01X1363099Y882166D01*
G02X1362396Y883423I772J1257D01*
G03X1361307Y885336I-2225J0D01*
G01X1361283Y885350D01*
X1361225Y885384D01*
G03X1359057Y885350I-1054J-1961D01*
G03X1357946Y883484I1114J-1927D01*
G01Y883423D01*
G02X1357243Y882166I-1475J0D01*
G01X1357208Y882146D01*
G02X1355734I-737J1277D01*
G01X1355699Y882166D01*
G02X1354996Y883423I772J1257D01*
G03X1353907Y885336I-2225J0D01*
G01X1353883Y885350D01*
X1353825Y885384D01*
G03X1351657Y885350I-1054J-1961D01*
G03X1350546Y883484I1114J-1927D01*
G01Y883423D01*
G02X1349843Y882166I-1475J0D01*
G01X1349808Y882146D01*
G02X1348334I-737J1277D01*
G01X1348299Y882166D01*
G02X1347596Y883423I772J1257D01*
G03X1346507Y885336I-2225J0D01*
G01X1346483Y885350D01*
X1346425Y885384D01*
G03X1344257Y885350I-1054J-1961D01*
G03X1343146Y883484I1114J-1927D01*
G01Y883423D01*
G02X1342443Y882166I-1475J0D01*
G01X1342408Y882146D01*
G02X1340934I-737J1277D01*
G01X1340899Y882166D01*
G02X1340196Y883423I772J1257D01*
G03X1339107Y885336I-2225J0D01*
G01X1339083Y885350D01*
X1339025Y885384D01*
G03X1336857Y885350I-1054J-1961D01*
G03X1335746Y883484I1114J-1927D01*
G01Y883423D01*
G02X1335043Y882166I-1475J0D01*
G01X1335008Y882146D01*
G02X1333534I-737J1277D01*
G01X1333499Y882166D01*
G02X1332796Y883423I772J1257D01*
G03X1331707Y885336I-2225J0D01*
G01X1331683Y885350D01*
X1331625Y885384D01*
G03X1329457Y885350I-1054J-1961D01*
G03X1328346Y883484I1114J-1927D01*
G01Y883423D01*
G02X1327643Y882166I-1475J0D01*
G01X1327608Y882146D01*
G02X1326134I-737J1277D01*
G03X1323966Y882180I-1114J-1927D01*
G01X1323908Y882146D01*
G02X1322434I-737J1277D01*
G03X1320208I-1113J-1927D01*
G02X1318734I-737J1277D01*
G03X1316508I-1113J-1927D01*
G02X1315034I-737J1277D01*
G01X1314993Y882170D01*
G03X1312807Y882146I-1072J-1951D01*
G02X1311333I-737J1277D01*
G03X1310365Y882440I-1114J-1926D01*
G03X1310222Y882444I-134J-2221D01*
G01X1309234D01*
X1307134Y880344D01*
G01X1402720Y918670D02*
X1402710Y918667D01*
X1398911Y920655D01*
G03X1397966Y920632I-452J-864D01*
G01X1397908Y920598D01*
G02X1396434I-737J1277D01*
G03X1394266Y920632I-1115J-1928D01*
G01X1394208Y920598D01*
G02X1392734I-737J1277D01*
G03X1390566Y920632I-1115J-1928D01*
G01X1390508Y920598D01*
G02X1389034I-737J1277D01*
G03X1386866Y920632I-1115J-1928D01*
G01X1386808Y920598D01*
G02X1385334I-737J1277D01*
G03X1383166Y920632I-1115J-1928D01*
G01X1383108Y920598D01*
G02X1381634I-737J1277D01*
G03X1379466Y920632I-1115J-1928D01*
G01X1379408Y920598D01*
G02X1377934I-737J1277D01*
G03X1375748Y920622I-1114J-1928D01*
G01X1375707Y920598D01*
G02X1374233I-737J1277D01*
G03X1372049Y920622I-1113J-1928D01*
G01X1372008Y920598D01*
G02X1370534I-737J1277D01*
G03X1368366Y920632I-1115J-1928D01*
G01X1368308Y920598D01*
G02X1366834I-737J1277D01*
G03X1364666Y920632I-1115J-1928D01*
G01X1364608Y920598D01*
G02X1363134I-737J1277D01*
G03X1360908I-1113J-1928D01*
G02X1359434I-737J1277D01*
G03X1357266Y920632I-1115J-1928D01*
G01X1357208Y920598D01*
G02X1355734I-737J1277D01*
G03X1353566Y920632I-1115J-1928D01*
G01X1353508Y920598D01*
G02X1352034I-737J1277D01*
G03X1349848Y920622I-1114J-1928D01*
G01X1349807Y920598D01*
G02X1348333I-737J1277D01*
G03X1346149Y920622I-1113J-1928D01*
G01X1346108Y920598D01*
G02X1344634I-737J1277D01*
G03X1342466Y920632I-1115J-1928D01*
G01X1342408Y920598D01*
G02X1340934I-737J1277D01*
G03X1338766Y920632I-1115J-1928D01*
G01X1338708Y920598D01*
G02X1337234I-737J1277D01*
G03X1335008I-1113J-1928D01*
G02X1333534I-737J1277D01*
G03X1331366Y920632I-1115J-1928D01*
G01X1331308Y920598D01*
G02X1329834I-737J1277D01*
G03X1327666Y920632I-1115J-1928D01*
G01X1327608Y920598D01*
G02X1326134I-737J1277D01*
G03X1323966Y920632I-1115J-1928D01*
G01X1323908Y920598D01*
G02X1322434I-737J1277D01*
G03X1319346Y921425I-3088J-5351D01*
G01X1314342D01*
G02X1314026Y921556I0J446D01*
G01X1313377Y922205D01*
G01X1393471Y915466D02*
X1391248Y916475D01*
G02X1390566Y916709I372J2195D01*
G01X1390508Y916743D01*
G03X1389034I-737J-1277D01*
G02X1386866Y916709I-1114J1927D01*
G01X1386808Y916743D01*
G03X1385334I-737J-1277D01*
G02X1383166Y916709I-1114J1927D01*
G01X1383108Y916743D01*
G03X1381634I-737J-1277D01*
G02X1379466Y916709I-1114J1927D01*
G01X1379408Y916743D01*
G03X1377934I-737J-1277D01*
G02X1375766Y916709I-1114J1927D01*
G01X1375708Y916743D01*
G03X1374234I-737J-1277D01*
G02X1372066Y916709I-1114J1927D01*
G01X1372008Y916743D01*
G03X1370534I-737J-1277D01*
G02X1368366Y916709I-1114J1927D01*
G01X1368308Y916743D01*
G03X1366834I-737J-1277D01*
G02X1364648Y916719I-1114J1927D01*
G01X1364607Y916743D01*
G03X1363133I-737J-1277D01*
G01X1363092Y916719D01*
G02X1360908Y916743I-1071J1951D01*
G03X1359434I-737J-1277D01*
G02X1357266Y916709I-1114J1927D01*
G01X1357208Y916743D01*
G03X1355734I-737J-1277D01*
G02X1353566Y916709I-1114J1927D01*
G01X1353508Y916743D01*
G03X1352034I-737J-1277D01*
G02X1349866Y916709I-1114J1927D01*
G01X1349808Y916743D01*
G03X1348334I-737J-1277D01*
G02X1346166Y916709I-1114J1927D01*
G01X1346108Y916743D01*
G03X1344634I-737J-1277D01*
G02X1342466Y916709I-1114J1927D01*
G01X1342408Y916743D01*
G03X1340934I-737J-1277D01*
G02X1338748Y916719I-1114J1927D01*
G01X1338707Y916743D01*
G03X1337233I-737J-1277D01*
G01X1337192Y916719D01*
G02X1335008Y916743I-1071J1951D01*
G03X1333534I-737J-1277D01*
G02X1331366Y916709I-1114J1927D01*
G01X1331308Y916743D01*
G03X1329834I-737J-1277D01*
G02X1327666Y916709I-1114J1927D01*
G01X1327608Y916743D01*
G03X1326134I-737J-1277D01*
G02X1323966Y916709I-1114J1927D01*
G01X1323908Y916743D01*
G03X1322434I-737J-1277D01*
G02X1320208I-1113J1927D01*
G03X1319471Y916942I-740J-1276D01*
G01X1319137D01*
X1317965Y918114D01*
X1306092D01*
X1305421Y918785D01*
G01X1403153Y1047749D02*
X1403131Y1047752D01*
X1400569Y1045823D01*
X1400567Y1045821D01*
X1400532Y1045801D01*
G03X1399829Y1044544I772J-1257D01*
G01Y1044505D01*
G02X1398717Y1042617I-2225J39D01*
G01X1398716D01*
G02X1398019Y1042393I-1112J2262D01*
G01X1397876Y1042250D01*
Y1040409D01*
X1396603Y1039136D01*
G01X1388353Y1054157D02*
X1388969Y1055224D01*
X1388886Y1055531D01*
G03X1387616Y1055434I-534J-1374D01*
G01X1387581Y1055414D01*
G03X1386878Y1054157I772J-1257D01*
G01Y1054084D01*
G02X1385766Y1052229I-2225J73D01*
G03X1385029Y1050986I737J-1277D01*
G01Y1050952D01*
G02X1383940Y1049039I-2225J0D01*
G01X1383916Y1049025D01*
X1383881Y1049005D01*
G03X1383178Y1047748I772J-1257D01*
G01Y1047687D01*
G02X1382067Y1045821I-2225J61D01*
G01X1382032Y1045801D01*
G03X1381329Y1044544I772J-1257D01*
G02X1380240Y1042631I-2225J0D01*
G01X1380216Y1042617D01*
X1380158Y1042583D01*
G02X1377990Y1042617I-1054J1961D01*
G03X1376516I-737J-1277D01*
G01X1376458Y1042583D01*
G02X1374290Y1042617I-1054J1961D01*
G03X1372816I-737J-1277D01*
G01X1372758Y1042583D01*
G02X1370590Y1042617I-1054J1961D01*
G03X1369116I-737J-1277D01*
G01X1369058Y1042583D01*
G02X1366890Y1042617I-1054J1961D01*
G03X1365416I-737J-1277D01*
G02X1363232Y1042593I-1113J1927D01*
G01X1363191Y1042617D01*
G03X1361717I-737J-1277D01*
G01X1361676Y1042593D01*
G02X1359490Y1042617I-1072J1951D01*
G03X1358016I-737J-1277D01*
G01X1357958Y1042583D01*
G02X1355790Y1042617I-1054J1961D01*
G03X1354316I-737J-1277D01*
G01X1354258Y1042583D01*
G02X1352090Y1042617I-1054J1961D01*
G03X1350616I-737J-1277D01*
G01X1350558Y1042583D01*
G02X1348390Y1042617I-1054J1961D01*
G03X1346916I-737J-1277D01*
G01X1346858Y1042583D01*
G02X1344690Y1042617I-1054J1961D01*
G03X1343216I-737J-1277D01*
G01X1343158Y1042583D01*
G02X1340990Y1042617I-1054J1961D01*
G03X1339516I-737J-1277D01*
G02X1337332Y1042593I-1113J1927D01*
G01X1337291Y1042617D01*
G03X1335817I-737J-1277D01*
G01X1335776Y1042593D01*
G02X1333590Y1042617I-1072J1951D01*
G03X1332116I-737J-1277D01*
G02X1329890I-1113J1927D01*
G03X1328416I-737J-1277D01*
G02X1326190I-1113J1927D01*
G03X1324716I-737J-1277D01*
G02X1322490I-1113J1927D01*
G02X1321378Y1044505I1113J1927D01*
G01Y1044544D01*
G03X1320675Y1045801I-1475J0D01*
G01X1320640Y1045821D01*
G03X1319903Y1046021I-742J-1276D01*
G01X1318648D01*
G01X1390204Y1057361D02*
X1389588Y1056294D01*
X1389237Y1056200D01*
G03X1387299Y1056118I-884J-2043D01*
G01X1387241Y1056084D01*
X1387217Y1056070D01*
G03X1386128Y1054157I1136J-1913D01*
G02X1385425Y1052900I-1475J0D01*
G01X1385390Y1052880D01*
G03X1384278Y1051025I1113J-1928D01*
G01Y1050918D01*
G02X1383541Y1049675I-1474J34D01*
G01X1383517Y1049661D01*
G03X1382428Y1047748I1136J-1913D01*
G02X1381725Y1046491I-1475J0D01*
G01X1381690Y1046471D01*
G03X1380579Y1044605I1114J-1927D01*
G01Y1044544D01*
G02X1378367Y1043267I-1475J0D01*
G03X1376199Y1043301I-1114J-1927D01*
G01X1376141Y1043267D01*
G02X1374667I-737J1277D01*
G03X1372499Y1043301I-1114J-1927D01*
G01X1372441Y1043267D01*
G02X1370967I-737J1277D01*
G03X1368799Y1043301I-1114J-1927D01*
G01X1368741Y1043267D01*
G02X1367267I-737J1277D01*
G03X1365081Y1043291I-1114J-1927D01*
G01X1365040Y1043267D01*
G02X1363566I-737J1277D01*
G01X1363525Y1043291D01*
G03X1361341Y1043267I-1071J-1951D01*
G02X1359867I-737J1277D01*
G03X1357699Y1043301I-1114J-1927D01*
G01X1357641Y1043267D01*
G02X1356167I-737J1277D01*
G03X1353999Y1043301I-1114J-1927D01*
G01X1353941Y1043267D01*
G02X1352467I-737J1277D01*
G03X1350299Y1043301I-1114J-1927D01*
G01X1350241Y1043267D01*
G02X1348767I-737J1277D01*
G03X1346599Y1043301I-1114J-1927D01*
G01X1346541Y1043267D01*
G02X1345067I-737J1277D01*
G03X1342899Y1043301I-1114J-1927D01*
G01X1342841Y1043267D01*
G02X1341367I-737J1277D01*
G03X1339181Y1043291I-1114J-1927D01*
G01X1339140Y1043267D01*
G02X1337666I-737J1277D01*
G01X1337625Y1043291D01*
G03X1335441Y1043267I-1071J-1951D01*
G02X1333967I-737J1277D01*
G03X1331781Y1043291I-1114J-1927D01*
G01X1331740Y1043267D01*
G02X1330266I-737J1277D01*
G03X1328040I-1113J-1927D01*
G02X1326566I-737J1277D01*
G03X1324340I-1113J-1927D01*
G02X1322866I-737J1277D01*
G01X1322831Y1043287D01*
G02X1322128Y1044544I772J1257D01*
G01Y1044617D01*
G03X1319903Y1046770I-2225J-73D01*
G01X1319302Y1047371D01*
G01X1379104Y1070178D02*
X1380335D01*
X1380561Y1069952D01*
G02X1378367Y1068901I-1457J226D01*
G03X1376141I-1113J-1927D01*
G02X1374667I-737J1277D01*
G03X1372441I-1113J-1927D01*
G02X1370967I-737J1277D01*
G03X1368799Y1068935I-1114J-1927D01*
G01X1368741Y1068901D01*
G02X1367267I-737J1277D01*
G03X1365099Y1068935I-1114J-1927D01*
G01X1365041Y1068901D01*
G02X1363567I-737J1277D01*
G03X1361381Y1068925I-1114J-1927D01*
G01X1361340Y1068901D01*
G02X1359866I-737J1277D01*
G03X1357682Y1068925I-1113J-1927D01*
G01X1357641Y1068901D01*
G02X1356167I-737J1277D01*
G03X1353999Y1068935I-1114J-1927D01*
G01X1353941Y1068901D01*
G02X1352467I-737J1277D01*
G03X1350299Y1068935I-1114J-1927D01*
G01X1350241Y1068901D01*
G02X1348767I-737J1277D01*
G03X1346541I-1113J-1927D01*
G02X1345067I-737J1277D01*
G03X1342899Y1068935I-1114J-1927D01*
G01X1342841Y1068901D01*
G02X1341367I-737J1277D01*
G03X1339199Y1068935I-1114J-1927D01*
G01X1339141Y1068901D01*
G02X1337667I-737J1277D01*
G03X1335481Y1068925I-1114J-1927D01*
G01X1335440Y1068901D01*
G02X1333966I-737J1277D01*
G03X1331740I-1113J-1927D01*
G02X1330266I-737J1277D01*
G03X1328082Y1068925I-1113J-1927D01*
G01X1328041Y1068901D01*
G02X1326567I-737J1277D01*
G03X1324381Y1068925I-1114J-1927D01*
G01X1324340Y1068901D01*
G02X1322866I-737J1277D01*
G03X1320640I-1113J-1927D01*
G02X1319903Y1068704I-736J1277D01*
G01X1318081D01*
X1317325Y1069460D01*
G01X1386504Y1063770D02*
X1385888Y1064837D01*
X1385537Y1064931D01*
G02X1383599Y1065013I-884J2043D01*
G01X1383541Y1065047D01*
G03X1382067I-737J-1277D01*
G02X1379899Y1065013I-1114J1927D01*
G01X1379841Y1065047D01*
G03X1378367I-737J-1277D01*
G02X1376141I-1113J1927D01*
G03X1374667I-737J-1277D01*
G02X1372441I-1113J1927D01*
G03X1370967I-737J-1277D01*
G02X1368799Y1065013I-1114J1927D01*
G01X1368741Y1065047D01*
G03X1367267I-737J-1277D01*
G02X1365081Y1065023I-1114J1927D01*
G01X1365040Y1065047D01*
G03X1363566I-737J-1277D01*
G02X1361382Y1065023I-1113J1927D01*
G01X1361341Y1065047D01*
G03X1359867I-737J-1277D01*
G02X1357699Y1065013I-1114J1927D01*
G01X1357641Y1065047D01*
G03X1356167I-737J-1277D01*
G02X1353999Y1065013I-1114J1927D01*
G01X1353941Y1065047D01*
G03X1352467I-737J-1277D01*
G02X1350299Y1065013I-1114J1927D01*
G01X1350241Y1065047D01*
G03X1348767I-737J-1277D01*
G02X1346541I-1113J1927D01*
G03X1345067I-737J-1277D01*
G02X1342899Y1065013I-1114J1927D01*
G01X1342841Y1065047D01*
G03X1341367I-737J-1277D01*
G02X1339181Y1065023I-1114J1927D01*
G01X1339140Y1065047D01*
G03X1337666I-737J-1277D01*
G02X1335482Y1065023I-1113J1927D01*
G01X1335441Y1065047D01*
G03X1333967I-737J-1277D01*
G02X1331781Y1065023I-1114J1927D01*
G01X1331740Y1065047D01*
G03X1330266I-737J-1277D01*
G02X1328040I-1113J1927D01*
G03X1326566I-737J-1277D01*
G02X1324340I-1113J1927D01*
G03X1322866I-737J-1277D01*
G02X1320640I-1113J1927D01*
G03X1319166I-737J-1277D01*
G01X1318293Y1064542D01*
G02X1318117Y1064495I-176J304D01*
G01X1315146D01*
G01X1306622Y166699D02*
X1305412Y163847D01*
X1305347Y163736D01*
G02X1303422Y162624I-1925J1110D01*
G01X1303417D01*
G03X1302141Y161887I0J-1473D01*
G01X1302081Y161783D01*
G03X1302082Y160488I1121J-647D01*
G01Y160486D01*
G02Y158260I-1925J-1113D01*
G03X1302227Y156470I1368J-790D01*
G01X1302293Y156389D01*
Y154927D01*
G01X1315770Y154288D02*
X1313977Y156081D01*
Y157298D01*
G02X1314270Y158485I2550J0D01*
G01X1314314Y158562D01*
G03Y160036I-1277J737D01*
G02Y162262I1928J1113D01*
G03Y163736I-1277J737D01*
G01X1314270Y163813D01*
G02X1314312Y165962I1972J1036D01*
G03Y167436I-1279J737D01*
G03X1313261Y168157I-1279J-737D01*
G01X1313034Y167930D01*
Y167912D01*
X1313033Y166699D01*
G01X1313037Y170399D02*
X1313036Y169168D01*
X1313291Y168912D01*
G02X1314963Y167812I-258J-2213D01*
G02Y165586I-1930J-1113D01*
G03X1314930Y164173I1279J-737D01*
G01X1314965Y164112D01*
G02Y161886I-1928J-1113D01*
G03Y160412I1277J-737D01*
G02X1314996Y158240I-1928J-1114D01*
G01X1314964Y158186D01*
X1314929Y158125D01*
G03X1315197Y156405I1312J-676D01*
G01X1317332Y154270D01*
G01X1411971Y909057D02*
X1411645Y906320D01*
G03X1411595Y905853I2175J-469D01*
G02X1410892Y904596I-1475J0D01*
G01X1410857Y904576D01*
G03X1409746Y902710I1114J-1927D01*
G01Y902649D01*
G02X1409043Y901392I-1475J0D01*
G01X1409008Y901372D01*
X1408984Y901358D01*
G03X1407895Y899445I1136J-1913D01*
G02X1407192Y898188I-1475J0D01*
G01X1407157Y898168D01*
G02X1405683I-737J1277D01*
G01X1405625Y898202D01*
G03X1403457Y898168I-1053J-1962D01*
G03X1402346Y896327I1114J-1928D01*
G01Y896201D01*
G03X1403458Y894313I2225J39D01*
G02X1404195Y893070I-737J-1277D01*
G01Y893002D01*
G02X1403458Y891759I-1474J34D01*
G03X1402346Y889871I1113J-1927D01*
G01Y889832D01*
G02X1401643Y888575I-1475J0D01*
G01X1401608Y888555D01*
G03X1400495Y886683I1112J-1928D01*
G01Y886627D01*
G02X1399792Y885370I-1475J0D01*
G01X1399757Y885350D01*
G03X1398646Y883484I1114J-1927D01*
G01Y883362D01*
G03X1399757Y881496I2225J61D01*
G01X1399792Y881476D01*
G02Y878962I-772J-1257D01*
G01X1399757Y878942D01*
G03X1398646Y877101I1114J-1928D01*
G01Y877014D01*
G02X1397943Y875757I-1475J0D01*
G01X1397908Y875737D01*
G02X1396434I-737J1277D01*
G03X1394266Y875771I-1114J-1927D01*
G01X1394208Y875737D01*
X1394184Y875723D01*
G03X1393095Y873810I1136J-1913D01*
G02X1392392Y872553I-1475J0D01*
G01X1392357Y872533D01*
G03X1391246Y870667I1114J-1927D01*
G01Y870606D01*
G02X1390543Y869349I-1475J0D01*
G01X1390508Y869329D01*
G02X1389034I-737J1277D01*
G03X1386808I-1113J-1928D01*
G03X1385695Y867431I1113J-1928D01*
G01Y867401D01*
G02X1384992Y866144I-1475J0D01*
G01X1384957Y866124D01*
G02X1383483I-737J1277D01*
G01X1383442Y866148D01*
G03X1381258Y866124I-1071J-1951D01*
G02X1379784I-737J1277D01*
G01X1379743Y866148D01*
G03X1377557Y866124I-1072J-1951D01*
G02X1376083I-737J1277D01*
G01X1376042Y866148D01*
G03X1373858Y866124I-1071J-1951D01*
G02X1372384I-737J1277D01*
G01X1372343Y866148D01*
G03X1370157Y866124I-1072J-1951D01*
G02X1368683I-737J1277D01*
G01X1368642Y866148D01*
G03X1366458Y866124I-1071J-1951D01*
G02X1364984I-737J1277D01*
G01X1364943Y866148D01*
G03X1362757Y866124I-1072J-1951D01*
G02X1361283I-737J1277D01*
G01X1361242Y866148D01*
G03X1359058Y866124I-1071J-1951D01*
G02X1357584I-737J1277D01*
G01X1357543Y866148D01*
G03X1355357Y866124I-1072J-1951D01*
G02X1353883I-737J1277D01*
G01X1353842Y866148D01*
G03X1351658Y866124I-1071J-1951D01*
G02X1350184I-737J1277D01*
G01X1350143Y866148D01*
G03X1347957Y866124I-1072J-1951D01*
G02X1346483I-737J1277D01*
G01X1346442Y866148D01*
G03X1344258Y866124I-1071J-1951D01*
G02X1342784I-737J1277D01*
G01X1342743Y866148D01*
G03X1340557Y866124I-1072J-1951D01*
G02X1339083I-737J1277D01*
G01X1339042Y866148D01*
G03X1336858Y866124I-1071J-1951D01*
G02X1335384I-737J1277D01*
G01X1335343Y866148D01*
G03X1333157Y866124I-1072J-1951D01*
G02X1331683I-737J1277D01*
G01X1331642Y866148D01*
G03X1329458Y866124I-1071J-1951D01*
G02X1327984I-737J1277D01*
G03X1325758I-1113J-1927D01*
G03X1324646Y864236I1113J-1927D01*
G01Y864197D01*
G02X1323943Y862940I-1475J0D01*
G01X1323908Y862920D01*
G03X1322796Y861032I1113J-1927D01*
G01Y860993D01*
G02X1322093Y859736I-1475J0D01*
G01X1322058Y859716D01*
X1322010Y859688D01*
G03X1320945Y857789I1161J-1899D01*
G02X1320265Y856546I-1476J0D01*
G01X1320206Y856512D01*
G03X1319095Y854671I1114J-1928D01*
G01Y854584D01*
G02X1318392Y853327I-1475J0D01*
G01X1318357Y853307D01*
G03X1317658Y852671I1113J-1926D01*
G01X1316500Y851513D01*
G01X1317995Y850835D02*
Y851414D01*
G02X1318732Y852657I1474J-34D01*
G01X1318756Y852671D01*
G03X1319845Y854584I-1136J1913D01*
G02X1320548Y855841I1475J0D01*
G01X1320583Y855861D01*
G03X1321695Y857733I-1114J1928D01*
G01Y857789D01*
G02X1322375Y859032I1476J0D01*
G01X1322434Y859066D01*
G03X1323546Y860954I-1113J1927D01*
G01Y860993D01*
G02X1324249Y862250I1475J0D01*
G01X1324284Y862270D01*
G03X1325396Y864158I-1113J1927D01*
G01Y864197D01*
G02X1326099Y865454I1475J0D01*
G01X1326134Y865474D01*
G02X1327608I737J-1277D01*
G03X1329834I1113J1927D01*
G02X1331308I737J-1277D01*
G01X1331366Y865440D01*
G03X1333534Y865474I1054J1961D01*
G02X1335008I737J-1277D01*
G03X1337234I1113J1927D01*
G02X1338708I737J-1277D01*
G01X1338766Y865440D01*
G03X1340934Y865474I1054J1961D01*
G02X1342408I737J-1277D01*
G03X1344634I1113J1927D01*
G02X1346108I737J-1277D01*
G01X1346166Y865440D01*
G03X1348334Y865474I1054J1961D01*
G02X1349808I737J-1277D01*
G03X1352034I1113J1927D01*
G02X1353508I737J-1277D01*
G01X1353566Y865440D01*
G03X1355734Y865474I1054J1961D01*
G02X1357208I737J-1277D01*
G03X1359434I1113J1927D01*
G02X1360908I737J-1277D01*
G01X1360966Y865440D01*
G03X1363134Y865474I1054J1961D01*
G02X1364608I737J-1277D01*
G03X1366834I1113J1927D01*
G02X1368308I737J-1277D01*
G01X1368366Y865440D01*
G03X1370534Y865474I1054J1961D01*
G02X1372008I737J-1277D01*
G03X1374234I1113J1927D01*
G02X1375708I737J-1277D01*
G01X1375766Y865440D01*
G03X1377934Y865474I1054J1961D01*
G02X1379408I737J-1277D01*
G03X1381634I1113J1927D01*
G02X1383108I737J-1277D01*
G01X1383166Y865440D01*
G03X1385334Y865474I1054J1961D01*
G01X1385358Y865488D01*
G03X1386446Y867401I-1138J1913D01*
G02X1387149Y868658I1475J0D01*
G01X1387184Y868678D01*
G02X1388658I737J-1277D01*
G03X1390842Y868654I1113J1928D01*
G01X1390883Y868678D01*
G03X1391996Y870550I-1112J1928D01*
G01Y870606D01*
G02X1392699Y871863I1475J0D01*
G01X1392734Y871883D01*
G03X1393845Y873749I-1114J1927D01*
G01Y873810D01*
G02X1394548Y875067I1475J0D01*
G01X1394583Y875087D01*
G02X1396057I737J-1277D01*
G03X1398225Y875053I1114J1927D01*
G01X1398283Y875087D01*
X1398307Y875101D01*
G03X1399396Y877014I-1136J1913D01*
G02X1400099Y878271I1475J0D01*
G01X1400134Y878291D01*
G03X1401246Y880163I-1114J1928D01*
G01Y880219D01*
G03X1400158Y882132I-2226J0D01*
G01X1400134Y882146D01*
X1400099Y882166D01*
G02Y884680I772J1257D01*
G01X1400134Y884700D01*
G03X1401245Y886566I-1114J1927D01*
G01Y886627D01*
G02X1401948Y887884I1475J0D01*
G01X1401983Y887904D01*
G03X1403096Y889776I-1112J1928D01*
G01Y889832D01*
G02X1403799Y891089I1475J0D01*
G01X1403834Y891109D01*
G03X1404946Y892997I-1113J1927D01*
G01Y893075D01*
G03X1403834Y894963I-2225J-39D01*
G01X1403799Y894983D01*
G02Y897497I772J1257D01*
G01X1403834Y897517D01*
G02X1405308I737J-1277D01*
G01X1405366Y897483D01*
G03X1407534Y897517I1053J1962D01*
G03X1408645Y899358I-1114J1928D01*
G01Y899445D01*
G02X1409348Y900702I1475J0D01*
G01X1409383Y900722D01*
X1409407Y900736D01*
G03X1410496Y902649I-1136J1913D01*
G02X1411199Y903906I1475J0D01*
G01X1411234Y903926D01*
X1411258Y903940D01*
G03X1412346Y905853I-1138J1913D01*
G02X1413049Y907110I1475J0D01*
G01X1413446Y907507D01*
Y909144D01*
G02X1414557Y910985I2225J-87D01*
G01X1414559Y910987D01*
G03X1415296Y912262I-736J1276D01*
G01Y912394D01*
X1415671Y915466D01*
G01X1419371Y909057D02*
Y907669D01*
X1419138Y907436D01*
Y906635D01*
G03X1418997Y905914I2084J-782D01*
G01Y905853D01*
X1418996D01*
G02X1418293Y904596I-1475J0D01*
G01X1418258Y904576D01*
G02X1416784I-737J1277D01*
G03X1414616Y904610I-1114J-1927D01*
G01X1414558Y904576D01*
X1414534Y904562D01*
G03X1413445Y902649I1136J-1913D01*
G01Y902615D01*
G02X1412708Y901372I-1474J34D01*
G01X1412660Y901344D01*
G03X1411595Y899445I1161J-1899D01*
G02X1410892Y898188I-1475J0D01*
G01X1410857Y898168D01*
G03X1409746Y896327I1114J-1928D01*
G01Y896240D01*
G02X1409043Y894983I-1475J0D01*
G01X1409008Y894963D01*
X1408960Y894935D01*
G03X1407895Y893036I1161J-1899D01*
G02X1407192Y891779I-1475J0D01*
G01X1407157Y891759D01*
G03X1406046Y889893I1114J-1927D01*
G01Y889832D01*
G02X1405343Y888575I-1475J0D01*
G01X1405308Y888555D01*
G03X1404195Y886683I1112J-1928D01*
G01Y886627D01*
G02X1403492Y885370I-1475J0D01*
G01X1403457Y885350D01*
G03X1402346Y883484I1114J-1927D01*
G01Y883384D01*
G03X1403458Y881496I2225J39D01*
G02X1404195Y880253I-737J-1277D01*
G01Y880185D01*
G02X1403458Y878942I-1474J34D01*
G03X1402346Y877087I1113J-1928D01*
G01Y877014D01*
G02X1401643Y875757I-1475J0D01*
G01X1401608Y875737D01*
X1401597Y875731D01*
X1401584Y875723D01*
G03X1400495Y873810I1136J-1913D01*
G02X1399792Y872553I-1475J0D01*
G01X1399757Y872533D01*
G03X1398646Y870667I1114J-1927D01*
G01Y870606D01*
G02X1397943Y869349I-1475J0D01*
G01X1397908Y869329D01*
G03X1396795Y867457I1112J-1928D01*
G01Y867367D01*
G02X1396058Y866124I-1474J34D01*
G02X1394584I-737J1277D01*
G01X1394543Y866148D01*
G03X1392357Y866124I-1072J-1951D01*
G02X1390883I-737J1277D01*
G01X1390842Y866148D01*
G03X1388658Y866124I-1071J-1951D01*
G03X1387546Y864236I1113J-1927D01*
G01Y864197D01*
G02X1386843Y862940I-1475J0D01*
G01X1386808Y862920D01*
G02X1385334I-737J1277D01*
G03X1383166Y862954I-1114J-1927D01*
G01X1383108Y862920D01*
G02X1381634I-737J1277D01*
G03X1379466Y862954I-1114J-1927D01*
G01X1379408Y862920D01*
G02X1377934I-737J1277D01*
G03X1375766Y862954I-1114J-1927D01*
G01X1375708Y862920D01*
G02X1374234I-737J1277D01*
G03X1372066Y862954I-1114J-1927D01*
G01X1372008Y862920D01*
G02X1370534I-737J1277D01*
G03X1368366Y862954I-1114J-1927D01*
G01X1368308Y862920D01*
G02X1366834I-737J1277D01*
G03X1364666Y862954I-1114J-1927D01*
G01X1364608Y862920D01*
G02X1363134I-737J1277D01*
G03X1360966Y862954I-1114J-1927D01*
G01X1360908Y862920D01*
G02X1359434I-737J1277D01*
G03X1357266Y862954I-1114J-1927D01*
G01X1357208Y862920D01*
G02X1355734I-737J1277D01*
G03X1353566Y862954I-1114J-1927D01*
G01X1353508Y862920D01*
G02X1352034I-737J1277D01*
G03X1349866Y862954I-1114J-1927D01*
G01X1349808Y862920D01*
G02X1348334I-737J1277D01*
G03X1346166Y862954I-1114J-1927D01*
G01X1346108Y862920D01*
G02X1344634I-737J1277D01*
G03X1342466Y862954I-1114J-1927D01*
G01X1342408Y862920D01*
G02X1340934I-737J1277D01*
G03X1338766Y862954I-1114J-1927D01*
G01X1338708Y862920D01*
G02X1337234I-737J1277D01*
G03X1335066Y862954I-1114J-1927D01*
G01X1335008Y862920D01*
G02X1333534I-737J1277D01*
G03X1331366Y862954I-1114J-1927D01*
G01X1331308Y862920D01*
G02X1329834I-737J1277D01*
G03X1327666Y862954I-1114J-1927D01*
G01X1327608Y862920D01*
X1327584Y862906D01*
G03X1326495Y860993I1136J-1913D01*
G01Y860959D01*
G02X1325758Y859716I-1474J34D01*
G03X1324646Y857828I1113J-1927D01*
G01Y857789D01*
G02X1323943Y856532I-1475J0D01*
G01X1323908Y856512D01*
G03X1322795Y854640I1112J-1928D01*
G01Y854584D01*
G02X1322092Y853327I-1475J0D01*
G01X1322057Y853307D01*
X1322009Y853279D01*
G03X1320944Y851380I1161J-1899D01*
G02X1320241Y850123I-1475J0D01*
G01X1320206Y850103D01*
G03X1319095Y848237I1114J-1927D01*
G01X1318245Y847387D01*
Y846005D01*
G01X1320948Y871485D02*
G03X1322434Y871883I0J2972D01*
G02X1323908I737J-1277D01*
G03X1327246Y873771I1113J1927D01*
G01Y873844D01*
G02X1329457Y875087I1474J-34D01*
G03X1331625Y875053I1114J1927D01*
G01X1331683Y875087D01*
G02X1333157I737J-1277D01*
G03X1335325Y875053I1114J1927D01*
G01X1335383Y875087D01*
G02X1336857I737J-1277D01*
G03X1339025Y875053I1114J1927D01*
G01X1339083Y875087D01*
G02X1340557I737J-1277D01*
G03X1342725Y875053I1114J1927D01*
G01X1342783Y875087D01*
G02X1344257I737J-1277D01*
G03X1346425Y875053I1114J1927D01*
G01X1346483Y875087D01*
G02X1347957I737J-1277D01*
G03X1350125Y875053I1114J1927D01*
G01X1350183Y875087D01*
G02X1351657I737J-1277D01*
G03X1353825Y875053I1114J1927D01*
G01X1353883Y875087D01*
G02X1355357I737J-1277D01*
G03X1357525Y875053I1114J1927D01*
G01X1357583Y875087D01*
G02X1359057I737J-1277D01*
G03X1361225Y875053I1114J1927D01*
G01X1361283Y875087D01*
G02X1362757I737J-1277D01*
G03X1364925Y875053I1114J1927D01*
G01X1364983Y875087D01*
G02X1366457I737J-1277D01*
G03X1368625Y875053I1114J1927D01*
G01X1368683Y875087D01*
G02X1370157I737J-1277D01*
G03X1372325Y875053I1114J1927D01*
G01X1372383Y875087D01*
G02X1373857I737J-1277D01*
G03X1376025Y875053I1114J1927D01*
G01X1376083Y875087D01*
G02X1377557I737J-1277D01*
G03X1379725Y875053I1114J1927D01*
G01X1379783Y875087D01*
G02X1381257I737J-1277D01*
G03X1383425Y875053I1114J1927D01*
G01X1383483Y875087D01*
G02X1384957I737J-1277D01*
G03X1387125Y875053I1114J1927D01*
G01X1387183Y875087D01*
G02X1388657I737J-1277D01*
G03X1391996Y877014I1114J1927D01*
G02X1392699Y878271I1475J0D01*
G01X1392734Y878291D01*
G03X1393846Y880163I-1114J1928D01*
G01Y880219D01*
G02X1394549Y881476I1475J0D01*
G01X1394584Y881496D01*
G03X1395696Y883384I-1113J1927D01*
G01Y883423D01*
G02X1396399Y884680I1475J0D01*
G01X1396434Y884700D01*
G03X1397545Y886566I-1114J1927D01*
G01Y886627D01*
G02X1398248Y887884I1475J0D01*
G01X1398283Y887904D01*
G03X1399396Y889776I-1112J1928D01*
G01Y889832D01*
G02X1400099Y891089I1475J0D01*
G01X1400158Y891123D01*
G03Y894949I-1138J1913D01*
G01X1400099Y894983D01*
G02Y897497I772J1257D01*
G01X1400134Y897517D01*
G03X1401245Y899358I-1114J1928D01*
G01Y899445D01*
G02X1401948Y900702I1475J0D01*
G01X1402007Y900736D01*
G03X1403096Y902649I-1136J1913D01*
G02X1405308Y903926I1475J0D01*
G01X1405366Y903892D01*
G03X1408645Y905792I1054J1961D01*
G01Y905853D01*
G02X1409348Y907110I1475J0D01*
G01X1409407Y907144D01*
G03X1410495Y909057I-1138J1913D01*
G02X1411175Y910300I1476J0D01*
G01X1411234Y910334D01*
G03X1412346Y912189I-1113J1928D01*
G01Y912296D01*
G02X1413083Y913539I1474J-34D01*
G01X1413107Y913553D01*
G03X1414196Y915466I-1136J1913D01*
G02X1414899Y916723I1475J0D01*
G01X1414934Y916743D01*
G03X1416045Y918609I-1114J1927D01*
G01Y918670D01*
G02X1416596Y919819I1475J-1D01*
G01X1416904Y919737D01*
X1417520Y918670D01*
G01X1410121Y912262D02*
X1408470Y911394D01*
G02X1407564Y910353I-2049J868D01*
G01X1407532Y910334D01*
G03X1406795Y909091I737J-1277D01*
G01Y908996D01*
G02X1405683Y907130I-2224J61D01*
G01X1405625Y907096D01*
G02X1403457Y907130I-1054J1961D01*
G03X1401983I-737J-1277D01*
G01X1401948Y907110D01*
G03X1401245Y905853I772J-1257D01*
G01Y905792D01*
G02X1400134Y903926I-2225J61D01*
G01X1400099Y903906D01*
G03X1399396Y902649I772J-1257D01*
G02X1398307Y900736I-2225J0D01*
G01X1398283Y900722D01*
X1398248Y900702D01*
G03X1397545Y899445I772J-1257D01*
G01Y899358D01*
G02X1396434Y897517I-2225J87D01*
G01X1396399Y897497D01*
G03X1395696Y896240I772J-1257D01*
G01Y896201D01*
G02X1394584Y894313I-2225J39D01*
G01X1394549Y894293D01*
G03X1393846Y893036I772J-1257D01*
G02X1392758Y891123I-2226J0D01*
G01X1392734Y891109D01*
X1392699Y891089D01*
G03X1391996Y889832I772J-1257D01*
G01Y889776D01*
G02X1390883Y887904I-2225J56D01*
G01X1390848Y887884D01*
G03X1390145Y886627I772J-1257D01*
G01Y886566D01*
G02X1389034Y884700I-2225J61D01*
G01X1388999Y884680D01*
G03X1388296Y883423I772J-1257D01*
G01Y883384D01*
G02X1387184Y881496I-2225J39D01*
G01X1387149Y881476D01*
G03X1386446Y880219I772J-1257D01*
G01Y880163D01*
G02X1385334Y878291I-2226J56D01*
G02X1383166Y878257I-1115J1928D01*
G01X1383108Y878291D01*
G03X1381634I-737J-1277D01*
G02X1379408I-1113J1928D01*
G03X1377934I-737J-1277D01*
G02X1375766Y878257I-1115J1928D01*
G01X1375708Y878291D01*
G03X1374234I-737J-1277D01*
G02X1372008I-1113J1928D01*
G03X1370534I-737J-1277D01*
G02X1368366Y878257I-1115J1928D01*
G01X1368308Y878291D01*
G03X1366834I-737J-1277D01*
G02X1364608I-1113J1928D01*
G03X1363134I-737J-1277D01*
G02X1360966Y878257I-1115J1928D01*
G01X1360908Y878291D01*
G03X1359434I-737J-1277D01*
G02X1357208I-1113J1928D01*
G03X1355734I-737J-1277D01*
G02X1353566Y878257I-1115J1928D01*
G01X1353508Y878291D01*
G03X1352034I-737J-1277D01*
G02X1349808I-1113J1928D01*
G03X1348334I-737J-1277D01*
G02X1346166Y878257I-1115J1928D01*
G01X1346108Y878291D01*
G03X1344634I-737J-1277D01*
G02X1342408I-1113J1928D01*
G03X1340934I-737J-1277D01*
G02X1338766Y878257I-1115J1928D01*
G01X1338708Y878291D01*
G03X1337234I-737J-1277D01*
G02X1335008I-1113J1928D01*
G03X1333534I-737J-1277D01*
G02X1331366Y878257I-1115J1928D01*
G01X1331308Y878291D01*
G03X1329834I-737J-1277D01*
G02X1327608I-1113J1928D01*
G03X1326134I-737J-1277D01*
G02X1323966Y878257I-1115J1928D01*
G01X1323908Y878291D01*
X1323875Y878310D01*
G03X1322435Y878291I-703J-1296D01*
G02X1320249Y878267I-1114J1928D01*
G01X1320208Y878291D01*
G03X1318734I-737J-1277D01*
G02X1316508I-1113J1928D01*
G03X1315034I-737J-1277D01*
G01X1314993Y878267D01*
G02X1314225Y878013I-1072J1952D01*
G01X1313869Y877657D01*
G01X1391620Y905853D02*
X1389961Y906839D01*
G02X1388657Y907130I-190J2218D01*
G03X1387183I-737J-1277D01*
G01X1387148Y907110D01*
G03X1386445Y905853I772J-1257D01*
G01Y905792D01*
G02X1385334Y903926I-2225J61D01*
G01X1385299Y903906D01*
G03X1384596Y902649I772J-1257D01*
G02X1383507Y900736I-2225J0D01*
G01X1383483Y900722D01*
X1383448Y900702D01*
G03X1382745Y899445I772J-1257D01*
G01Y899358D01*
G02X1381634Y897517I-2225J87D01*
G01X1381599Y897497D01*
G03X1380896Y896240I772J-1257D01*
G02X1379807Y894327I-2225J0D01*
G01X1379783Y894313D01*
X1379748Y894293D01*
G03X1379045Y893036I772J-1257D01*
G01Y892975D01*
G02X1377934Y891109I-2225J61D01*
G02X1375766Y891075I-1114J1927D01*
G01X1375708Y891109D01*
G03X1374234I-737J-1277D01*
G02X1372008I-1113J1927D01*
G03X1370534I-737J-1277D01*
G02X1368308I-1113J1927D01*
G03X1366834I-737J-1277D01*
G02X1364608I-1113J1927D01*
G03X1363134I-737J-1277D01*
G02X1360966Y891075I-1114J1927D01*
G01X1360908Y891109D01*
G03X1359434I-737J-1277D01*
G02X1357266Y891075I-1114J1927D01*
G01X1357208Y891109D01*
G03X1355734I-737J-1277D01*
G02X1353508I-1113J1927D01*
G03X1352034I-737J-1277D01*
G02X1349866Y891075I-1114J1927D01*
G01X1349808Y891109D01*
G03X1348334I-737J-1277D01*
G02X1346166Y891075I-1114J1927D01*
G01X1346108Y891109D01*
G03X1344634I-737J-1277D01*
G02X1342408I-1113J1927D01*
G03X1340934I-737J-1277D01*
G02X1338708I-1113J1927D01*
G03X1337234I-737J-1277D01*
G01X1337193Y891085D01*
G02X1335007Y891109I-1072J1951D01*
G03X1333533I-737J-1277D01*
G02X1331349Y891085I-1113J1927D01*
G01X1331308Y891109D01*
G03X1329834I-737J-1277D01*
G02X1327666Y891075I-1114J1927D01*
G01X1327608Y891109D01*
G03X1326134I-737J-1277D01*
G02X1323966Y891075I-1114J1927D01*
G01X1323908Y891109D01*
G03X1322434I-737J-1277D01*
G01X1322393Y891085D01*
G02X1320207Y891109I-1072J1951D01*
G03X1318733I-737J-1277D01*
G02X1316549Y891085I-1113J1927D01*
G01X1316508Y891109D01*
G03X1315034I-737J-1277D01*
G01X1314993Y891085D01*
G02X1312807Y891109I-1072J1951D01*
G03X1311333I-737J-1277D01*
G03X1311027Y890875I735J-1278D01*
G01X1310622Y890470D01*
X1309922D01*
G01X1386504Y1044544D02*
X1384784Y1043528D01*
G02X1383940Y1042631I-1979J1017D01*
G01X1383916Y1042617D01*
X1383881Y1042597D01*
G03X1383178Y1041340I772J-1257D01*
G01Y1038768D01*
X1379598Y1035188D01*
X1375898D01*
X1374597Y1033887D01*
G02X1372816Y1033654I-1042J1044D01*
G01X1372758Y1033688D01*
G03X1370590Y1033654I-1054J-1961D01*
G02X1369116I-737J1277D01*
G01X1369058Y1033688D01*
G03X1366890Y1033654I-1054J-1961D01*
G02X1365416I-737J1277D01*
G01X1365358Y1033688D01*
G03X1363190Y1033654I-1054J-1961D01*
G02X1361716I-737J1277D01*
G03X1359532Y1033678I-1113J-1927D01*
G01X1359491Y1033654D01*
G02X1358017I-737J1277D01*
G01X1357976Y1033678D01*
G03X1355790Y1033654I-1072J-1951D01*
G02X1354316I-737J1277D01*
G01X1354258Y1033688D01*
G03X1352090Y1033654I-1054J-1961D01*
G02X1350616I-737J1277D01*
G01X1350558Y1033688D01*
G03X1348390Y1033654I-1054J-1961D01*
G02X1346916I-737J1277D01*
G01X1346858Y1033688D01*
G03X1344690Y1033654I-1054J-1961D01*
G02X1343216I-737J1277D01*
G01X1343158Y1033688D01*
G03X1340990Y1033654I-1054J-1961D01*
G02X1339516I-737J1277D01*
G01X1339458Y1033688D01*
G03X1337290Y1033654I-1054J-1961D01*
G02X1335816I-737J1277D01*
G03X1333632Y1033678I-1113J-1927D01*
G01X1333591Y1033654D01*
G02X1332117I-737J1277D01*
G03X1329931Y1033678I-1114J-1927D01*
G01X1329890Y1033654D01*
G02X1328416I-737J1277D01*
G01X1328358Y1033688D01*
G03X1326190Y1033654I-1054J-1961D01*
G02X1324716I-737J1277D01*
G03X1322249Y1034315I-2467J-4275D01*
G01X1316837D01*
G01X1314733Y1055885D02*
X1319903D01*
G03X1320640Y1056084I-3J1475D01*
G02X1322866I1113J-1927D01*
G03X1324340I737J1277D01*
G02X1326566I1113J-1927D01*
G03X1328040I737J1277D01*
G02X1330266I1113J-1927D01*
G03X1331740I737J1277D01*
G02X1333926Y1056108I1114J-1927D01*
G01X1333967Y1056084D01*
G03X1335441I737J1277D01*
G01X1335499Y1056118D01*
G02X1337667Y1056084I1054J-1961D01*
G03X1339141I737J1277D01*
G01X1339199Y1056118D01*
G02X1341367Y1056084I1054J-1961D01*
G03X1342841I737J1277D01*
G01X1342899Y1056118D01*
G02X1345067Y1056084I1054J-1961D01*
G03X1346541I737J1277D01*
G01X1346582Y1056108D01*
G02X1348766Y1056084I1071J-1951D01*
G03X1350240I737J1277D01*
G01X1350281Y1056108D01*
G02X1352467Y1056084I1072J-1951D01*
G03X1353941I737J1277D01*
G01X1353999Y1056118D01*
G02X1356167Y1056084I1054J-1961D01*
G03X1357641I737J1277D01*
G02X1359867I1113J-1927D01*
G03X1361341I737J1277D01*
G01X1361399Y1056118D01*
G02X1363567Y1056084I1054J-1961D01*
G03X1365041I737J1277D01*
G01X1365099Y1056118D01*
G02X1367267Y1056084I1054J-1961D01*
G03X1368741I737J1277D01*
G01X1368799Y1056118D01*
G02X1370967Y1056084I1054J-1961D01*
G03X1372441I737J1277D01*
G01X1372482Y1056108D01*
G02X1374666Y1056084I1071J-1951D01*
G03X1376140I737J1277D01*
G01X1376181Y1056108D01*
G02X1378367Y1056084I1072J-1951D01*
G03X1379841I737J1277D01*
G01X1379876Y1056104D01*
G03X1380561Y1057135I-773J1256D01*
G01X1380335Y1057361D01*
X1379104D01*
G01X1313826Y1062222D02*
X1314739D01*
X1316242Y1060719D01*
X1317471D01*
X1319526Y1061569D01*
G03X1320864Y1061754I377J2201D01*
G01X1321016Y1061842D01*
G02X1322490I737J-1277D01*
G03X1324716I1113J1928D01*
G02X1326190I737J-1277D01*
G03X1328416I1113J1928D01*
G02X1329890I737J-1277D01*
G03X1332116I1113J1928D01*
G02X1333590I737J-1277D01*
G03X1335776Y1061818I1114J1928D01*
G01X1335817Y1061842D01*
G02X1337291I737J-1277D01*
G01X1337332Y1061818D01*
G03X1339516Y1061842I1071J1952D01*
G02X1340990I737J-1277D01*
G03X1343158Y1061808I1115J1928D01*
G01X1343216Y1061842D01*
G02X1344690I737J-1277D01*
G03X1346858Y1061808I1115J1928D01*
G01X1346916Y1061842D01*
G02X1348390I737J-1277D01*
G03X1350558Y1061808I1115J1928D01*
G01X1350616Y1061842D01*
G02X1352090I737J-1277D01*
G03X1354258Y1061808I1115J1928D01*
G01X1354316Y1061842D01*
G02X1355790I737J-1277D01*
G03X1357958Y1061808I1115J1928D01*
G01X1358016Y1061842D01*
G02X1359490I737J-1277D01*
G03X1361676Y1061818I1114J1928D01*
G01X1361717Y1061842D01*
G02X1363191I737J-1277D01*
G01X1363232Y1061818D01*
G03X1365416Y1061842I1071J1952D01*
G02X1366890I737J-1277D01*
G03X1369058Y1061808I1115J1928D01*
G01X1369116Y1061842D01*
G02X1370590I737J-1277D01*
G03X1372758Y1061808I1115J1928D01*
G01X1372816Y1061842D01*
G02X1374290I737J-1277D01*
G03X1376518I1114J1928D01*
G03X1377616Y1063513I-1114J1928D01*
G01X1377873Y1063770D01*
X1379104D01*
G01X1315995Y1057526D02*
X1317980D01*
X1318859Y1058405D01*
G02X1319166Y1058638I1038J-1049D01*
G02X1320640I737J-1277D01*
G03X1322866I1113J1927D01*
G02X1324340I737J-1277D01*
G03X1326566I1113J1927D01*
G02X1328040I737J-1277D01*
G03X1330266I1113J1927D01*
G02X1331740I737J-1277D01*
G03X1333966I1113J1927D01*
G02X1335440I737J-1277D01*
G01X1335481Y1058614D01*
G03X1337667Y1058638I1072J1951D01*
G02X1339141I737J-1277D01*
G01X1339182Y1058614D01*
G03X1341366Y1058638I1071J1951D01*
G02X1342840I737J-1277D01*
G01X1342881Y1058614D01*
G03X1345067Y1058638I1072J1951D01*
G02X1346541I737J-1277D01*
G01X1346599Y1058604D01*
G03X1348767Y1058638I1054J1961D01*
G02X1350241I737J-1277D01*
G03X1352467I1113J1927D01*
G02X1353941I737J-1277D01*
G01X1353999Y1058604D01*
G03X1356167Y1058638I1054J1961D01*
G02X1357641I737J-1277D01*
G01X1357699Y1058604D01*
G03X1359867Y1058638I1054J1961D01*
G02X1361341I737J-1277D01*
G01X1361399Y1058604D01*
G03X1363567Y1058638I1054J1961D01*
G02X1365041I737J-1277D01*
G01X1365082Y1058614D01*
G03X1367266Y1058638I1071J1951D01*
G02X1368740I737J-1277D01*
G01X1368781Y1058614D01*
G03X1370967Y1058638I1072J1951D01*
G02X1372441I737J-1277D01*
G01X1372499Y1058604D01*
G03X1374667Y1058638I1054J1961D01*
G02X1376141I737J-1277D01*
G03X1378367I1113J1927D01*
G02X1379841I737J-1277D01*
G03X1382067I1113J1927D01*
G02X1383541I737J-1277D01*
G01X1383599Y1058604D01*
G03X1385767Y1058638I1054J1961D01*
G02X1387241I737J-1277D01*
G01X1387299Y1058604D01*
G03X1389237Y1058522I1054J1961D01*
G01X1389650Y1058935D01*
X1391205D01*
X1394649Y1052905D01*
X1397604Y1050952D01*
G01X1315882Y1058894D02*
X1318287D01*
X1318330Y1058937D01*
G02X1318538Y1059119I1566J-1580D01*
G02X1318790Y1059288I1363J-1760D01*
G02X1321016I1113J-1927D01*
G03X1322490I737J1277D01*
G02X1324716I1113J-1927D01*
G03X1326190I737J1277D01*
G02X1328416I1113J-1927D01*
G03X1329890I737J1277D01*
G02X1332116I1113J-1927D01*
G03X1333590I737J1277D01*
G02X1335776Y1059312I1114J-1927D01*
G01X1335817Y1059288D01*
G03X1337291I737J1277D01*
G02X1339475Y1059312I1113J-1927D01*
G01X1339516Y1059288D01*
G03X1340990I737J1277D01*
G02X1343158Y1059322I1114J-1927D01*
G01X1343216Y1059288D01*
G03X1344690I737J1277D01*
G02X1346858Y1059322I1114J-1927D01*
G01X1346916Y1059288D01*
G03X1348390I737J1277D01*
G02X1350616I1113J-1927D01*
G03X1352090I737J1277D01*
G02X1354258Y1059322I1114J-1927D01*
G01X1354316Y1059288D01*
G03X1355790I737J1277D01*
G02X1358015I1112J-1927D01*
G01X1358016D01*
G03X1359490I737J1277D01*
G02X1361676Y1059312I1114J-1927D01*
G01X1361717Y1059288D01*
G03X1363191I737J1277D01*
G02X1365375Y1059312I1113J-1927D01*
G01X1365416Y1059288D01*
G03X1366890I737J1277D01*
G02X1369058Y1059322I1114J-1927D01*
G01X1369116Y1059288D01*
G03X1370590I737J1277D01*
G02X1372758Y1059322I1114J-1927D01*
G01X1372816Y1059288D01*
G03X1374290I737J1277D01*
G01X1374331Y1059312D01*
G02X1376517Y1059288I1072J-1951D01*
G03X1377991I737J1276D01*
G01X1377992D01*
G02X1380216I1112J-1927D01*
G03X1381690I737J1277D01*
G01X1381691D01*
X1381803Y1059353D01*
X1384653Y1060565D01*
G01X1379104Y1050952D02*
X1376260Y1049744D01*
X1376141Y1049675D01*
Y1049676D01*
G02X1374667I-737J1276D01*
G03X1372442I-1112J-1926D01*
G01X1372441D01*
G02X1370967I-737J1276D01*
G03X1368799Y1049710I-1114J-1927D01*
G01X1368741Y1049676D01*
G02X1367267I-737J1276D01*
G03X1365099Y1049710I-1114J-1927D01*
G01X1365041Y1049676D01*
G02X1363567I-737J1276D01*
G03X1361381Y1049700I-1114J-1927D01*
G01X1361340Y1049676D01*
G02X1359866I-737J1276D01*
G03X1357682Y1049700I-1113J-1927D01*
G01X1357641Y1049676D01*
G02X1356167I-737J1276D01*
G03X1353999Y1049710I-1114J-1927D01*
G01X1353941Y1049676D01*
G02X1352467I-737J1276D01*
G03X1350299Y1049710I-1114J-1927D01*
G01X1350241Y1049676D01*
G02X1348767I-737J1276D01*
G03X1346599Y1049710I-1114J-1927D01*
G01X1346541Y1049676D01*
G02X1345067I-737J1276D01*
G03X1342899Y1049710I-1114J-1927D01*
G01X1342841Y1049676D01*
G02X1341367I-737J1276D01*
G03X1339199Y1049710I-1114J-1927D01*
G01X1339141Y1049676D01*
G02X1337667I-737J1276D01*
G03X1335481Y1049700I-1114J-1927D01*
G01X1335440Y1049676D01*
G02X1333966I-737J1276D01*
G03X1331740I-1113J-1927D01*
G02X1330266I-737J1276D01*
G03X1328040I-1113J-1927D01*
G02X1326566I-737J1276D01*
G03X1324340I-1113J-1927D01*
G02X1322866I-737J1276D01*
G03X1320640I-1113J-1927D01*
G02X1319166I-737J1276D01*
G01X1318013D01*
X1317311Y1048974D01*
X1311937D01*
G01X1319442Y159299D02*
X1320707Y158034D01*
Y157248D01*
X1322693Y155262D01*
G01X1316242Y164849D02*
Y166080D01*
X1316470Y166308D01*
G02X1317522Y165586I-228J-1459D01*
G02Y164112I-1280J-737D01*
G03Y161886I1930J-1113D01*
G03X1319331Y160775I1929J1113D01*
G01X1319445Y160774D01*
X1319522D01*
G02X1320722Y160036I-80J-1475D01*
G03X1322537Y158924I1930J1113D01*
G01X1322729D01*
G02X1323932Y158186I-77J-1475D01*
G01X1324311Y157528D01*
Y156716D01*
X1325179Y155848D01*
G01X1316242Y168549D02*
Y167318D01*
X1316497Y167063D01*
G02X1318172Y165962I-255J-2213D01*
G02Y163736I-1930J-1113D01*
G03Y162262I1280J-737D01*
G03X1319372Y161524I1280J737D01*
G01X1319449D01*
X1319563Y161523D01*
G02X1321372Y160412I-120J-2224D01*
G03X1322575Y159674I1280J737D01*
G01X1322767D01*
G02X1324582Y158562I-115J-2225D01*
G01X1324633D01*
X1325304Y157891D01*
G01X1327505Y242276D02*
Y242189D01*
X1327641Y242053D01*
Y239885D01*
X1329033Y238493D01*
Y236616D01*
X1329034Y236615D01*
Y233221D01*
X1334303Y227952D01*
Y217343D01*
X1335371Y216275D01*
X1336177D01*
X1336527Y215925D01*
Y214799D01*
G01X1328525Y242276D02*
Y242189D01*
X1328390Y242054D01*
Y240196D01*
X1329782Y238804D01*
Y238125D01*
X1330173Y237734D01*
Y236694D01*
X1329783Y236304D01*
Y233532D01*
X1331006Y232309D01*
X1331559D01*
X1332295Y231572D01*
Y231021D01*
X1333030Y230286D01*
X1333582D01*
X1334318Y229549D01*
Y228998D01*
X1335053Y228263D01*
Y217655D01*
X1335052Y217654D01*
X1335682Y217024D01*
X1336177D01*
X1336527Y217374D01*
Y218499D01*
G01X1419371Y915466D02*
X1419357Y915452D01*
Y912960D01*
G03X1420450Y911005I2295J0D01*
G01X1420485Y910985D01*
G02X1421596Y909144I-1114J-1928D01*
G01Y908996D01*
G02X1420485Y907130I-2225J61D01*
G01X1420450Y907110D01*
G03X1419747Y905853I772J-1257D01*
G01X1419746D01*
Y905814D01*
G02X1418634Y903926I-2225J39D01*
G01X1418593Y903902D01*
G02X1416407Y903926I-1072J1951D01*
G03X1414933I-737J-1277D01*
G03X1414196Y902683I737J-1277D01*
G01Y902610D01*
G02X1413084Y900722I-2225J39D01*
G01X1413049Y900702D01*
G03X1412346Y899445I772J-1257D01*
G01Y899389D01*
G02X1411234Y897517I-2226J56D01*
G01X1411199Y897497D01*
G03X1410496Y896240I772J-1257D01*
G01Y896201D01*
G02X1409384Y894313I-2225J39D01*
G01X1409349Y894293D01*
G03X1408646Y893036I772J-1257D01*
G02X1407558Y891123I-2226J0D01*
G01X1407534Y891109D01*
X1407499Y891089D01*
G03X1406796Y889832I772J-1257D01*
G01Y889776D01*
G02X1405683Y887904I-2225J56D01*
G01X1405648Y887884D01*
G03X1404945Y886627I772J-1257D01*
G01Y886566D01*
G02X1403834Y884700I-2225J61D01*
G01X1403799Y884680D01*
G03Y882166I772J-1257D01*
G01X1403834Y882146D01*
G02X1404946Y880258I-1113J-1927D01*
G01Y880146D01*
G02X1403834Y878291I-2225J73D01*
G01X1403799Y878271D01*
G03X1403096Y877014I772J-1257D01*
G02X1402007Y875101I-2225J0D01*
G01X1401983Y875087D01*
X1401948Y875067D01*
G03X1401245Y873810I772J-1257D01*
G01Y873749D01*
G02X1400134Y871883I-2225J61D01*
G01X1400099Y871863D01*
G03X1399396Y870606I772J-1257D01*
G01Y870550D01*
G02X1398283Y868678I-2225J56D01*
G03X1397546Y867435I737J-1277D01*
G01Y867362D01*
G02X1396434Y865474I-2225J39D01*
G02X1394208I-1113J1927D01*
G03X1392734I-737J-1277D01*
G02X1390566Y865440I-1114J1927D01*
G01X1390508Y865474D01*
G03X1389034I-737J-1277D01*
G01X1388999Y865454D01*
G03X1388296Y864197I772J-1257D01*
G02X1387207Y862284I-2225J0D01*
G01X1387183Y862270D01*
X1387125Y862236D01*
G02X1384957Y862270I-1054J1961D01*
G03X1383483I-737J-1277D01*
G01X1383425Y862236D01*
G02X1381257Y862270I-1054J1961D01*
G03X1379783I-737J-1277D01*
G01X1379725Y862236D01*
G02X1377557Y862270I-1054J1961D01*
G03X1376083I-737J-1277D01*
G01X1376025Y862236D01*
G02X1373857Y862270I-1054J1961D01*
G03X1372383I-737J-1277D01*
G01X1372325Y862236D01*
G02X1370157Y862270I-1054J1961D01*
G03X1368683I-737J-1277D01*
G01X1368625Y862236D01*
G02X1366457Y862270I-1054J1961D01*
G03X1364983I-737J-1277D01*
G01X1364925Y862236D01*
G02X1362757Y862270I-1054J1961D01*
G03X1361283I-737J-1277D01*
G01X1361225Y862236D01*
G02X1359057Y862270I-1054J1961D01*
G03X1357583I-737J-1277D01*
G01X1357525Y862236D01*
G02X1355357Y862270I-1054J1961D01*
G03X1353883I-737J-1277D01*
G01X1353825Y862236D01*
G02X1351657Y862270I-1054J1961D01*
G03X1350183I-737J-1277D01*
G01X1350125Y862236D01*
G02X1347957Y862270I-1054J1961D01*
G03X1346483I-737J-1277D01*
G01X1346425Y862236D01*
G02X1344257Y862270I-1054J1961D01*
G03X1342783I-737J-1277D01*
G01X1342725Y862236D01*
G02X1340557Y862270I-1054J1961D01*
G03X1339083I-737J-1277D01*
G01X1339025Y862236D01*
G02X1336857Y862270I-1054J1961D01*
G03X1335383I-737J-1277D01*
G01X1335325Y862236D01*
G02X1333157Y862270I-1054J1961D01*
G03X1331683I-737J-1277D01*
G01X1331625Y862236D01*
G02X1329457Y862270I-1054J1961D01*
G03X1327983I-737J-1277D01*
G03X1327246Y861027I737J-1277D01*
G01Y860954D01*
G02X1326134Y859066I-2225J39D01*
G01X1326099Y859046D01*
G03X1325396Y857789I772J-1257D01*
G01Y857733D01*
G02X1324283Y855861I-2225J56D01*
G01X1324248Y855841D01*
G03X1323545Y854584I772J-1257D01*
G01Y854545D01*
G02X1322433Y852657I-2225J39D01*
G01X1322398Y852637D01*
G03X1321695Y851380I772J-1257D01*
G02X1320607Y849467I-2226J0D01*
G01X1320583Y849453D01*
X1320548Y849433D01*
G03X1319845Y848176I772J-1257D01*
G01Y847135D01*
G01X1375404Y1063770D02*
X1376635D01*
X1376861Y1063544D01*
G02X1376176Y1062513I-1458J225D01*
G01X1376141Y1062493D01*
G02X1374667I-737J1277D01*
G03X1372499Y1062527I-1115J-1928D01*
G01X1372441Y1062493D01*
G02X1370967I-737J1277D01*
G03X1368799Y1062527I-1115J-1928D01*
G01X1368741Y1062493D01*
G02X1367267I-737J1277D01*
G03X1365081Y1062517I-1114J-1928D01*
G01X1365040Y1062493D01*
G02X1363566I-737J1277D01*
G01X1363525Y1062517D01*
G03X1361341Y1062493I-1071J-1952D01*
G02X1359867I-737J1277D01*
G03X1357699Y1062527I-1115J-1928D01*
G01X1357641Y1062493D01*
G02X1356167I-737J1277D01*
G03X1353999Y1062527I-1115J-1928D01*
G01X1353941Y1062493D01*
G02X1352467I-737J1277D01*
G03X1350299Y1062527I-1115J-1928D01*
G01X1350241Y1062493D01*
G02X1348767I-737J1277D01*
G03X1346599Y1062527I-1115J-1928D01*
G01X1346541Y1062493D01*
G02X1345067I-737J1277D01*
G03X1342899Y1062527I-1115J-1928D01*
G01X1342841Y1062493D01*
G02X1341367I-737J1277D01*
G03X1339181Y1062517I-1114J-1928D01*
G01X1339140Y1062493D01*
G02X1337666I-737J1277D01*
G01X1337625Y1062517D01*
G03X1335441Y1062493I-1071J-1952D01*
G02X1333967I-737J1277D01*
G03X1331781Y1062517I-1114J-1928D01*
G01X1331740Y1062493D01*
G02X1330266I-737J1277D01*
G03X1328040I-1113J-1928D01*
G02X1326566I-737J1277D01*
G03X1324340I-1113J-1928D01*
G02X1322866I-737J1277D01*
G03X1320640I-1113J-1928D01*
G01X1320505Y1062415D01*
G02X1319153Y1062491I-602J1355D01*
G01X1317281D01*
X1317150Y1062622D01*
G01X1382804Y1057361D02*
X1381573D01*
X1381314Y1057102D01*
G02X1380240Y1055448I-2210J259D01*
G01X1380216Y1055434D01*
X1380158Y1055400D01*
G02X1377990Y1055434I-1054J1961D01*
G03X1376516I-737J-1277D01*
G02X1374290I-1113J1927D01*
G03X1372816I-737J-1277D01*
G01X1372758Y1055400D01*
G02X1370590Y1055434I-1054J1961D01*
G03X1369116I-737J-1277D01*
G01X1369058Y1055400D01*
G02X1366890Y1055434I-1054J1961D01*
G03X1365416I-737J-1277D01*
G01X1365358Y1055400D01*
G02X1363190Y1055434I-1054J1961D01*
G03X1361716I-737J-1277D01*
G01X1361675Y1055410D01*
G02X1359491Y1055434I-1071J1951D01*
G03X1358017I-737J-1277D01*
G01X1357976Y1055410D01*
G02X1355790Y1055434I-1072J1951D01*
G03X1354316I-737J-1277D01*
G01X1354258Y1055400D01*
G02X1352090Y1055434I-1054J1961D01*
G03X1350616I-737J-1277D01*
G02X1348390I-1113J1927D01*
G03X1346916I-737J-1277D01*
G01X1346858Y1055400D01*
G02X1344690Y1055434I-1054J1961D01*
G03X1343216I-737J-1277D01*
G01X1343158Y1055400D01*
G02X1340990Y1055434I-1054J1961D01*
G03X1339516I-737J-1277D01*
G01X1339458Y1055400D01*
G02X1337290Y1055434I-1054J1961D01*
G03X1335816I-737J-1277D01*
G01X1335775Y1055410D01*
G02X1333591Y1055434I-1071J1951D01*
G03X1332117I-737J-1277D01*
G02X1329931Y1055410I-1114J1927D01*
G01X1329890Y1055434D01*
G03X1328416I-737J-1277D01*
G02X1326190I-1113J1927D01*
G03X1324716I-737J-1277D01*
G02X1322490I-1113J1927D01*
G03X1321016I-737J-1277D01*
G02X1319903Y1055136I-1112J1927D01*
G01X1316478D01*
X1316092Y1054750D01*
G01X1339727Y216649D02*
X1340805Y217270D01*
X1340895Y217606D01*
G02X1340863Y217682I2036J902D01*
G02X1341007Y219612I2072J816D01*
G03Y221086I-1280J737D01*
G02X1341008Y223310I1930J1111D01*
G03X1341128Y223578I-1283J735D01*
G03X1341155Y223740I-483J164D01*
G01Y233169D01*
X1341019Y233305D01*
Y233349D01*
G01X1346147Y212949D02*
X1345069Y213570D01*
X1344979Y213906D01*
G03X1345011Y213982I-2036J902D01*
G03X1344867Y215912I-2072J816D01*
G02Y217386I1280J737D01*
G03Y219612I-1930J1113D01*
G02Y221086I1280J737D01*
G03X1344875Y223299I-1930J1113D01*
G01X1344874Y223300D01*
G02X1344728Y223853I973J553D01*
G01Y227787D01*
X1346530Y231390D01*
Y232810D01*
X1346665Y232945D01*
Y233032D01*
G01X1346147Y216649D02*
Y217880D01*
X1346405Y218138D01*
G03X1346488Y218149I-251J2212D01*
G03X1348074Y219235I-341J2200D01*
G03X1348076Y219238I-1851J1236D01*
G01X1348074Y219239D01*
G03X1348073Y221461I-1927J1110D01*
G02X1347878Y222101I1277J739D01*
G02X1347875Y222193I1472J94D01*
G01Y227321D01*
X1349005Y228451D01*
X1349197D01*
X1349258Y228512D01*
G01X1342937Y214799D02*
X1344015Y214178D01*
X1344311Y214258D01*
X1344313Y214257D01*
X1344314Y214258D01*
G03X1344218Y215538I-1375J540D01*
G02Y217760I1929J1111D01*
G03Y219238I-1281J739D01*
G02Y221460I1929J1111D01*
G03X1344223Y222929I-1281J739D01*
G01X1344222Y222931D01*
G02X1343979Y223854I1625J921D01*
G01Y227964D01*
X1345781Y231567D01*
Y232809D01*
X1345645Y232945D01*
Y233032D01*
G01X1338290Y230929D02*
Y230842D01*
X1338155Y230707D01*
Y224601D01*
X1338956Y223800D01*
Y221960D01*
X1338628Y221390D01*
X1338756Y220910D01*
X1339727Y220349D01*
G01X1337270Y230929D02*
Y230842D01*
X1337406Y230706D01*
Y228284D01*
X1337016Y227894D01*
Y226854D01*
X1337406Y226464D01*
Y224291D01*
X1337405Y224290D01*
X1338206Y223489D01*
Y222239D01*
X1337908Y221792D01*
X1337425Y221680D01*
X1336527Y222199D01*
G01X1342937Y218499D02*
X1341859Y217878D01*
X1341563Y217958D01*
G02X1341657Y219236I1374J541D01*
G03Y221462I-1930J1113D01*
G02Y222936I1280J737D01*
G03X1341839Y223339I-1930J1114D01*
G03X1341904Y223738I-1195J399D01*
G01Y233127D01*
X1342039Y233262D01*
Y233349D01*
G01X1346147Y220349D02*
Y219118D01*
X1346373Y218892D01*
G03X1347404Y219577I-225J1458D01*
G01X1347424Y219612D01*
G03Y221086I-1277J737D01*
G02X1347130Y222052I1926J1114D01*
G02X1347126Y222196I2221J134D01*
G01Y222896D01*
X1346736Y223286D01*
Y223986D01*
X1347126Y224376D01*
Y225076D01*
X1346736Y225466D01*
Y226166D01*
X1347126Y226556D01*
Y227632D01*
X1348475Y228981D01*
Y229173D01*
X1348536Y229234D01*
G01X1357205Y225533D02*
X1357144Y225472D01*
X1356952D01*
X1354722Y223242D01*
G03X1354489Y222935I1049J-1038D01*
G03Y221461I1277J-737D01*
G02Y219235I-1928J-1113D01*
G01X1354447Y219162D01*
X1354424Y219112D01*
G03X1354489Y217761I1342J-613D01*
G02X1354601Y215754I-1928J-1114D01*
G01X1354690Y215419D01*
X1355766Y214798D01*
G01X1356483Y226255D02*
X1356422Y226194D01*
Y226002D01*
X1356023Y225603D01*
X1354190Y223771D01*
G03X1353839Y223308I1583J-1564D01*
G03X1353840Y221087I1927J-1110D01*
G02Y219609I-1279J-739D01*
G01X1353780Y219506D01*
X1353743Y219424D01*
G03X1353840Y217386I2023J-925D01*
G02X1353935Y216106I-1279J-738D01*
G01X1353932Y216107D01*
X1353637Y216027D01*
X1352561Y216648D01*
G01Y220348D02*
X1351483Y219727D01*
X1351187Y219807D01*
G02X1351281Y221085I1374J541D01*
G03X1351579Y222197I-1930J1113D01*
G01Y225016D01*
X1353498Y226935D01*
X1353690D01*
X1353751Y226996D01*
G01X1358181Y220940D02*
X1358094D01*
X1357958Y220804D01*
X1356116D01*
X1355766Y221154D01*
Y222198D01*
G01X1349351Y218498D02*
X1350429Y219119D01*
X1350519Y219455D01*
G02X1350487Y219531I2036J902D01*
G02X1350631Y221460I2072J815D01*
G03X1350829Y222198I-1280J739D01*
G01Y225326D01*
X1352968Y227465D01*
Y227657D01*
X1353029Y227718D01*
G01X1358181Y219920D02*
X1358094D01*
X1357959Y220055D01*
X1356117D01*
X1355766Y219704D01*
Y218498D01*
G01X1486721Y838075D02*
Y838711D01*
X1486346Y839086D01*
Y842102D01*
G02X1487071Y842887I1475J-635D01*
G03X1488194Y844192I-1102J2084D01*
G01Y845058D01*
G03X1487083Y846899I-2225J-87D01*
G01X1487048Y846919D01*
G02X1486346Y848118I772J1257D01*
G01Y848140D01*
G02X1486345Y848154I354J32D01*
G01Y848237D01*
G03X1485234Y850103I-2225J-61D01*
G01X1485199Y850123D01*
G02Y852637I772J1257D01*
G01X1485234Y852657D01*
G03X1486346Y854545I-1113J1927D01*
G01Y854618D01*
G02X1487083Y855861I1474J-34D01*
G03X1488196Y857733I-1112J1928D01*
G01Y857789D01*
G02X1488899Y859046I1475J0D01*
G01X1488934Y859066D01*
G03X1490045Y860932I-1114J1927D01*
G01Y861054D01*
G03X1488934Y862920I-2225J-61D01*
G03X1486766Y862954I-1114J-1927D01*
G01X1486708Y862920D01*
G02X1485234I-737J1277D01*
G01X1485199Y862940D01*
G02X1484496Y864197I772J1257D01*
G01Y864236D01*
G03X1483384Y866124I-2225J-39D01*
G01X1483343Y866148D01*
G03X1481157Y866124I-1072J-1951D01*
G02X1479683I-737J1277D01*
G01X1479642Y866148D01*
G03X1477458Y866124I-1071J-1951D01*
G02X1475984I-737J1277D01*
G01X1475981Y866126D01*
X1475949Y866144D01*
G02Y868658I772J1257D01*
G01X1475981Y868676D01*
X1475984Y868678D01*
G03X1473757Y872533I-1113J1928D01*
G02X1471545Y873810I-737J1277D01*
G01Y873871D01*
G03X1470434Y875737I-2225J-61D01*
G01X1470399Y875757D01*
G02X1469696Y877014I772J1257D01*
G01Y877087D01*
G03X1466357Y878942I-2225J-73D01*
G02X1464883I-737J1277D01*
G01X1464842Y878966D01*
G03X1462658Y878942I-1071J-1952D01*
G02X1461184I-737J1277D01*
G01X1461143Y878966D01*
G03X1458957Y878942I-1072J-1952D01*
G02X1457483I-737J1277D01*
G01X1457442Y878966D01*
G03X1455258Y878942I-1071J-1952D01*
G02X1453784I-737J1277D01*
G01X1453743Y878966D01*
G03X1451557Y878942I-1072J-1952D01*
G02X1450083I-737J1277D01*
G01X1450042Y878966D01*
G03X1447858Y878942I-1071J-1952D01*
G02X1446384I-737J1277D01*
G01X1446343Y878966D01*
G03X1444157Y878942I-1072J-1952D01*
G02X1442683I-737J1277D01*
G01X1442642Y878966D01*
G03X1440458Y878942I-1071J-1952D01*
G02X1438984I-737J1277D01*
G01X1438943Y878966D01*
G03X1436757Y878942I-1072J-1952D01*
G02X1435283I-737J1277D01*
G01X1435242Y878966D01*
G03X1433058Y878942I-1071J-1952D01*
G02X1431584I-737J1277D01*
G03X1429358I-1113J-1928D01*
G02X1427884I-737J1277D01*
G03X1425658I-1113J-1928D01*
G02X1424184I-737J1277D01*
G01X1424143Y878966D01*
G03X1421957Y878942I-1072J-1952D01*
G02X1420483I-737J1277D01*
G01X1420442Y878966D01*
G03X1417146Y877087I-1071J-1952D01*
G01Y877014D01*
G02X1414934Y875737I-1475J0D01*
G03X1412708I-1113J-1927D01*
G02X1411234I-737J1277D01*
G03X1407910Y874069I-1113J-1928D01*
G01X1407651Y873810D01*
X1406420D01*
G01X1413820Y925079D02*
X1410968Y923866D01*
X1410858Y923802D01*
G02X1409384I-737J1276D01*
G01X1409343Y923826D01*
G03X1407157Y923802I-1072J-1951D01*
G02X1405683I-737J1277D01*
G03X1404571Y924100I-1112J-1926D01*
G01X1485221Y838075D02*
Y838723D01*
X1485596Y839098D01*
Y842246D01*
G02X1486719Y843551I2225J-779D01*
G03X1487444Y844336I-750J1420D01*
G01Y844971D01*
G03X1486741Y846228I-1475J0D01*
G01X1486706Y846248D01*
G02X1485595Y848089I1114J1928D01*
G01Y848217D01*
G03X1484859Y849452I-1475J-42D01*
G01X1484817Y849476D01*
G02Y853283I1154J1903D01*
G01X1484860Y853308D01*
G03X1485596Y854553I-739J1277D01*
G01Y854626D01*
G02X1486708Y856511I2224J-42D01*
G03X1487446Y857744I-737J1278D01*
G01Y857789D01*
G02X1488517Y859693I2226J1D01*
G01X1488560Y859717D01*
G03X1489295Y860944I-740J1277D01*
G01Y861042D01*
G03X1488558Y862270I-1475J-50D01*
G03X1487132Y862299I-739J-1277D01*
G01X1487086Y862271D01*
G02X1483746Y864197I-1115J1926D01*
G01Y864228D01*
G03X1483008Y865474I-1475J-32D01*
G01X1483006Y865475D01*
X1482973Y865494D01*
G03X1481532Y865474I-703J-1297D01*
G02X1479306Y865475I-1112J1927D01*
G01X1479272Y865494D01*
G03X1477833Y865474I-702J-1297D01*
G02X1475556Y869297I-1112J1927D01*
G01X1475581Y869312D01*
X1475613Y869330D01*
G03X1474132Y871883I-742J1275D01*
G02X1470795Y873809I-1112J1927D01*
G01Y873859D01*
G03X1470059Y875086I-1475J-50D01*
G01X1470017Y875110D01*
G02X1468946Y877014I1155J1903D01*
G01Y877073D01*
G03X1466732Y878292I-1475J-59D01*
G02X1464506Y878293I-1112J1927D01*
G01X1464473Y878312D01*
G03X1463033Y878292I-702J-1298D01*
G02X1460807Y878293I-1112J1927D01*
G01X1460773Y878312D01*
G03X1459332Y878292I-703J-1298D01*
G02X1457106Y878293I-1112J1927D01*
G01X1457073Y878312D01*
G03X1455633Y878292I-702J-1298D01*
G02X1453407Y878293I-1112J1927D01*
G01X1453373Y878312D01*
G03X1451932Y878292I-703J-1298D01*
G02X1449706Y878293I-1112J1927D01*
G01X1449673Y878312D01*
G03X1448233Y878292I-702J-1298D01*
G02X1446007Y878293I-1112J1927D01*
G01X1445973Y878312D01*
G03X1444532Y878292I-703J-1298D01*
G02X1442306Y878293I-1112J1927D01*
G01X1442273Y878312D01*
G03X1440833Y878292I-702J-1298D01*
G02X1438607Y878293I-1112J1927D01*
G01X1438573Y878312D01*
G03X1437132Y878292I-703J-1298D01*
G02X1434906Y878293I-1112J1927D01*
G01X1434873Y878312D01*
G03X1433433Y878292I-702J-1298D01*
G02X1431209I-1112J1927D01*
G03X1429733I-738J-1278D01*
G02X1427509I-1112J1927D01*
G03X1426033I-738J-1278D01*
G02X1423807Y878293I-1112J1927D01*
G01X1423773Y878312D01*
G03X1422332Y878292I-703J-1298D01*
G02X1420106Y878293I-1112J1927D01*
G01X1420073Y878312D01*
G03X1417896Y877073I-702J-1298D01*
G01Y877014D01*
G02X1415660Y874789I-2225J0D01*
G01X1414800D01*
X1413821Y873810D01*
G01X1479321Y838203D02*
Y838921D01*
X1478946Y839296D01*
Y842102D01*
G02X1479671Y842887I1475J-635D01*
G03X1480794Y844192I-1102J2084D01*
G01Y845058D01*
G03X1479683Y846899I-2225J-87D01*
G01X1479336Y847110D01*
G02X1478960Y847753I414J674D01*
G01X1478946Y848118D01*
G02X1478945Y848172I1468J54D01*
G01Y848177D01*
G03X1477834Y850103I-2224J0D01*
G02X1477835Y852657I738J1277D01*
G03X1478946Y854545I-1114J1927D01*
G01Y854618D01*
G02X1479683Y855861I1474J-34D01*
G03X1480796Y857733I-1112J1928D01*
G01Y857789D01*
G02X1481499Y859046I1475J0D01*
G01X1481534Y859066D01*
G03X1482645Y860932I-1114J1927D01*
G01Y861054D01*
G03X1481534Y862920I-2225J-61D01*
G03X1479366Y862954I-1114J-1927D01*
G01X1479308Y862920D01*
G02X1477834I-737J1277D01*
G03X1475666Y862954I-1114J-1927D01*
G01X1475608Y862920D01*
G02X1474134I-737J1277D01*
G03X1471966Y862954I-1114J-1927D01*
G01X1471908Y862920D01*
G02X1470434I-737J1277D01*
G01X1470399Y862940D01*
G02X1469696Y864197I772J1257D01*
G01Y864236D01*
G03X1468584Y866124I-2225J-39D01*
G01X1468543Y866148D01*
G03X1466357Y866124I-1072J-1951D01*
G02X1464883I-737J1277D01*
G02X1464146Y867367I737J1277D01*
G01Y867435D01*
G02X1464883Y868678I1474J-34D01*
G03X1465996Y870550I-1112J1928D01*
G01Y870606D01*
G02X1466699Y871863I1475J0D01*
G01X1466734Y871883D01*
G03X1467845Y873749I-1114J1927D01*
G01Y873871D01*
G03X1466734Y875737I-2225J-61D01*
G03X1464566Y875771I-1114J-1927D01*
G01X1464508Y875737D01*
G02X1463034I-737J1277D01*
G03X1460866Y875771I-1114J-1927D01*
G01X1460808Y875737D01*
G02X1459334I-737J1277D01*
G03X1457166Y875771I-1114J-1927D01*
G01X1457108Y875737D01*
G02X1455634I-737J1277D01*
G03X1453466Y875771I-1114J-1927D01*
G01X1453408Y875737D01*
G02X1451934I-737J1277D01*
G03X1449766Y875771I-1114J-1927D01*
G01X1449708Y875737D01*
G02X1448234I-737J1277D01*
G03X1446008I-1113J-1927D01*
G02X1444534I-737J1277D01*
G03X1442366Y875771I-1114J-1927D01*
G01X1442308Y875737D01*
G02X1440834I-737J1277D01*
G03X1438666Y875771I-1114J-1927D01*
G01X1438608Y875737D01*
G02X1437134I-737J1277D01*
G03X1434966Y875771I-1114J-1927D01*
G01X1434908Y875737D01*
G02X1433434I-737J1277D01*
G03X1431266Y875771I-1114J-1927D01*
G01X1431208Y875737D01*
G02X1429734I-737J1278D01*
G03X1427508I-1113J-1927D01*
G02X1426034I-737J1277D01*
G03X1423808I-1113J-1927D01*
G01X1423760Y875709D01*
G03X1422710Y874069I1161J-1899D01*
G01X1422451Y873810D01*
X1421220D01*
G01X1524966Y878060D02*
X1524084Y878942D01*
G03X1521916Y878976I-1115J-1928D01*
G01X1521858Y878942D01*
G02X1520384I-737J1277D01*
G03X1518158I-1113J-1928D01*
G02X1516684I-737J1277D01*
G03X1514498Y878966I-1114J-1928D01*
G01X1514457Y878942D01*
G02X1512983I-737J1277D01*
G01X1512942Y878966D01*
G03X1510758Y878942I-1071J-1952D01*
G02X1509284I-737J1277D01*
G03X1507058I-1113J-1928D01*
G02X1505584I-737J1277D01*
G03X1503358I-1113J-1928D01*
G02X1501884I-737J1277D01*
G03X1499658I-1113J-1928D01*
G02X1498184I-737J1277D01*
G01X1498143Y878966D01*
G03X1495957Y878942I-1072J-1952D01*
G02X1494483I-737J1277D01*
G01X1494442Y878966D01*
G03X1492258Y878942I-1071J-1952D01*
G02X1490784I-737J1277D01*
G01X1490743Y878966D01*
G03X1488557Y878942I-1072J-1952D01*
G02X1487083I-737J1277D01*
G01X1487042Y878966D01*
G03X1484858Y878942I-1071J-1952D01*
G02X1483384I-737J1277D01*
G01X1483343Y878966D01*
G03X1481157Y878942I-1072J-1952D01*
G02X1479683I-737J1277D01*
G01X1479642Y878966D01*
G03X1477458Y878942I-1071J-1952D01*
G02X1475984I-737J1277D01*
G01X1475943Y878966D01*
G03X1473757Y878942I-1072J-1952D01*
G01X1473230Y878415D01*
X1472137D01*
X1471397Y879155D01*
Y880625D01*
X1469827Y882195D01*
X1468807D01*
X1468287Y881675D01*
X1466697D01*
X1465597Y882775D01*
Y883835D01*
X1464257Y885175D01*
X1462897D01*
X1462117Y884395D01*
Y882975D01*
X1460447Y881305D01*
X1459667D01*
X1458437Y882535D01*
Y884055D01*
X1457137Y885355D01*
X1455547D01*
X1454247Y884055D01*
Y882825D01*
X1452947Y881525D01*
X1451867D01*
X1450887Y882505D01*
Y884345D01*
X1449777Y885455D01*
X1448147D01*
X1446947Y884255D01*
Y882585D01*
X1445817Y881455D01*
X1444737D01*
X1443607Y882585D01*
Y884125D01*
X1442477Y885255D01*
X1440697D01*
X1439517Y884075D01*
Y882315D01*
X1439047Y881845D01*
X1437445D01*
X1437158Y882132D01*
X1437134Y882146D01*
X1437099Y882166D01*
G02X1436396Y883423I772J1257D01*
G03X1435307Y885336I-2225J0D01*
G01X1435283Y885350D01*
X1435248Y885370D01*
G02X1434545Y886627I772J1257D01*
G01Y886714D01*
G03X1433434Y888555I-2225J-87D01*
G01X1433399Y888575D01*
G02X1432696Y889832I772J1257D01*
G01Y889871D01*
G03X1431584Y891759I-2225J-39D01*
G01X1431549Y891779D01*
G02X1430846Y893036I772J1257D01*
G01Y893075D01*
G03X1429734Y894963I-2225J-39D01*
G02Y897517I738J1277D01*
G03X1430845Y899442I-1112J1925D01*
G01Y899506D01*
G03X1429734Y901372I-2225J-61D01*
G01X1429699Y901392D01*
G02X1428996Y902649I772J1257D01*
G01Y902688D01*
G03X1427884Y904576I-2225J-39D01*
G01X1427849Y904596D01*
G02X1427146Y905853I772J1257D01*
G01Y905914D01*
G03X1426035Y907780I-2225J-61D01*
G01X1426000Y907800D01*
G02X1425297Y909057I772J1257D01*
G01Y909113D01*
G03X1424185Y910985I-2226J-56D01*
G01X1424150Y911005D01*
G02X1423447Y912262I772J1257D01*
G03X1422358Y914175I-2225J0D01*
G01X1422334Y914189D01*
X1422299Y914209D01*
G02X1421596Y915466I772J1257D01*
G03X1420507Y917379I-2225J0D01*
G01X1420483Y917393D01*
X1420448Y917413D01*
G02X1419745Y918670I772J1257D01*
G01Y918757D01*
G03X1418634Y920598I-2225J-87D01*
G03X1416637Y920715I-1115J-1928D01*
G01X1416287Y920808D01*
X1415671Y921875D01*
G01X1526566Y878605D02*
X1523973Y881198D01*
X1522957D01*
G02X1521858Y881496I13J2225D01*
G03X1520384I-737J-1277D01*
G02X1518158I-1113J1927D01*
G03X1516684I-737J-1277D01*
G01X1516643Y881472D01*
G02X1513346Y883362I-1072J1951D01*
G01Y883423D01*
G03X1512643Y884680I-1475J0D01*
G01X1512608Y884700D01*
G02X1511496Y886588I1113J1927D01*
G01Y886627D01*
G03X1509284Y887904I-1475J0D01*
G02X1507058I-1113J1928D01*
G03X1505584I-737J-1277D01*
G02X1503358I-1113J1928D01*
G03X1501884I-737J-1277D01*
G01X1501843Y887880D01*
G02X1499657Y887904I-1072J1952D01*
G03X1498183I-737J-1277D01*
G01X1498125Y887870D01*
G02X1495957Y887904I-1053J1962D01*
G03X1494483I-737J-1277D01*
G01X1494425Y887870D01*
G02X1492257Y887904I-1053J1962D01*
G03X1490783I-737J-1277D01*
G01X1490725Y887870D01*
G02X1488557Y887904I-1053J1962D01*
G03X1487083I-737J-1277D01*
G01X1487025Y887870D01*
G02X1484857Y887904I-1053J1962D01*
G03X1483383I-737J-1277D01*
G01X1483325Y887870D01*
G02X1481157Y887904I-1053J1962D01*
G03X1479683I-737J-1277D01*
G01X1479625Y887870D01*
G02X1477457Y887904I-1053J1962D01*
G03X1475983I-737J-1277D01*
G01X1475925Y887870D01*
G02X1473757Y887904I-1053J1962D01*
G03X1472283I-737J-1277D01*
G01X1472225Y887870D01*
G02X1470057Y887904I-1053J1962D01*
G03X1468583I-737J-1277D01*
G01X1468525Y887870D01*
G02X1466357Y887904I-1053J1962D01*
G03X1464883I-737J-1277D01*
G01X1464825Y887870D01*
G02X1462657Y887904I-1053J1962D01*
G03X1461183I-737J-1277D01*
G01X1461125Y887870D01*
G02X1458957Y887904I-1053J1962D01*
G03X1457483I-737J-1277D01*
G01X1457425Y887870D01*
G02X1455257Y887904I-1053J1962D01*
G03X1453783I-737J-1277D01*
G01X1453725Y887870D01*
G02X1451557Y887904I-1053J1962D01*
G03X1450083I-737J-1277D01*
G01X1450025Y887870D01*
G02X1447857Y887904I-1053J1962D01*
G03X1446383I-737J-1277D01*
G01X1446325Y887870D01*
G02X1444157Y887904I-1053J1962D01*
G03X1442683I-737J-1277D01*
G01X1442625Y887870D01*
G02X1439346Y889745I-1054J1962D01*
G01Y889832D01*
G03X1438643Y891089I-1475J0D01*
G01X1438560Y891137D01*
G02X1437495Y893036I1161J1899D01*
G03X1436792Y894293I-1475J0D01*
G01X1436757Y894313D01*
G02X1435646Y896179I1114J1927D01*
G01Y896240D01*
G03X1434943Y897497I-1475J0D01*
G01X1434908Y897517D01*
G02X1433795Y899389I1112J1928D01*
G01Y899445D01*
G03X1433092Y900702I-1475J0D01*
G01X1433057Y900722D01*
G02X1431946Y902588I1114J1927D01*
G01Y902649D01*
G03X1431243Y903906I-1475J0D01*
G01X1431184Y903940D01*
G02X1430095Y905853I1136J1913D01*
G01Y905887D01*
G03X1429358Y907130I-1474J-34D01*
G02X1428246Y909018I1113J1927D01*
G01Y909057D01*
G03X1427521Y910327I-1475J0D01*
G01X1427508Y910334D01*
G02X1426396Y912175I1112J1928D01*
G01Y912296D01*
G03X1425659Y913539I-1474J-34D01*
G01X1425635Y913553D01*
G02X1424546Y915466I1136J1913D01*
G03X1423843Y916723I-1475J0D01*
G01X1423760Y916771D01*
G02X1422695Y918670I1161J1899D01*
G03X1420687Y920044I-1474J0D01*
G01X1420604Y919737D01*
X1421220Y918670D01*
G01X1527916Y879125D02*
X1525082Y881959D01*
X1523148D01*
G02X1522234Y882146I-177J1464D01*
G03X1520008I-1113J-1927D01*
G02X1518534I-737J1277D01*
G03X1516308I-1113J-1927D01*
G02X1514096Y883423I-737J1277D01*
G01Y883462D01*
G03X1512984Y885350I-2225J-39D01*
G01X1512949Y885370D01*
G02X1512246Y886627I772J1257D01*
G01Y886700D01*
G03X1508908Y888555I-2225J-73D01*
G02X1507434I-737J1277D01*
G03X1505208I-1113J-1928D01*
G02X1503734I-737J1277D01*
G03X1501508I-1113J-1928D01*
G02X1500034I-737J1277D01*
G03X1497866Y888589I-1115J-1928D01*
G01X1497808Y888555D01*
G02X1496334I-737J1277D01*
G03X1494166Y888589I-1115J-1928D01*
G01X1494108Y888555D01*
G02X1492634I-737J1277D01*
G03X1490466Y888589I-1115J-1928D01*
G01X1490408Y888555D01*
G02X1488934I-737J1277D01*
G03X1486766Y888589I-1115J-1928D01*
G01X1486708Y888555D01*
G02X1485234I-737J1277D01*
G03X1483066Y888589I-1115J-1928D01*
G01X1483008Y888555D01*
G02X1481534I-737J1277D01*
G03X1479366Y888589I-1115J-1928D01*
G01X1479308Y888555D01*
G02X1477834I-737J1277D01*
G03X1475666Y888589I-1115J-1928D01*
G01X1475608Y888555D01*
G02X1474134I-737J1277D01*
G03X1471966Y888589I-1115J-1928D01*
G01X1471908Y888555D01*
G02X1470434I-737J1277D01*
G03X1468266Y888589I-1115J-1928D01*
G01X1468208Y888555D01*
G02X1466734I-737J1277D01*
G03X1464566Y888589I-1115J-1928D01*
G01X1464508Y888555D01*
G02X1463034I-737J1277D01*
G03X1460866Y888589I-1115J-1928D01*
G01X1460808Y888555D01*
G02X1459334I-737J1277D01*
G03X1457166Y888589I-1115J-1928D01*
G01X1457108Y888555D01*
G02X1455634I-737J1277D01*
G03X1453466Y888589I-1115J-1928D01*
G01X1453408Y888555D01*
G02X1451934I-737J1277D01*
G03X1449766Y888589I-1115J-1928D01*
G01X1449708Y888555D01*
G02X1448234I-737J1277D01*
G03X1446066Y888589I-1115J-1928D01*
G01X1446008Y888555D01*
G02X1444534I-737J1277D01*
G03X1442366Y888589I-1115J-1928D01*
G01X1442308Y888555D01*
G02X1440096Y889832I-737J1277D01*
G01Y889871D01*
G03X1438984Y891759I-2225J-39D01*
G01X1438949Y891779D01*
G02X1438246Y893036I772J1257D01*
G03X1437158Y894949I-2226J0D01*
G01X1437099Y894983D01*
G02X1436396Y896240I772J1257D01*
G01Y896296D01*
G03X1435283Y898168I-2225J-56D01*
G01X1435248Y898188D01*
G02X1434545Y899445I772J1257D01*
G01Y899506D01*
G03X1433434Y901372I-2225J-61D01*
G01X1433399Y901392D01*
G02X1432696Y902649I772J1257D01*
G03X1431607Y904562I-2225J0D01*
G01X1431583Y904576D01*
G02X1430846Y905819I737J1277D01*
G01Y905892D01*
G03X1429734Y907780I-2225J-39D01*
G02X1428997Y909023I737J1277D01*
G01Y909113D01*
G03X1427884Y910985I-2225J-56D01*
G01X1427871Y910992D01*
G02X1427146Y912262I750J1270D01*
G01Y912323D01*
G03X1426034Y914189I-2224J-61D01*
G01X1425999Y914209D01*
G02X1425296Y915466I772J1257D01*
G01Y915505D01*
G03X1424184Y917393I-2225J-39D01*
G01X1424149Y917413D01*
G02X1423446Y918670I772J1257D01*
G01Y918726D01*
G03X1420337Y920715I-2226J-56D01*
G01X1419987Y920808D01*
X1419371Y921875D01*
G01X1429355Y923802D02*
G02X1427947Y923764I-739J1277D01*
G01X1427881Y923802D01*
X1427810Y923843D01*
G03X1425658Y923802I-1039J-1968D01*
G02X1424184I-737J1277D01*
G01X1424072Y923868D01*
X1421220Y925079D01*
G01X1438304Y1076587D02*
X1437073D01*
X1436815Y1076845D01*
G03X1435717Y1078514I-2210J-258D01*
G01X1435682Y1078534D01*
G02X1434979Y1079791I772J1257D01*
G03X1433890Y1081704I-2225J0D01*
G01X1433866Y1081718D01*
X1433825Y1081742D01*
G03X1431641Y1081718I-1071J-1951D01*
G02X1430167I-737J1277D01*
G03X1427999Y1081752I-1114J-1927D01*
G01X1427941Y1081718D01*
G02X1426467I-737J1277D01*
G03X1424281Y1081742I-1114J-1927D01*
G01X1424240Y1081718D01*
G03X1423128Y1079830I1113J-1927D01*
G01Y1079752D01*
G03X1424240Y1077864I2225J39D01*
G01X1424275Y1077844D01*
G02Y1075330I-772J-1257D01*
G01X1424240Y1075310D01*
G03X1423128Y1073422I1113J-1927D01*
G01Y1073310D01*
G03X1424240Y1071455I2225J73D01*
G01X1424275Y1071435D01*
G02Y1068921I-772J-1257D01*
G01X1424240Y1068901D01*
G03X1423128Y1067013I1113J-1927D01*
G01Y1066935D01*
G03X1424240Y1065047I2225J39D01*
G01X1424275Y1065027D01*
G02X1424978Y1063770I-772J-1257D01*
G01Y1063714D01*
G03X1426091Y1061842I2225J56D01*
G01X1426104Y1061835D01*
G02X1426829Y1060565I-750J-1270D01*
G01Y1060504D01*
G03X1427941Y1058638I2224J61D01*
G01X1427976Y1058618D01*
G02X1428679Y1057361I-772J-1257D01*
G01Y1057300D01*
G03X1429790Y1055434I2225J61D01*
G01X1429825Y1055414D01*
G02X1430528Y1054157I-772J-1257D01*
G01Y1054101D01*
G03X1431641Y1052229I2225J56D01*
G03X1433865I1112J1928D01*
G01X1433898Y1052248D01*
G02X1435340Y1052229I704J-1296D01*
G03X1437526Y1052205I1114J1928D01*
G01X1437567Y1052229D01*
G02X1439041I737J-1277D01*
G03X1441265I1112J1928D01*
G01X1441298Y1052248D01*
G02X1442740Y1052229I704J-1296D01*
G03X1444908Y1052195I1115J1928D01*
G01X1444966Y1052229D01*
G02X1446440I737J-1277D01*
G01X1446481Y1052205D01*
G03X1448667Y1052229I1072J1952D01*
G02X1450141I737J-1277D01*
G03X1452325Y1052205I1113J1928D01*
G01X1452366Y1052229D01*
G02X1453840I737J-1277D01*
G03X1456026Y1052205I1114J1928D01*
G01X1456067Y1052229D01*
G02X1457541I737J-1277D01*
G01X1457599Y1052195D01*
G03X1459767Y1052229I1053J1962D01*
G02X1461241I737J-1277D01*
G01X1461299Y1052195D01*
G03X1463467Y1052229I1053J1962D01*
G02X1464941I737J-1277D01*
G01X1464999Y1052195D01*
G03X1467167Y1052229I1053J1962D01*
G02X1468641I737J-1277D01*
G01X1468682Y1052205D01*
G03X1470866Y1052229I1071J1952D01*
G02X1472340I737J-1277D01*
G01X1472381Y1052205D01*
G03X1474567Y1052229I1072J1952D01*
G02X1476041I737J-1277D01*
G01X1476099Y1052195D01*
G03X1478267Y1052229I1053J1962D01*
G02X1479741I737J-1277D01*
G01X1479799Y1052195D01*
G03X1481967Y1052229I1053J1962D01*
G02X1483441I737J-1277D01*
G01X1483499Y1052195D01*
G03X1485667Y1052229I1053J1962D01*
G02X1487141I737J-1277D01*
G01X1487199Y1052195D01*
G03X1489367Y1052229I1053J1962D01*
G02X1490841I737J-1277D01*
G01X1490899Y1052195D01*
G03X1493067Y1052229I1053J1962D01*
G02X1494541I737J-1277D01*
G03X1496725Y1052205I1113J1928D01*
G01X1496766Y1052229D01*
G02X1498240I737J-1277D01*
G03X1500466I1113J1928D01*
G02X1501940I737J-1277D01*
G01X1501981Y1052205D01*
G03X1504167Y1052229I1072J1952D01*
G02X1505641I737J-1277D01*
G01X1505663Y1052216D01*
G03X1507867Y1052230I1090J1941D01*
G02X1509341I737J-1277D01*
G01X1509409Y1052191D01*
G03X1511566Y1052229I1044J1966D01*
G02X1513040I737J-1277D01*
G03X1514806Y1051756I1766J3060D01*
G01X1525994D01*
X1526932Y1050818D01*
X1527931D01*
G01X1523181Y1036495D02*
X1521307D01*
X1520776Y1036184D01*
G02X1518590Y1036208I-1072J1952D01*
G03X1517116I-737J-1277D01*
G02X1514890I-1113J1928D01*
G03X1513416I-737J-1277D01*
G02X1511190I-1113J1928D01*
G03X1509716I-737J-1277D01*
G02X1507490I-1113J1928D01*
G03X1506016I-737J-1277D01*
G01X1505958Y1036174D01*
G02X1503790Y1036208I-1053J1962D01*
G03X1502316I-737J-1277D01*
G01X1502258Y1036174D01*
G02X1500090Y1036208I-1053J1962D01*
G03X1498616I-737J-1277D01*
G01X1498575Y1036184D01*
G02X1496391Y1036208I-1071J1952D01*
G03X1494917I-737J-1277D01*
G01X1494876Y1036184D01*
G02X1492690Y1036208I-1072J1952D01*
G03X1491216I-737J-1277D01*
G01X1491158Y1036174D01*
G02X1488990Y1036208I-1053J1962D01*
G03X1487516I-737J-1277D01*
G02X1485290I-1113J1928D01*
G03X1483816I-737J-1277D01*
G01X1483758Y1036174D01*
G02X1481590Y1036208I-1053J1962D01*
G03X1480116I-737J-1277D01*
G01X1480058Y1036174D01*
G02X1477890Y1036208I-1053J1962D01*
G03X1476416I-737J-1277D01*
G01X1476358Y1036174D01*
G02X1474190Y1036208I-1053J1962D01*
G03X1472716I-737J-1277D01*
G01X1472675Y1036184D01*
G02X1470491Y1036208I-1071J1952D01*
G03X1469017I-737J-1277D01*
G01X1468976Y1036184D01*
G02X1466790Y1036208I-1072J1952D01*
G03X1465316I-737J-1277D01*
G01X1465258Y1036174D01*
G02X1463090Y1036208I-1053J1962D01*
G03X1461616I-737J-1277D01*
G02X1459432Y1036184I-1113J1928D01*
G01X1459391Y1036208D01*
G03X1457917I-737J-1277D01*
G01X1457876Y1036184D01*
G02X1455690Y1036208I-1072J1952D01*
G03X1454952Y1036409I-744J-1275D01*
G01X1454011D01*
X1450575Y1039845D01*
X1446823D01*
X1445328Y1041340D01*
G03X1444625Y1042597I-1475J0D01*
G01X1444590Y1042617D01*
G03X1443116I-737J-1277D01*
G02X1440890I-1113J1927D01*
G03X1439416I-737J-1277D01*
G01X1439358Y1042583D01*
G02X1437190Y1042617I-1054J1961D01*
G03X1435716I-737J-1277D01*
G01X1435658Y1042583D01*
G02X1433490Y1042617I-1054J1961D01*
G02X1432379Y1044483I1114J1927D01*
G01Y1044544D01*
G03X1431676Y1045801I-1475J0D01*
G01X1431641Y1045821D01*
G02X1430528Y1047693I1112J1928D01*
G01Y1047749D01*
G03X1429846Y1048993I-1476J0D01*
G01X1429790Y1049025D01*
G02X1428679Y1050891I1114J1927D01*
G01Y1050952D01*
G03X1428128Y1052101I-1475J-1D01*
G01X1427820Y1052019D01*
X1427203Y1050952D01*
G01X1434604Y1076587D02*
X1435835D01*
X1436061Y1076813D01*
G03X1435376Y1077844I-1458J-225D01*
G01X1435341Y1077864D01*
G02X1434229Y1079752I1113J1927D01*
G01Y1079791D01*
G03X1433526Y1081048I-1475J0D01*
G01X1433491Y1081068D01*
G03X1432017I-737J-1277D01*
G01X1431976Y1081044D01*
G02X1429790Y1081068I-1072J1951D01*
G03X1428316I-737J-1277D01*
G01X1428258Y1081034D01*
G02X1426090Y1081068I-1054J1961D01*
G03X1424616I-737J-1277D01*
G01X1424581Y1081048D01*
G03Y1078534I772J-1257D01*
G01X1424616Y1078514D01*
G02X1425728Y1076626I-1113J-1927D01*
G01Y1076548D01*
G02X1424616Y1074660I-2225J39D01*
G01X1424581Y1074640D01*
G03Y1072126I772J-1257D01*
G01X1424616Y1072106D01*
G02X1425729Y1070208I-1113J-1928D01*
G01Y1070178D01*
G02X1424664Y1068279I-2226J0D01*
G01X1424616Y1068251D01*
X1424581Y1068231D01*
G03Y1065717I772J-1257D01*
G01X1424616Y1065697D01*
G02X1425728Y1063809I-1113J-1927D01*
G01Y1063770D01*
G03X1426418Y1062521I1475J0D01*
G01X1426467Y1062493D01*
G02X1427579Y1060652I-1112J-1928D01*
G01Y1060531D01*
G03X1428316Y1059288I1474J34D01*
G01X1428340Y1059274D01*
G02X1429429Y1057361I-1136J-1913D01*
G03X1430132Y1056104I1475J0D01*
G01X1430167Y1056084D01*
G02X1431278Y1054218I-1114J-1927D01*
G01Y1054157D01*
G03X1431981Y1052900I1475J0D01*
G01X1432016Y1052880D01*
G03X1433490I737J1277D01*
G01X1433548Y1052914D01*
G02X1435716Y1052880I1053J-1962D01*
G03X1437158Y1052861I738J1277D01*
G01X1437191Y1052880D01*
G02X1439375Y1052904I1113J-1928D01*
G01X1439416Y1052880D01*
G03X1440890I737J1277D01*
G01X1440948Y1052914D01*
G02X1443116Y1052880I1053J-1962D01*
G03X1444558Y1052861I738J1277D01*
G01X1444591Y1052880D01*
X1444632Y1052904D01*
G02X1446816Y1052880I1071J-1952D01*
G03X1448290I737J1277D01*
G02X1450476Y1052904I1114J-1928D01*
G01X1450517Y1052880D01*
G03X1451991I737J1277D01*
G01X1452049Y1052914D01*
G02X1454217Y1052880I1053J-1962D01*
G03X1455691I737J1277D01*
G02X1457875Y1052904I1113J-1928D01*
G01X1457916Y1052880D01*
G03X1459390I737J1277D01*
G02X1461558Y1052914I1115J-1928D01*
G01X1461616Y1052880D01*
G03X1463090I737J1277D01*
G02X1465258Y1052914I1115J-1928D01*
G01X1465316Y1052880D01*
G03X1466790I737J1277D01*
G02X1468958Y1052914I1115J-1928D01*
G01X1469016Y1052880D01*
G03X1470490I737J1277D01*
G02X1472716I1113J-1928D01*
G03X1474190I737J1277D01*
G02X1476358Y1052914I1115J-1928D01*
G01X1476416Y1052880D01*
G03X1477890I737J1277D01*
G02X1480058Y1052914I1115J-1928D01*
G01X1480116Y1052880D01*
G03X1481590I737J1277D01*
G02X1483758Y1052914I1115J-1928D01*
G01X1483816Y1052880D01*
G03X1485290I737J1277D01*
G02X1487458Y1052914I1115J-1928D01*
G01X1487516Y1052880D01*
G03X1488990I737J1277D01*
G02X1491158Y1052914I1115J-1928D01*
G01X1491216Y1052880D01*
G03X1492690I737J1277D01*
G02X1494876Y1052904I1114J-1928D01*
G01X1494917Y1052880D01*
G03X1496391I737J1277D01*
G01X1496432Y1052904D01*
G02X1498616Y1052880I1071J-1952D01*
G03X1500090I737J1277D01*
G02X1502258Y1052914I1115J-1928D01*
G01X1502316Y1052880D01*
G03X1503790I737J1277D01*
G02X1505958Y1052914I1115J-1928D01*
G01X1506016Y1052880D01*
G03X1507490I737J1277D01*
G02X1509658Y1052914I1115J-1928D01*
G01X1509716Y1052880D01*
G03X1511190I737J1277D01*
G02X1513416I1113J-1928D01*
G03X1514631Y1052555I1215J2107D01*
G01X1527637D01*
X1527647Y1052545D01*
G01X1477821Y838203D02*
Y838803D01*
X1478196Y839178D01*
Y842246D01*
G02X1479319Y843551I2225J-779D01*
G03X1480044Y844336I-750J1420D01*
G01Y845041D01*
G03X1479307Y846249I-1475J-71D01*
G01X1479293Y846257D01*
X1478944Y846469D01*
G02X1478210Y847724I806J1314D01*
G01Y847725D01*
X1478196Y848090D01*
Y848091D01*
G02X1478195Y848143I2224J69D01*
G01Y848176D01*
G03X1477492Y849433I-1475J0D01*
G01X1477457Y849453D01*
G02X1476346Y851319I1114J1927D01*
G01Y851419D01*
G02X1477458Y853307I2225J-39D01*
G03X1478195Y854550I-737J1277D01*
G01Y854640D01*
G02X1479308Y856512I2225J-56D01*
G01X1479343Y856532D01*
G03X1480046Y857789I-772J1257D01*
G01Y857850D01*
G02X1481157Y859716I2225J-61D01*
G01X1481161Y859718D01*
X1481192Y859736D01*
G03Y862250I-773J1257D01*
G01X1481157Y862270D01*
G03X1479683I-737J-1277D01*
G01X1479625Y862236D01*
G02X1477457Y862270I-1054J1961D01*
G03X1475983I-737J-1277D01*
G01X1475925Y862236D01*
G02X1473757Y862270I-1054J1961D01*
G03X1472283I-737J-1277D01*
G01X1472225Y862236D01*
G02X1470057Y862270I-1054J1961D01*
G02X1468946Y864136I1114J1927D01*
G01Y864197D01*
G03X1468243Y865454I-1475J0D01*
G01X1468208Y865474D01*
G03X1466734I-737J-1277D01*
G02X1464566Y865440I-1114J1927D01*
G01X1464508Y865474D01*
X1464484Y865488D01*
G02X1463395Y867401I1136J1913D01*
G01Y867457D01*
G02X1464508Y869329I2225J-56D01*
G01X1464543Y869349D01*
G03X1465246Y870606I-772J1257D01*
G01Y870667D01*
G02X1466357Y872533I2225J-61D01*
G01X1466361Y872535D01*
X1466392Y872553D01*
G03Y875067I-773J1257D01*
G01X1466357Y875087D01*
G03X1464883I-737J-1277D01*
G01X1464825Y875053D01*
G02X1462657Y875087I-1054J1961D01*
G03X1461183I-737J-1277D01*
G01X1461125Y875053D01*
G02X1458957Y875087I-1054J1961D01*
G03X1457483I-737J-1277D01*
G01X1457425Y875053D01*
G02X1455257Y875087I-1054J1961D01*
G03X1453783I-737J-1277D01*
G01X1453725Y875053D01*
G02X1451557Y875087I-1054J1961D01*
G03X1450083I-737J-1277D01*
G01X1450042Y875063D01*
G02X1447858Y875087I-1071J1951D01*
G03X1446384I-737J-1277D01*
G01X1446343Y875063D01*
G02X1444157Y875087I-1072J1951D01*
G03X1442683I-737J-1277D01*
G01X1442625Y875053D01*
G02X1440457Y875087I-1054J1961D01*
G03X1438983I-737J-1277D01*
G01X1438925Y875053D01*
G02X1436757Y875087I-1054J1961D01*
G03X1435283I-737J-1277D01*
G01X1435225Y875053D01*
G02X1433057Y875087I-1054J1961D01*
G03X1431583I-737J-1277D01*
G01X1431542Y875063D01*
G02X1430440Y874789I-1070J1951D01*
G01X1429600D01*
X1428621Y873810D01*
G01X1515824Y888406D02*
X1515435D01*
G02X1515346Y888443I0J125D01*
G01X1512914Y890875D01*
G03X1512608Y891109I-1041J-1044D01*
G03X1511134I-737J-1277D01*
G02X1508908I-1113J1927D01*
G03X1507434I-737J-1277D01*
G02X1505266Y891075I-1114J1927D01*
G01X1505208Y891109D01*
G03X1503734I-737J-1277D01*
G02X1501508I-1113J1927D01*
G03X1500034I-737J-1277D01*
G02X1497866Y891075I-1114J1927D01*
G01X1497808Y891109D01*
G03X1496334I-737J-1277D01*
G02X1494166Y891075I-1114J1927D01*
G01X1494108Y891109D01*
G03X1492634I-737J-1277D01*
G02X1490408I-1113J1927D01*
G03X1488934I-737J-1277D01*
G02X1486766Y891075I-1114J1927D01*
G01X1486708Y891109D01*
G03X1485234I-737J-1277D01*
G02X1483066Y891075I-1114J1927D01*
G01X1483008Y891109D01*
G03X1481534I-737J-1277D01*
G02X1479308I-1113J1927D01*
G03X1477834I-737J-1277D01*
G02X1475608I-1113J1927D01*
G03X1474134I-737J-1277D01*
G02X1471966Y891075I-1114J1927D01*
G01X1471908Y891109D01*
G03X1470434I-737J-1277D01*
G02X1468266Y891075I-1114J1927D01*
G01X1468208Y891109D01*
G03X1466734I-737J-1277D01*
G02X1464508I-1113J1927D01*
G03X1463034I-737J-1277D01*
G02X1460866Y891075I-1114J1927D01*
G01X1460808Y891109D01*
G03X1459334I-737J-1277D01*
G02X1457166Y891075I-1114J1927D01*
G01X1457108Y891109D01*
G03X1455634I-737J-1277D01*
G02X1453408I-1113J1927D01*
G03X1451934I-737J-1277D01*
G02X1449766Y891075I-1114J1927D01*
G01X1449708Y891109D01*
G03X1448234I-737J-1277D01*
G02X1446008I-1113J1927D01*
G01X1445960Y891137D01*
G02X1444895Y893036I1161J1899D01*
G03X1444192Y894293I-1475J0D01*
G01X1444157Y894313D01*
G02X1443046Y896179I1114J1927D01*
G01Y896240D01*
G03X1442343Y897497I-1475J0D01*
G01X1442308Y897517D01*
G02X1441195Y899389I1112J1928D01*
G01Y899445D01*
G03X1440492Y900702I-1475J0D01*
G01X1440457Y900722D01*
G02X1439346Y902588I1114J1927D01*
G01Y902649D01*
G03X1438643Y903906I-1475J0D01*
G01X1438608Y903926D01*
X1438584Y903940D01*
G02X1438166Y904261I1137J1913D01*
G01X1438087Y904340D01*
X1435313D01*
X1434171Y905482D01*
Y909057D01*
G01X1516252Y891005D02*
X1513846D01*
X1513445Y891406D01*
G03X1512984Y891759I-1572J-1575D01*
G03X1510758I-1113J-1927D01*
G02X1509284I-737J1277D01*
G01X1509243Y891783D01*
G03X1507057Y891759I-1072J-1951D01*
G02X1505583I-737J1277D01*
G01X1505542Y891783D01*
G03X1503358Y891759I-1071J-1951D01*
G02X1501884I-737J1277D01*
G01X1501843Y891783D01*
G03X1499657Y891759I-1072J-1951D01*
G02X1498183I-737J1277D01*
G01X1498125Y891793D01*
G03X1495957Y891759I-1054J-1961D01*
G02X1494483I-737J1277D01*
G01X1494442Y891783D01*
G03X1492258Y891759I-1071J-1951D01*
G02X1490784I-737J1277D01*
G01X1490743Y891783D01*
G03X1488557Y891759I-1072J-1951D01*
G02X1487083I-737J1277D01*
G01X1487025Y891793D01*
G03X1484857Y891759I-1054J-1961D01*
G02X1483383I-737J1277D01*
G01X1483342Y891783D01*
G03X1481158Y891759I-1071J-1951D01*
G02X1479684I-737J1277D01*
G03X1477458I-1113J-1927D01*
G02X1475984I-737J1277D01*
G01X1475943Y891783D01*
G03X1473757Y891759I-1072J-1951D01*
G02X1472283I-737J1277D01*
G01X1472225Y891793D01*
G03X1470057Y891759I-1054J-1961D01*
G02X1468583I-737J1277D01*
G01X1468542Y891783D01*
G03X1466358Y891759I-1071J-1951D01*
G02X1464884I-737J1277D01*
G01X1464843Y891783D01*
G03X1462657Y891759I-1072J-1951D01*
G02X1461183I-737J1277D01*
G01X1461125Y891793D01*
G03X1458957Y891759I-1054J-1961D01*
G02X1457483I-737J1277D01*
G01X1457442Y891783D01*
G03X1455258Y891759I-1071J-1951D01*
G02X1453784I-737J1277D01*
G01X1453743Y891783D01*
G03X1451557Y891759I-1072J-1951D01*
G02X1450083I-737J1277D01*
G01X1450042Y891783D01*
G03X1447858Y891759I-1071J-1951D01*
G02X1446384I-737J1277D01*
G01X1446349Y891779D01*
G02X1445646Y893036I772J1257D01*
G03X1444558Y894949I-2226J0D01*
G01X1444534Y894963D01*
X1444499Y894983D01*
G02X1443796Y896240I772J1257D01*
G01Y896296D01*
G03X1442683Y898168I-2225J-56D01*
G01X1442648Y898188D01*
G02X1441945Y899445I772J1257D01*
G01Y899506D01*
G03X1440834Y901372I-2225J-61D01*
G01X1440799Y901392D01*
G02X1440096Y902649I772J1257D01*
G03X1439007Y904562I-2225J0D01*
G01X1438983Y904576D01*
G02X1438317Y905401I737J1277D01*
G01X1438049Y905669D01*
X1437605Y905853D01*
X1436020D01*
G01X1513847Y915322D02*
X1510401D01*
X1509214Y916509D01*
G03X1508908Y916743I-1041J-1044D01*
G03X1507434I-737J-1277D01*
G02X1505208I-1113J1927D01*
G03X1503734I-737J-1277D01*
G01X1503693Y916719D01*
G02X1501507Y916743I-1072J1951D01*
G03X1500033I-737J-1277D01*
G01X1499992Y916719D01*
G02X1497808Y916743I-1071J1951D01*
G03X1496334I-737J-1277D01*
G02X1494166Y916709I-1114J1927D01*
G01X1494108Y916743D01*
G03X1492634I-737J-1277D01*
G02X1490466Y916709I-1114J1927D01*
G01X1490408Y916743D01*
G03X1488934I-737J-1277D01*
G02X1486766Y916709I-1114J1927D01*
G01X1486708Y916743D01*
G03X1485234I-737J-1277D01*
G02X1483066Y916709I-1114J1927D01*
G01X1483008Y916743D01*
G03X1481534I-737J-1277D01*
G02X1479366Y916709I-1114J1927D01*
G01X1479308Y916743D01*
G03X1477834I-737J-1277D01*
G02X1475648Y916719I-1114J1927D01*
G01X1475607Y916743D01*
G03X1474133I-737J-1277D01*
G01X1474092Y916719D01*
G02X1471908Y916743I-1071J1951D01*
G03X1470434I-737J-1277D01*
G02X1468266Y916709I-1114J1927D01*
G01X1468208Y916743D01*
G03X1466734I-737J-1277D01*
G02X1464566Y916709I-1114J1927D01*
G01X1464508Y916743D01*
G03X1463034I-737J-1277D01*
G02X1460866Y916709I-1114J1927D01*
G01X1460808Y916743D01*
G03X1459334I-737J-1277D01*
G02X1457166Y916709I-1114J1927D01*
G01X1457108Y916743D01*
G03X1455634I-737J-1277D01*
G01X1455576Y916709D01*
G02X1453408Y916743I-1054J1961D01*
G03X1451934I-737J-1277D01*
G02X1449748Y916719I-1114J1927D01*
G01X1449707Y916743D01*
G03X1448233I-737J-1276D01*
G02X1446049Y916719I-1113J1927D01*
G01X1446008Y916743D01*
G03X1444534I-737J-1277D01*
G02X1442366Y916709I-1114J1927D01*
G01X1442308Y916743D01*
G03X1440834I-737J-1277D01*
G02X1440337Y916531I-1115J1926D01*
G01X1437871Y915466D01*
G01X1519447Y914215D02*
X1518357D01*
X1517383Y913241D01*
X1515571D01*
G02X1514458Y913539I0J2226D01*
G03X1512984I-737J-1277D01*
G02X1510758I-1113J1927D01*
G03X1509284I-737J-1277D01*
G02X1507058I-1113J1927D01*
G03X1505584I-737J-1277D01*
G02X1503358I-1113J1927D01*
G03X1501884I-737J-1277D01*
G02X1499698Y913515I-1114J1927D01*
G01X1499657Y913539D01*
G03X1498183I-737J-1277D01*
G01X1498125Y913505D01*
G02X1495957Y913539I-1054J1961D01*
G03X1494483I-737J-1277D01*
G01X1494425Y913505D01*
G02X1492257Y913539I-1054J1961D01*
G03X1490783I-737J-1277D01*
G01X1490725Y913505D01*
G02X1488557Y913539I-1054J1961D01*
G03X1487083I-737J-1277D01*
G01X1487042Y913515D01*
G02X1484858Y913539I-1071J1951D01*
G03X1483384I-737J-1277D01*
G01X1483343Y913515D01*
G02X1481157Y913539I-1072J1951D01*
G03X1479683I-737J-1277D01*
G01X1479625Y913505D01*
G02X1477457Y913539I-1054J1961D01*
G03X1475983I-737J-1277D01*
G02X1473757I-1113J1927D01*
G03X1472283I-737J-1277D01*
G01X1472225Y913505D01*
G02X1470057Y913539I-1054J1961D01*
G03X1468583I-737J-1277D01*
G01X1468525Y913505D01*
G02X1466357Y913539I-1054J1961D01*
G03X1464883I-737J-1277D01*
G01X1464825Y913505D01*
G02X1462657Y913539I-1054J1961D01*
G03X1461183I-737J-1277D01*
G01X1461142Y913515D01*
G02X1458958Y913539I-1071J1951D01*
G03X1457484I-737J-1277D01*
G02X1455300Y913515I-1113J1927D01*
G01X1455259Y913539D01*
G03X1453785I-737J-1277D01*
G02X1451557I-1114J1927D01*
G03X1450083I-737J-1277D01*
G02X1447899Y913515I-1113J1927D01*
G01X1447858Y913539D01*
X1447825Y913558D01*
G03X1446385Y913539I-703J-1296D01*
G02X1444157I-1114J1927D01*
G03X1442683I-737J-1277D01*
G01X1442625Y913505D01*
G02X1440457Y913539I-1054J1961D01*
G03X1438983I-737J-1277D01*
G01X1438948Y913519D01*
G03X1438263Y912488I773J-1256D01*
G01X1438489Y912262D01*
X1439720D01*
G01X1517437Y914915D02*
X1516512Y913990D01*
X1515571D01*
G02X1514834Y914189I3J1476D01*
G03X1512608I-1113J-1927D01*
G02X1511134I-737J1277D01*
G03X1508908I-1113J-1927D01*
G02X1507434I-737J1277D01*
G03X1505208I-1113J-1927D01*
G02X1503734I-737J1277D01*
G01X1503693Y914213D01*
G03X1501507Y914189I-1072J-1951D01*
G02X1500033I-737J1277D01*
G03X1497849Y914213I-1113J-1927D01*
G01X1497808Y914189D01*
G02X1496334I-737J1277D01*
G03X1494166Y914223I-1114J-1927D01*
G01X1494108Y914189D01*
G02X1492634I-737J1277D01*
G03X1490466Y914223I-1114J-1927D01*
G01X1490408Y914189D01*
G02X1488934I-737J1277D01*
G03X1486766Y914223I-1114J-1927D01*
G01X1486708Y914189D01*
G02X1485234I-737J1277D01*
G03X1483008I-1113J-1927D01*
G02X1481534I-737J1277D01*
G03X1479366Y914223I-1114J-1927D01*
G01X1479308Y914189D01*
G02X1477834I-737J1277D01*
G03X1475648Y914213I-1114J-1927D01*
G01X1475607Y914189D01*
G02X1474133I-737J1277D01*
G03X1471949Y914213I-1113J-1927D01*
G01X1471908Y914189D01*
G02X1470434I-737J1277D01*
G03X1468266Y914223I-1114J-1927D01*
G01X1468208Y914189D01*
G02X1466734I-737J1277D01*
G03X1464566Y914223I-1114J-1927D01*
G01X1464508Y914189D01*
G02X1463034I-737J1277D01*
G03X1460866Y914223I-1114J-1927D01*
G01X1460808Y914189D01*
G02X1459334I-737J1277D01*
G03X1457108I-1113J-1927D01*
G02X1455634I-737J1277D01*
G01X1455576Y914223D01*
G03X1453408Y914189I-1054J-1961D01*
G02X1451934I-737J1277D01*
G03X1449748Y914213I-1114J-1927D01*
G01X1449707Y914189D01*
G02X1448267Y914170I-737J1277D01*
G01X1448234Y914189D01*
X1448176Y914223D01*
G03X1446008Y914189I-1054J-1961D01*
G02X1444534I-737J1277D01*
G03X1442366Y914223I-1114J-1927D01*
G01X1442308Y914189D01*
G02X1440834I-737J1277D01*
G03X1438666Y914223I-1114J-1927D01*
G01X1438608Y914189D01*
X1438584Y914175D01*
G03X1437510Y912521I1136J-1913D01*
G01X1437251Y912262D01*
X1436020D01*
G01X1513097Y916723D02*
X1510062D01*
X1509745Y917040D01*
G03X1509284Y917393I-1572J-1575D01*
G03X1507058I-1113J-1927D01*
G02X1505584I-737J1277D01*
G03X1503358I-1113J-1927D01*
G02X1501884I-737J1277D01*
G03X1499716Y917427I-1114J-1927D01*
G01X1499658Y917393D01*
G02X1498184I-737J1277D01*
G01X1498143Y917417D01*
G03X1495957Y917393I-1072J-1951D01*
G02X1494483I-737J1277D01*
G01X1494425Y917427D01*
G03X1492257Y917393I-1054J-1961D01*
G02X1490783I-737J1277D01*
G01X1490725Y917427D01*
G03X1488557Y917393I-1054J-1961D01*
G02X1487083I-737J1277D01*
G01X1487025Y917427D01*
G03X1484857Y917393I-1054J-1961D01*
G02X1483383I-737J1277D01*
G01X1483325Y917427D01*
G03X1481157Y917393I-1054J-1961D01*
G02X1479683I-737J1277D01*
G01X1479625Y917427D01*
G03X1477457Y917393I-1054J-1961D01*
G02X1475983I-737J1277D01*
G03X1473799Y917417I-1113J-1927D01*
G01X1473758Y917393D01*
G02X1472284I-737J1277D01*
G01X1472243Y917417D01*
G03X1470057Y917393I-1072J-1951D01*
G02X1468583I-737J1277D01*
G01X1468525Y917427D01*
G03X1466357Y917393I-1054J-1961D01*
G02X1464883I-737J1277D01*
G01X1464825Y917427D01*
G03X1462657Y917393I-1054J-1961D01*
G02X1461183I-737J1277D01*
G01X1461125Y917427D01*
G03X1458957Y917393I-1054J-1961D01*
G02X1457483I-737J1277D01*
G03X1455259I-1112J-1927D01*
G02X1453785I-737J1277D01*
G03X1451557I-1114J-1927D01*
G02X1450126Y917369I-737J1277D01*
G01X1450083Y917394D01*
G03X1447857I-1113J-1927D01*
G01X1447814Y917369D01*
G02X1446383Y917393I-694J1301D01*
G01X1446325Y917427D01*
G03X1445772Y917635I-1053J-1961D01*
G01X1443420Y918670D01*
G01X1511857Y1033379D02*
X1454393D01*
X1452416Y1035356D01*
Y1036846D01*
X1450207Y1039055D01*
X1446408D01*
X1445908Y1039555D01*
X1431928D01*
X1430904Y1040579D01*
Y1044544D01*
G01Y1038136D02*
X1432758D01*
X1433227Y1038605D01*
X1445567D01*
X1446027Y1038145D01*
X1449727D01*
X1451357Y1036515D01*
Y1035045D01*
X1454613Y1031789D01*
Y1030779D01*
X1455241Y1030151D01*
G03X1457858Y1029766I1567J1568D01*
G01X1457916Y1029800D01*
G02X1459390I737J-1277D01*
G03X1461616I1113J1927D01*
G02X1463090I737J-1277D01*
G03X1465258Y1029766I1114J1927D01*
G01X1465316Y1029800D01*
G02X1466790I737J-1277D01*
G03X1468958Y1029766I1114J1927D01*
G01X1469016Y1029800D01*
G02X1470490I737J-1277D01*
G03X1472716I1113J1927D01*
G02X1474190I737J-1277D01*
G03X1476358Y1029766I1114J1927D01*
G01X1476416Y1029800D01*
G02X1477890I737J-1277D01*
G03X1480058Y1029766I1114J1927D01*
G01X1480116Y1029800D01*
G02X1481590I737J-1277D01*
G03X1483758Y1029766I1114J1927D01*
G01X1483816Y1029800D01*
G02X1485290I737J-1277D01*
G03X1487458Y1029766I1114J1927D01*
G01X1487516Y1029800D01*
G02X1488990I737J-1277D01*
G03X1491158Y1029766I1114J1927D01*
G01X1491216Y1029800D01*
G02X1492690I737J-1277D01*
G03X1494858Y1029766I1114J1927D01*
G01X1494916Y1029800D01*
G02X1496390I737J-1277D01*
G03X1498616I1113J1927D01*
G02X1500090I737J-1277D01*
G03X1502258Y1029766I1114J1927D01*
G01X1502316Y1029800D01*
G02X1503790I737J-1277D01*
G03X1505958Y1029766I1114J1927D01*
G01X1506016Y1029800D01*
G02X1507490I737J-1277D01*
G03X1509716I1113J1927D01*
G02X1511190I737J-1277D01*
G02X1511497Y1029567I-731J-1282D01*
G01X1512727Y1028337D01*
Y1027698D01*
X1513732Y1026693D01*
G01X1523181Y1038244D02*
X1521826D01*
X1520441Y1036859D01*
G02X1518967I-737J1277D01*
G01X1518966D01*
G03X1516740I-1113J-1928D01*
G02X1515266I-737J1277D01*
G03X1513040I-1113J-1928D01*
G02X1511566I-737J1277D01*
G03X1509340I-1113J-1928D01*
G02X1507866I-737J1277D01*
G03X1505682Y1036883I-1113J-1928D01*
G01X1505641Y1036859D01*
G02X1504167I-737J1277D01*
G03X1501999Y1036893I-1115J-1928D01*
G01X1501941Y1036859D01*
G02X1500467I-737J1277D01*
G03X1498299Y1036893I-1115J-1928D01*
G01X1498241Y1036859D01*
G02X1496767I-737J1277D01*
G03X1494541I-1113J-1928D01*
G02X1493067I-737J1277D01*
G03X1490899Y1036893I-1115J-1928D01*
G01X1490841Y1036859D01*
G02X1489367I-737J1277D01*
G03X1487181Y1036883I-1114J-1928D01*
G01X1487140Y1036859D01*
G02X1485666I-737J1277D01*
G03X1483482Y1036883I-1113J-1928D01*
G01X1483441Y1036859D01*
G02X1481967I-737J1277D01*
G03X1479799Y1036893I-1115J-1928D01*
G01X1479741Y1036859D01*
G02X1478267I-737J1277D01*
G03X1476099Y1036893I-1115J-1928D01*
G01X1476041Y1036859D01*
G02X1474567I-737J1277D01*
G03X1472399Y1036893I-1115J-1928D01*
G01X1472341Y1036859D01*
G02X1470867I-737J1277D01*
G03X1468641I-1113J-1928D01*
G02X1467167I-737J1277D01*
G03X1464999Y1036893I-1115J-1928D01*
G01X1464941Y1036859D01*
G02X1463467I-737J1277D01*
G03X1461281Y1036883I-1114J-1928D01*
G01X1461240Y1036859D01*
G02X1459766I-737J1277D01*
G01X1459725Y1036883D01*
G03X1457541Y1036859I-1071J-1952D01*
G02X1456067I-737J1277D01*
G03X1454953Y1037158I-1115J-1928D01*
G01X1454322D01*
X1453247Y1038233D01*
Y1041640D01*
X1452480Y1042407D01*
G02X1451990Y1042617I626J2136D01*
G03X1450516I-737J-1277D01*
G01X1450458Y1042583D01*
G02X1448290Y1042617I-1054J1961D01*
G03X1446817I-737J-1276D01*
G01X1445940D01*
X1445553Y1042777D01*
G03X1442781Y1043291I-1700J-1437D01*
G01X1442740Y1043267D01*
G02X1441266I-737J1277D01*
G03X1439082Y1043291I-1113J-1927D01*
G01X1439041Y1043267D01*
G02X1437567I-737J1277D01*
G03X1435399Y1043301I-1114J-1927D01*
G01X1435341Y1043267D01*
G02X1433867I-737J1277D01*
G01X1433832Y1043287D01*
G02X1433129Y1044544I772J1257D01*
G01Y1044600D01*
G03X1432016Y1046472I-2225J-56D01*
G01X1431981Y1046492D01*
G02X1431278Y1047749I772J1257D01*
G01Y1047810D01*
G03X1430167Y1049676I-2225J-61D01*
G01X1430111Y1049708D01*
G02X1429429Y1050952I794J1244D01*
G01Y1051008D01*
G03X1428532Y1052739I-2225J-55D01*
G01X1428437Y1053090D01*
X1429053Y1054157D01*
G01X1519310Y1048862D02*
X1518523Y1049649D01*
X1514199D01*
X1513277Y1048727D01*
X1512303D01*
G02X1511190Y1049025I-1J2225D01*
G01X1511147Y1049050D01*
G03X1509716Y1049026I-694J-1301D01*
G01X1509658Y1048992D01*
G02X1507490Y1049026I-1054J1961D01*
G03X1506059Y1049050I-737J-1277D01*
G01X1506016Y1049025D01*
X1505958Y1048991D01*
G02X1503790Y1049025I-1054J1961D01*
G03X1502316I-737J-1276D01*
G02X1500090I-1113J1927D01*
G03X1498616I-737J-1276D01*
G02X1496390I-1113J1927D01*
G03X1494916I-737J-1276D01*
G01X1494858Y1048991D01*
G02X1492690Y1049025I-1054J1961D01*
G03X1491216I-737J-1276D01*
G01X1491158Y1048991D01*
G02X1488990Y1049025I-1054J1961D01*
G03X1487516I-737J-1276D01*
G01X1487458Y1048991D01*
G02X1485290Y1049025I-1054J1961D01*
G03X1483816I-737J-1276D01*
G01X1483758Y1048991D01*
G02X1481590Y1049025I-1054J1961D01*
G03X1480116I-737J-1276D01*
G01X1480058Y1048991D01*
G02X1477890Y1049025I-1054J1961D01*
G03X1476416I-737J-1276D01*
G01X1476358Y1048991D01*
G02X1474190Y1049025I-1054J1961D01*
G03X1472716I-737J-1276D01*
G02X1470490I-1113J1927D01*
G03X1469016I-737J-1276D01*
G01X1468958Y1048991D01*
G02X1466790Y1049025I-1054J1961D01*
G03X1465316I-737J-1276D01*
G01X1465258Y1048991D01*
G02X1463090Y1049025I-1054J1961D01*
G03X1461616I-737J-1276D01*
G01X1461558Y1048991D01*
G02X1459390Y1049025I-1054J1961D01*
G03X1457916I-737J-1276D01*
G01X1457858Y1048991D01*
G02X1455690Y1049025I-1054J1961D01*
G03X1454216I-737J-1276D01*
G02X1451990I-1113J1927D01*
G03X1450516I-737J-1276D01*
G01X1450460Y1048993D01*
G03X1449778Y1047749I794J-1244D01*
G01Y1047662D01*
G02X1448667Y1045821I-2225J87D01*
G02X1446499Y1045787I-1115J1928D01*
G01X1446441Y1045821D01*
X1446398Y1045846D01*
G03X1444967Y1045822I-694J-1302D01*
G02X1442781Y1045798I-1114J1928D01*
G01X1442740Y1045822D01*
G03X1441309Y1045846I-737J-1278D01*
G01X1441266Y1045821D01*
G02X1439082Y1045797I-1113J1928D01*
G01X1439041Y1045821D01*
X1438998Y1045846D01*
G03X1437567Y1045822I-694J-1302D01*
G03X1436847Y1044770I738J-1277D01*
G01X1437073Y1044544D01*
X1438304D01*
G01X1434604D02*
X1435835D01*
X1436092Y1044801D01*
G02X1437190Y1046472I2212J-257D01*
G02X1439358Y1046506I1115J-1928D01*
G01X1439416Y1046472D01*
G03X1440890I737J1277D01*
G02X1443116I1113J-1928D01*
G03X1444590I737J1278D01*
G02X1446758Y1046506I1115J-1928D01*
G01X1446816Y1046472D01*
G03X1448290I737J1277D01*
G01X1448325Y1046492D01*
G03X1449028Y1047749I-772J1257D01*
G02X1450117Y1049662I2225J0D01*
G01X1450141Y1049676D01*
X1450182Y1049700D01*
G02X1452366Y1049676I1071J-1951D01*
G03X1453840I737J1276D01*
G01X1453881Y1049700D01*
G02X1456067Y1049676I1072J-1951D01*
G03X1457541I737J1276D01*
G01X1457599Y1049710D01*
G02X1459767Y1049676I1054J-1961D01*
G03X1461241I737J1276D01*
G01X1461299Y1049710D01*
G02X1463467Y1049676I1054J-1961D01*
G03X1464941I737J1276D01*
G01X1464999Y1049710D01*
G02X1467167Y1049676I1054J-1961D01*
G03X1468641I737J1276D01*
G01X1468682Y1049700D01*
G02X1470866Y1049676I1071J-1951D01*
G03X1472340I737J1276D01*
G01X1472381Y1049700D01*
G02X1474567Y1049676I1072J-1951D01*
G03X1476041I737J1276D01*
G01X1476099Y1049710D01*
G02X1478267Y1049676I1054J-1961D01*
G03X1479741I737J1276D01*
G01X1479799Y1049710D01*
G02X1481967Y1049676I1054J-1961D01*
G03X1483441I737J1276D01*
G01X1483499Y1049710D01*
G02X1485667Y1049676I1054J-1961D01*
G03X1487141I737J1276D01*
G01X1487199Y1049710D01*
G02X1489367Y1049676I1054J-1961D01*
G03X1490841I737J1276D01*
G01X1490899Y1049710D01*
G02X1493067Y1049676I1054J-1961D01*
G03X1494541I737J1276D01*
G01X1494582Y1049700D01*
G02X1496766Y1049676I1071J-1951D01*
G03X1498240I737J1276D01*
G02X1500466I1113J-1927D01*
G03X1501940I737J1276D01*
G01X1501981Y1049700D01*
G02X1504167Y1049676I1072J-1951D01*
G03X1505641I737J1276D01*
G01X1505699Y1049710D01*
G02X1507867Y1049676I1054J-1961D01*
G03X1509341I737J1277D01*
G01X1509382Y1049700D01*
G02X1511566Y1049676I1071J-1951D01*
G03X1512303Y1049476I742J1275D01*
G01X1512966D01*
X1513888Y1050398D01*
X1524437D01*
G01X1514784Y1058576D02*
X1512577Y1058815D01*
G03X1511675Y1058701I-274J-1454D01*
G01X1511566Y1058638D01*
G02X1509382Y1058614I-1113J1927D01*
G01X1509341Y1058638D01*
G03X1507867I-737J-1277D01*
G02X1505699Y1058604I-1114J1927D01*
G01X1505641Y1058638D01*
G03X1504167I-737J-1277D01*
G02X1501999Y1058604I-1114J1927D01*
G01X1501941Y1058638D01*
G03X1500467I-737J-1277D01*
G02X1498241I-1113J1927D01*
G03X1496767I-737J-1277D01*
G02X1494599Y1058604I-1114J1927D01*
G01X1494541Y1058638D01*
G03X1493067I-737J-1277D01*
G02X1490899Y1058604I-1114J1927D01*
G01X1490841Y1058638D01*
G03X1489367I-737J-1277D01*
G02X1487199Y1058604I-1114J1927D01*
G01X1487141Y1058638D01*
G03X1485667I-737J-1277D01*
G02X1483499Y1058604I-1114J1927D01*
G01X1483441Y1058638D01*
G03X1481967I-737J-1277D01*
G02X1479799Y1058604I-1114J1927D01*
G01X1479741Y1058638D01*
G03X1478267I-737J-1277D01*
G02X1476099Y1058604I-1114J1927D01*
G01X1476041Y1058638D01*
G03X1474567I-737J-1277D01*
G02X1472399Y1058604I-1114J1927D01*
G01X1472341Y1058638D01*
G03X1470867I-737J-1277D01*
G02X1468699Y1058604I-1114J1927D01*
G01X1468641Y1058638D01*
G03X1467167I-737J-1277D01*
G02X1464999Y1058604I-1114J1927D01*
G01X1464941Y1058638D01*
G03X1463467I-737J-1277D01*
G02X1461281Y1058614I-1114J1927D01*
G01X1461240Y1058638D01*
G03X1459766I-737J-1277D01*
G02X1457540I-1113J1927D01*
G03X1456066I-737J-1277D01*
G01X1456025Y1058614D01*
G02X1453841Y1058638I-1071J1951D01*
G03X1452367I-737J-1277D01*
G02X1450181Y1058614I-1114J1927D01*
G01X1450157Y1058628D01*
X1450140Y1058638D01*
G03X1448666I-737J-1277D01*
G01X1448608Y1058604D01*
G02X1446440Y1058638I-1054J1961D01*
G03X1444966I-737J-1277D01*
G01X1444925Y1058614D01*
G02X1442741Y1058638I-1071J1951D01*
G03X1441267I-737J-1277D01*
G01X1441226Y1058614D01*
G02X1439270Y1058522I-1072J1951D01*
G01X1438919Y1058428D01*
X1438303Y1057361D01*
G01X1436454Y1054157D02*
X1435838Y1055224D01*
X1435921Y1055531D01*
G02X1437191Y1055434I534J-1374D01*
G01X1437232Y1055410D01*
G03X1439416Y1055434I1071J1951D01*
G02X1440890I737J-1277D01*
G03X1443076Y1055410I1114J1927D01*
G01X1443117Y1055434D01*
G02X1444591I737J-1277D01*
G01X1444632Y1055410D01*
G03X1446816Y1055434I1071J1951D01*
G02X1448290I737J-1277D01*
G01X1448331Y1055410D01*
G03X1450517Y1055434I1072J1951D01*
G02X1451991I737J-1277D01*
G03X1454217I1113J1927D01*
G02X1455691I737J-1277D01*
G01X1455732Y1055410D01*
G03X1457916Y1055434I1071J1951D01*
G02X1459390I737J-1277D01*
G03X1461616I1113J1927D01*
G02X1463090I737J-1277D01*
G03X1465258Y1055400I1114J1927D01*
G01X1465316Y1055434D01*
G02X1466790I737J-1277D01*
G03X1468958Y1055400I1114J1927D01*
G01X1469016Y1055434D01*
G02X1470490I737J-1277D01*
G03X1472658Y1055400I1114J1927D01*
G01X1472716Y1055434D01*
G02X1474190I737J-1277D01*
G03X1476358Y1055400I1114J1927D01*
G01X1476416Y1055434D01*
G02X1477890I737J-1277D01*
G03X1480058Y1055400I1114J1927D01*
G01X1480116Y1055434D01*
G02X1481590I737J-1277D01*
G03X1483758Y1055400I1114J1927D01*
G01X1483816Y1055434D01*
G02X1485290I737J-1277D01*
G03X1487458Y1055400I1114J1927D01*
G01X1487516Y1055434D01*
G02X1488990I737J-1277D01*
G03X1491158Y1055400I1114J1927D01*
G01X1491216Y1055434D01*
G02X1492690I737J-1277D01*
G03X1494876Y1055410I1114J1927D01*
G01X1494917Y1055434D01*
G02X1496391I737J-1277D01*
G03X1498575Y1055410I1113J1927D01*
G01X1498616Y1055434D01*
G02X1500090I737J-1277D01*
G03X1502258Y1055400I1114J1927D01*
G01X1502316Y1055434D01*
G02X1503790I737J-1277D01*
G03X1505958Y1055400I1114J1927D01*
G01X1506016Y1055434D01*
G02X1507490I737J-1277D01*
G03X1509658Y1055400I1114J1927D01*
G01X1509716Y1055434D01*
G02X1511190I737J-1277D01*
G03X1513416I1113J1927D01*
G02X1514153Y1055633I740J-1276D01*
G01X1515850D01*
X1516241Y1056024D01*
G01X1434604Y1057361D02*
X1435220Y1056294D01*
X1435571Y1056200D01*
G02X1437525Y1056108I883J-2043D01*
G01X1437566Y1056084D01*
G03X1439040I737J1277D01*
G01X1439081Y1056108D01*
G02X1441267Y1056084I1072J-1951D01*
G03X1442741I737J1277D01*
G02X1444925Y1056108I1113J-1927D01*
G01X1444966Y1056084D01*
G03X1446440I737J1277D01*
G02X1448666I1113J-1927D01*
G03X1450140I737J1277D01*
G02X1452326Y1056108I1114J-1927D01*
G01X1452367Y1056084D01*
G03X1453841I737J1277D01*
G02X1456025Y1056108I1113J-1927D01*
G01X1456066Y1056084D01*
G03X1457540I737J1277D01*
G02X1459766I1113J-1927D01*
G03X1461240I737J1277D01*
G01X1461281Y1056108D01*
G02X1463467Y1056084I1072J-1951D01*
G03X1464941I737J1277D01*
G01X1464999Y1056118D01*
G02X1467167Y1056084I1054J-1961D01*
G03X1468641I737J1277D01*
G01X1468699Y1056118D01*
G02X1470867Y1056084I1054J-1961D01*
G03X1472341I737J1277D01*
G01X1472399Y1056118D01*
G02X1474567Y1056084I1054J-1961D01*
G03X1476041I737J1277D01*
G01X1476099Y1056118D01*
G02X1478267Y1056084I1054J-1961D01*
G03X1479741I737J1277D01*
G01X1479799Y1056118D01*
G02X1481967Y1056084I1054J-1961D01*
G03X1483441I737J1277D01*
G01X1483499Y1056118D01*
G02X1485667Y1056084I1054J-1961D01*
G03X1487141I737J1277D01*
G01X1487199Y1056118D01*
G02X1489367Y1056084I1054J-1961D01*
G03X1490841I737J1277D01*
G01X1490899Y1056118D01*
G02X1493067Y1056084I1054J-1961D01*
G03X1494541I737J1277D01*
G02X1496767I1113J-1927D01*
G03X1498241I737J1277D01*
G01X1498299Y1056118D01*
G02X1500467Y1056084I1054J-1961D01*
G03X1501941I737J1277D01*
G01X1501999Y1056118D01*
G02X1504167Y1056084I1054J-1961D01*
G03X1505641I737J1277D01*
G01X1505699Y1056118D01*
G02X1507867Y1056084I1054J-1961D01*
G03X1509341I737J1277D01*
G01X1509382Y1056108D01*
G02X1511566Y1056084I1071J-1951D01*
G03X1513040I737J1277D01*
G02X1514153Y1056382I1112J-1927D01*
G01X1515050D01*
X1515765Y1057097D01*
G01X1515154Y1061993D02*
X1513540D01*
X1512661Y1061114D01*
Y1060325D01*
X1512372Y1060036D01*
X1511675Y1059501D01*
G03X1511322Y1059364I628J-2140D01*
G01X1511190Y1059288D01*
G02X1509716I-737J1277D01*
G01X1509658Y1059322D01*
G03X1507490Y1059288I-1054J-1961D01*
G02X1506016I-737J1277D01*
G01X1505958Y1059322D01*
G03X1503790Y1059288I-1054J-1961D01*
G02X1502316I-737J1277D01*
G01X1502275Y1059312D01*
G03X1500091Y1059288I-1071J-1951D01*
G02X1498617I-737J1277D01*
G01X1498576Y1059312D01*
G03X1496390Y1059288I-1072J-1951D01*
G02X1494916I-737J1277D01*
G01X1494858Y1059322D01*
G03X1492690Y1059288I-1054J-1961D01*
G02X1491216I-737J1277D01*
G01X1491158Y1059322D01*
G03X1488990Y1059288I-1054J-1961D01*
G02X1487516I-737J1277D01*
G01X1487458Y1059322D01*
G03X1485290Y1059288I-1054J-1961D01*
G02X1483816I-737J1277D01*
G01X1483758Y1059322D01*
G03X1481590Y1059288I-1054J-1961D01*
G02X1480116I-737J1277D01*
G01X1480058Y1059322D01*
G03X1477890Y1059288I-1054J-1961D01*
G02X1476416I-737J1277D01*
G01X1476358Y1059322D01*
G03X1474190Y1059288I-1054J-1961D01*
G02X1472716I-737J1277D01*
G01X1472658Y1059322D01*
G03X1470490Y1059288I-1054J-1961D01*
G02X1469016I-737J1277D01*
G01X1468958Y1059322D01*
G03X1466790Y1059288I-1054J-1961D01*
G02X1465316I-737J1277D01*
G01X1465258Y1059322D01*
G03X1463090Y1059288I-1054J-1961D01*
G02X1461616I-737J1277D01*
G03X1459390I-1113J-1927D01*
G02X1457916I-737J1277D01*
G03X1455732Y1059312I-1113J-1927D01*
G01X1455691Y1059288D01*
G02X1454217I-737J1277D01*
G01X1454176Y1059312D01*
G03X1451990Y1059288I-1072J-1951D01*
G02X1450516I-737J1277D01*
G03X1448332Y1059312I-1113J-1927D01*
G01X1448291Y1059288D01*
G02X1446817I-737J1277D01*
G03X1444649Y1059322I-1114J-1927D01*
G01X1444591Y1059288D01*
G02X1443117I-737J1277D01*
G03X1440891I-1113J-1927D01*
G02X1439621Y1059191I-736J1277D01*
G01X1439538Y1059498D01*
X1440154Y1060565D01*
G01X1443853Y1066974D02*
X1446701Y1065764D01*
X1446816Y1065697D01*
G03X1448290I737J1277D01*
G02X1450458Y1065731I1114J-1927D01*
G01X1450516Y1065697D01*
G03X1451990I737J1277D01*
G02X1454158Y1065731I1114J-1927D01*
G01X1454216Y1065697D01*
G03X1455690I737J1277D01*
G02X1457876Y1065721I1114J-1927D01*
G01X1457917Y1065697D01*
G03X1459391I737J1277D01*
G02X1461575Y1065721I1113J-1927D01*
G01X1461616Y1065697D01*
G03X1463090I737J1277D01*
G02X1465258Y1065731I1114J-1927D01*
G01X1465316Y1065697D01*
G03X1466790I737J1277D01*
G02X1468958Y1065731I1114J-1927D01*
G01X1469016Y1065697D01*
G03X1470490I737J1277D01*
G02X1472658Y1065731I1114J-1927D01*
G01X1472716Y1065697D01*
G03X1474190I737J1277D01*
G02X1476358Y1065731I1114J-1927D01*
G01X1476416Y1065697D01*
G03X1477890I737J1277D01*
G02X1480058Y1065731I1114J-1927D01*
G01X1480116Y1065697D01*
G03X1481590I737J1277D01*
G02X1483758Y1065731I1114J-1927D01*
G01X1483816Y1065697D01*
G03X1485290I737J1277D01*
G02X1487458Y1065731I1114J-1927D01*
G01X1487516Y1065697D01*
G03X1488990I737J1277D01*
G02X1491158Y1065731I1114J-1927D01*
G01X1491216Y1065697D01*
G03X1492690I737J1277D01*
G02X1494858Y1065731I1114J-1927D01*
G01X1494916Y1065697D01*
G03X1496390I737J1277D01*
G02X1498558Y1065731I1114J-1927D01*
G01X1498616Y1065697D01*
G03X1500090I737J1277D01*
G02X1502316I1113J-1927D01*
G03X1503790I737J1277D01*
G02X1505958Y1065731I1114J-1927D01*
G01X1506016Y1065697D01*
G03X1507490I737J1277D01*
G02X1509658Y1065731I1114J-1927D01*
G01X1509716Y1065697D01*
G03X1511190I737J1277D01*
G01X1511225Y1065717D01*
G03X1511928Y1066974I-772J1257D01*
G02X1513017Y1068887I2225J0D01*
G01X1513041Y1068901D01*
X1513099Y1068935D01*
G02X1515267Y1068901I1054J-1961D01*
G03X1516741I737J1277D01*
G01X1516799Y1068935D01*
G02X1518967Y1068901I1054J-1961D01*
G03X1520441I737J1277D01*
G01X1520499Y1068935D01*
G02X1522667Y1068901I1054J-1961D01*
G03X1523404Y1068701I742J1276D01*
G01X1524699D01*
X1525420Y1069422D01*
G01X1432753Y1066974D02*
X1434937Y1065284D01*
X1435382Y1065023D01*
G03X1437566Y1065047I1071J1951D01*
G02X1439040I737J-1277D01*
G01X1439081Y1065023D01*
G03X1441267Y1065047I1072J1951D01*
G02X1442740I737J-1276D01*
G01X1442741D01*
X1442799Y1065013D01*
G03X1444967Y1065047I1054J1961D01*
G02X1446441I737J-1277D01*
G01X1446499Y1065013D01*
G03X1448667Y1065047I1054J1961D01*
G02X1450141I737J-1277D01*
G01X1450199Y1065013D01*
G03X1452367Y1065047I1054J1961D01*
G02X1453841I737J-1277D01*
G01X1453899Y1065013D01*
G03X1456067Y1065047I1054J1961D01*
G02X1457541I737J-1277D01*
G03X1459767I1113J1927D01*
G02X1461241I737J-1277D01*
G01X1461299Y1065013D01*
G03X1463467Y1065047I1054J1961D01*
G02X1464941I737J-1277D01*
G01X1464999Y1065013D01*
G03X1467167Y1065047I1054J1961D01*
G02X1468641I737J-1277D01*
G01X1468699Y1065013D01*
G03X1470867Y1065047I1054J1961D01*
G02X1472341I737J-1277D01*
G01X1472399Y1065013D01*
G03X1474567Y1065047I1054J1961D01*
G02X1476041I737J-1277D01*
G01X1476099Y1065013D01*
G03X1478267Y1065047I1054J1961D01*
G02X1479741I737J-1277D01*
G01X1479799Y1065013D01*
G03X1481967Y1065047I1054J1961D01*
G02X1483441I737J-1277D01*
G01X1483499Y1065013D01*
G03X1485667Y1065047I1054J1961D01*
G02X1487141I737J-1277D01*
G01X1487199Y1065013D01*
G03X1489367Y1065047I1054J1961D01*
G02X1490841I737J-1277D01*
G01X1490899Y1065013D01*
G03X1493067Y1065047I1054J1961D01*
G02X1494541I737J-1277D01*
G01X1494599Y1065013D01*
G03X1496767Y1065047I1054J1961D01*
G02X1498241I737J-1277D01*
G01X1498282Y1065023D01*
G03X1500466Y1065047I1071J1951D01*
G02X1501940I737J-1277D01*
G01X1501981Y1065023D01*
G03X1504167Y1065047I1072J1951D01*
G02X1505641I737J-1277D01*
G01X1505699Y1065013D01*
G03X1507867Y1065047I1054J1961D01*
G02X1509341I737J-1277D01*
G01X1509399Y1065013D01*
G03X1511567Y1065047I1054J1961D01*
G03X1512678Y1066913I-1114J1927D01*
G01Y1066974D01*
G02X1513381Y1068231I1475J0D01*
G01X1513416Y1068251D01*
G02X1514890I737J-1277D01*
G03X1517058Y1068217I1114J1927D01*
G01X1517116Y1068251D01*
G02X1518590I737J-1277D01*
G03X1520758Y1068217I1114J1927D01*
G01X1520816Y1068251D01*
G02X1522290I737J-1277D01*
G03X1523404Y1067952I1114J1926D01*
G01X1523750D01*
X1524330Y1067372D01*
G01X1516713Y898275D02*
X1515484Y897814D01*
X1509745D01*
G03X1509284Y898168I-1575J-1574D01*
G01X1509243Y898192D01*
G03X1507057Y898168I-1072J-1952D01*
G02X1505583I-737J1277D01*
G01X1505542Y898192D01*
G03X1503358Y898168I-1071J-1952D01*
G02X1501884I-737J1277D01*
G03X1499658I-1113J-1928D01*
G02X1498184I-737J1277D01*
G01X1498143Y898192D01*
G03X1495957Y898168I-1072J-1952D01*
G02X1494483I-737J1277D01*
G01X1494425Y898202D01*
G03X1492257Y898168I-1053J-1962D01*
G02X1490783I-737J1277D01*
G01X1490725Y898202D01*
G03X1488557Y898168I-1053J-1962D01*
G02X1487083I-737J1277D01*
G01X1487025Y898202D01*
G03X1484857Y898168I-1053J-1962D01*
G02X1483383I-737J1277D01*
G03X1481157I-1113J-1928D01*
G02X1479683I-737J1277D01*
G03X1477457I-1113J-1928D01*
G02X1475983I-737J1277D01*
G01X1475942Y898192D01*
G03X1473758Y898168I-1071J-1952D01*
G02X1472284I-737J1277D01*
G01X1472243Y898192D01*
G03X1470057Y898168I-1072J-1952D01*
G02X1468583I-737J1277D01*
G01X1468525Y898202D01*
G03X1466357Y898168I-1053J-1962D01*
G02X1464883I-737J1277D01*
G01X1464825Y898202D01*
G03X1462657Y898168I-1053J-1962D01*
G02X1461183I-737J1277D01*
G01X1461125Y898202D01*
G03X1458957Y898168I-1053J-1962D01*
G02X1457483I-737J1277D01*
G03X1455257I-1113J-1928D01*
G02X1453783I-737J1277D01*
G01X1453725Y898202D01*
G03X1451557Y898168I-1053J-1962D01*
G02X1450083I-737J1277D01*
G01X1450025Y898202D01*
G03X1447857Y898168I-1053J-1962D01*
G02X1446383I-737J1277D01*
G01X1446348Y898188D01*
G02X1445645Y899445I772J1257D01*
G01Y899506D01*
G03X1445525Y900169I-2225J-60D01*
G01X1445271Y902649D01*
G01X1517250Y894014D02*
X1515570D01*
G02X1514458Y894313I2J2227D01*
G03X1512984I-737J-1277D01*
G02X1510758I-1113J1927D01*
G03X1509284I-737J-1277D01*
G01X1509243Y894289D01*
G02X1507057Y894313I-1072J1951D01*
G03X1505583I-737J-1277D01*
G01X1505542Y894289D01*
G02X1503358Y894313I-1071J1951D01*
G03X1501884I-737J-1277D01*
G01X1501843Y894289D01*
G02X1499657Y894313I-1072J1951D01*
G03X1498183I-737J-1277D01*
G01X1498125Y894279D01*
G02X1495957Y894313I-1054J1961D01*
G03X1494483I-737J-1277D01*
G01X1494442Y894289D01*
G02X1492258Y894313I-1071J1951D01*
G03X1490784I-737J-1277D01*
G01X1490743Y894289D01*
G02X1488557Y894313I-1072J1951D01*
G03X1487083I-737J-1277D01*
G01X1487025Y894279D01*
G02X1484857Y894313I-1054J1961D01*
G03X1483383I-737J-1277D01*
G02X1481199Y894289I-1113J1927D01*
G01X1481158Y894313D01*
G03X1479684I-737J-1277D01*
G02X1477516Y894279I-1114J1927D01*
G01X1477458Y894313D01*
G03X1475984I-737J-1277D01*
G01X1475943Y894289D01*
G02X1473757Y894313I-1072J1951D01*
G03X1472283I-737J-1277D01*
G01X1472225Y894279D01*
G02X1470057Y894313I-1054J1961D01*
G03X1468583I-737J-1277D01*
G01X1468542Y894289D01*
G02X1466358Y894313I-1071J1951D01*
G03X1464884I-737J-1277D01*
G01X1464843Y894289D01*
G02X1462657Y894313I-1072J1951D01*
G03X1461183I-737J-1277D01*
G01X1461125Y894279D01*
G02X1458957Y894313I-1054J1961D01*
G03X1457483I-737J-1277D01*
G02X1455299Y894289I-1113J1927D01*
G01X1455258Y894313D01*
G03X1453784I-737J-1277D01*
G01X1453743Y894289D01*
G02X1451557Y894313I-1072J1951D01*
G03X1450287Y894410I-736J-1277D01*
G01X1450204Y894103D01*
X1450820Y893036D01*
G01X1516503Y895620D02*
X1515647Y894764D01*
X1515571D01*
G02X1514834Y894963I3J1476D01*
G03X1512608I-1113J-1927D01*
G02X1511134I-737J1277D01*
G03X1508908I-1113J-1927D01*
G02X1507434I-737J1277D01*
G03X1505266Y894997I-1114J-1927D01*
G01X1505208Y894963D01*
G02X1503734I-737J1277D01*
G03X1501508I-1113J-1927D01*
G02X1500034I-737J1277D01*
G03X1497866Y894997I-1114J-1927D01*
G01X1497808Y894963D01*
G02X1496334I-737J1277D01*
G03X1494166Y894997I-1114J-1927D01*
G01X1494108Y894963D01*
G02X1492634I-737J1277D01*
G03X1490408I-1113J-1927D01*
G02X1488934I-737J1277D01*
G03X1486766Y894997I-1114J-1927D01*
G01X1486708Y894963D01*
G02X1485234I-737J1277D01*
G03X1483048Y894987I-1114J-1927D01*
G01X1483007Y894963D01*
G02X1481533I-737J1277D01*
G01X1481475Y894997D01*
G03X1479307Y894963I-1054J-1961D01*
G02X1477833I-737J1277D01*
G01X1477792Y894987D01*
G03X1475608Y894963I-1071J-1951D01*
G02X1474134I-737J1277D01*
G03X1471966Y894997I-1114J-1927D01*
G01X1471908Y894963D01*
G02X1470434I-737J1277D01*
G03X1468266Y894997I-1114J-1927D01*
G01X1468208Y894963D01*
G02X1466734I-737J1277D01*
G03X1464508I-1113J-1927D01*
G02X1463034I-737J1277D01*
G03X1460866Y894997I-1114J-1927D01*
G01X1460808Y894963D01*
G02X1459334I-737J1277D01*
G03X1457148Y894987I-1114J-1927D01*
G01X1457107Y894963D01*
G02X1455633I-737J1277D01*
G01X1455592Y894987D01*
G03X1453408Y894963I-1071J-1951D01*
G02X1451934I-737J1277D01*
G03X1449937Y895080I-1115J-1927D01*
G01X1449587Y895173D01*
X1448971Y896240D01*
G01X1517266Y900265D02*
X1514915D01*
X1514458Y900722D01*
G03X1512984I-737J-1277D01*
G02X1510758I-1113J1927D01*
G03X1509284I-737J-1277D01*
G01X1509243Y900698D01*
G02X1507057Y900722I-1072J1951D01*
G03X1505583I-737J-1277D01*
G01X1505542Y900698D01*
G02X1503358Y900722I-1071J1951D01*
G03X1501884I-737J-1277D01*
G02X1499658I-1113J1927D01*
G03X1498184I-737J-1277D01*
G01X1498143Y900698D01*
G02X1495957Y900722I-1072J1951D01*
G03X1494483I-737J-1277D01*
G01X1494425Y900688D01*
G02X1492257Y900722I-1054J1961D01*
G03X1490783I-737J-1277D01*
G01X1490725Y900688D01*
G02X1488557Y900722I-1054J1961D01*
G03X1487083I-737J-1277D01*
G02X1484857I-1113J1927D01*
G03X1483383I-737J-1277D01*
G01X1483325Y900688D01*
G02X1481157Y900722I-1054J1961D01*
G03X1479683I-737J-1277D01*
G01X1479625Y900688D01*
G02X1477457Y900722I-1054J1961D01*
G03X1475983I-737J-1277D01*
G01X1475942Y900698D01*
G02X1473758Y900722I-1071J1951D01*
G03X1472284I-737J-1277D01*
G01X1472243Y900698D01*
G02X1470057Y900722I-1072J1951D01*
G03X1468583I-737J-1277D01*
G01X1468525Y900688D01*
G02X1466357Y900722I-1054J1961D01*
G03X1464883I-737J-1277D01*
G01X1464825Y900688D01*
G02X1462657Y900722I-1054J1961D01*
G03X1461183I-737J-1277D01*
G02X1458957I-1113J1927D01*
G03X1457483I-737J-1277D01*
G01X1457425Y900688D01*
X1454520Y899445D01*
G01X1456371Y902649D02*
X1458492Y901654D01*
G02X1459333Y901372I-273J-2209D01*
G03X1460807I737J1277D01*
G01X1460848Y901396D01*
G02X1463034Y901372I1072J-1951D01*
G03X1464508I737J1277D01*
G01X1464566Y901406D01*
G02X1466734Y901372I1054J-1961D01*
G03X1468208I737J1277D01*
G01X1468266Y901406D01*
G02X1470434Y901372I1054J-1961D01*
G03X1471908I737J1277D01*
G02X1474134I1113J-1927D01*
G03X1475608I737J1277D01*
G01X1475666Y901406D01*
G02X1477834Y901372I1054J-1961D01*
G03X1479308I737J1277D01*
G01X1479366Y901406D01*
G02X1481534Y901372I1054J-1961D01*
G03X1483008I737J1277D01*
G01X1483049Y901396D01*
G02X1485233Y901372I1071J-1951D01*
G03X1486707I737J1277D01*
G01X1486748Y901396D01*
G02X1488934Y901372I1072J-1951D01*
G03X1490408I737J1277D01*
G01X1490466Y901406D01*
G02X1492634Y901372I1054J-1961D01*
G03X1494108I737J1277D01*
G01X1494166Y901406D01*
G02X1496334Y901372I1054J-1961D01*
G03X1497808I737J1277D01*
G02X1500034I1113J-1927D01*
G03X1501508I737J1277D01*
G02X1503734I1113J-1927D01*
G03X1505208I737J1277D01*
G01X1505266Y901406D01*
G02X1507434Y901372I1054J-1961D01*
G03X1508908I737J1277D01*
G02X1511134I1113J-1927D01*
G03X1512608I737J1277D01*
G02X1514834I1113J-1927D01*
G01X1517784D01*
G01X1513865Y902741D02*
X1512914Y903692D01*
G03X1512608Y903926I-1041J-1044D01*
G03X1511134I-737J-1277D01*
G02X1508908I-1113J1927D01*
G03X1507434I-737J-1277D01*
G02X1505208I-1113J1927D01*
G03X1503734I-737J-1277D01*
G02X1501508I-1113J1927D01*
G03X1500034I-737J-1277D01*
G02X1497866Y903892I-1114J1927D01*
G01X1497808Y903926D01*
G03X1496334I-737J-1277D01*
G02X1494108I-1113J1927D01*
G03X1492634I-737J-1277D01*
G02X1490466Y903892I-1114J1927D01*
G01X1490408Y903926D01*
G03X1488934I-737J-1277D01*
G02X1486748Y903902I-1114J1927D01*
G01X1486707Y903926D01*
G03X1485233I-737J-1277D01*
G02X1483049Y903902I-1113J1927D01*
G01X1483008Y903926D01*
G03X1481534I-737J-1277D01*
G02X1479366Y903892I-1114J1927D01*
G01X1479308Y903926D01*
G03X1477834I-737J-1277D01*
G02X1475666Y903892I-1114J1927D01*
G01X1475608Y903926D01*
G03X1474134I-737J-1277D01*
G02X1471966Y903892I-1114J1927D01*
G01X1471908Y903926D01*
G03X1470434I-737J-1277D01*
G02X1468208I-1113J1927D01*
G03X1466734I-737J-1277D01*
G02X1464566Y903892I-1114J1927D01*
G01X1464508Y903926D01*
G03X1463034I-737J-1277D01*
G02X1460848Y903902I-1114J1927D01*
G01X1460807Y903926D01*
G03X1459333I-737J-1277D01*
G02X1457149Y903902I-1113J1927D01*
G01X1457108Y903926D01*
G03X1455634I-737J-1277D01*
G01X1455545Y903874D01*
G03X1454463Y902001I1081J-1873D01*
G01X1453607Y901145D01*
X1451657D01*
X1450153Y902649D01*
X1448971D01*
G01X1520697Y910655D02*
X1518855D01*
X1518534Y910334D01*
G02X1516308I-1113J1928D01*
G03X1514834I-737J-1277D01*
G02X1512608I-1113J1928D01*
G03X1511134I-737J-1277D01*
G02X1508908I-1113J1928D01*
G03X1507434I-737J-1277D01*
G02X1505208I-1113J1928D01*
G03X1503734I-737J-1277D01*
G02X1501508I-1113J1928D01*
G03X1500034I-737J-1277D01*
G02X1497848Y910310I-1114J1928D01*
G01X1497807Y910334D01*
G03X1496333I-737J-1277D01*
G02X1494149Y910310I-1113J1928D01*
G01X1494108Y910334D01*
G03X1492634I-737J-1277D01*
G02X1490466Y910300I-1115J1928D01*
G01X1490408Y910334D01*
G03X1488934I-737J-1277D01*
G02X1486766Y910300I-1115J1928D01*
G01X1486708Y910334D01*
G03X1485234I-737J-1277D01*
G02X1483008I-1113J1928D01*
G03X1481534I-737J-1277D01*
G02X1479366Y910300I-1115J1928D01*
G01X1479308Y910334D01*
G03X1477834I-737J-1277D01*
G02X1475666Y910300I-1115J1928D01*
G01X1475608Y910334D01*
G03X1474134I-737J-1277D01*
G02X1471966Y910300I-1115J1928D01*
G01X1471908Y910334D01*
G03X1470434I-737J-1277D01*
G02X1468266Y910300I-1115J1928D01*
G01X1468208Y910334D01*
G03X1466734I-737J-1277D01*
G02X1464566Y910300I-1115J1928D01*
G01X1464508Y910334D01*
G03X1463034I-737J-1277D01*
G02X1460866Y910300I-1115J1928D01*
G01X1460808Y910334D01*
G03X1459334I-737J-1277D01*
G01X1459293Y910310D01*
G02X1458449Y910047I-1071J1952D01*
G01X1456370Y909057D01*
G01X1452671Y902649D02*
G02X1454949Y904398I7795J-7795D01*
G01X1455257Y904576D01*
G02X1457425Y904610I1114J-1927D01*
G01X1457483Y904576D01*
G03X1458957I737J1277D01*
G02X1461183I1113J-1927D01*
G03X1462657I737J1277D01*
G02X1464825Y904610I1114J-1927D01*
G01X1464883Y904576D01*
G03X1466357I737J1277D01*
G02X1468543Y904600I1114J-1927D01*
G01X1468584Y904576D01*
G03X1470058I737J1277D01*
G02X1472242Y904600I1113J-1927D01*
G01X1472283Y904576D01*
G03X1473757I737J1277D01*
G02X1475925Y904610I1114J-1927D01*
G01X1475983Y904576D01*
G03X1477457I737J1277D01*
G02X1479625Y904610I1114J-1927D01*
G01X1479683Y904576D01*
G03X1481157I737J1277D01*
G02X1483325Y904610I1114J-1927D01*
G01X1483383Y904576D01*
G03X1484857I737J1277D01*
G02X1487083I1113J-1927D01*
G03X1488557I737J1277D01*
G02X1490725Y904610I1114J-1927D01*
G01X1490783Y904576D01*
G03X1492257I737J1277D01*
G02X1494443Y904600I1114J-1927D01*
G01X1494484Y904576D01*
G03X1495958I737J1277D01*
G02X1498142Y904600I1113J-1927D01*
G01X1498183Y904576D01*
G03X1499657I737J1277D01*
G02X1501843Y904600I1114J-1927D01*
G01X1501884Y904576D01*
G03X1503358I737J1277D01*
G02X1505584I1113J-1927D01*
G03X1507058I737J1277D01*
G02X1509284I1113J-1927D01*
G03X1510758I737J1277D01*
G02X1512984I1113J-1927D01*
G02X1513944Y903840I-2304J-4000D01*
G01X1515642D01*
G01X1523843Y908804D02*
X1522978D01*
X1522495Y908321D01*
X1520623D01*
X1520315Y908013D01*
G02X1520008Y907780I-1038J1049D01*
G02X1518534I-737J1277D01*
G03X1516308I-1113J-1927D01*
G02X1514834I-737J1277D01*
G03X1512608I-1113J-1927D01*
G02X1511134I-737J1277D01*
G03X1508908I-1113J-1927D01*
G02X1507434I-737J1277D01*
G03X1505208I-1113J-1927D01*
G02X1503734I-737J1277D01*
G03X1501508I-1113J-1927D01*
G02X1500034I-737J1277D01*
G03X1497848Y907804I-1114J-1927D01*
G01X1497807Y907780D01*
G02X1496333I-737J1277D01*
G01X1496292Y907804D01*
G03X1494108Y907780I-1071J-1951D01*
G02X1492634I-737J1277D01*
G03X1490466Y907814I-1114J-1927D01*
G01X1490408Y907780D01*
G02X1488934I-737J1277D01*
G03X1486766Y907814I-1114J-1927D01*
G01X1486708Y907780D01*
G02X1485234I-737J1277D01*
G03X1483066Y907814I-1114J-1927D01*
G01X1483008Y907780D01*
G02X1481534I-737J1277D01*
G03X1479366Y907814I-1114J-1927D01*
G01X1479308Y907780D01*
G02X1477834I-737J1277D01*
G03X1475666Y907814I-1114J-1927D01*
G01X1475608Y907780D01*
G02X1474134I-737J1277D01*
G03X1471966Y907814I-1114J-1927D01*
G01X1471908Y907780D01*
G02X1470434I-737J1277D01*
G03X1468208I-1113J-1927D01*
G02X1466734I-737J1277D01*
G03X1464566Y907814I-1114J-1927D01*
G01X1464508Y907780D01*
G02X1463034I-737J1277D01*
G03X1460866Y907814I-1114J-1927D01*
G01X1460808Y907780D01*
G02X1459334I-737J1277D01*
G03X1457106I-1114J-1927D01*
G02X1455632I-737J1277D01*
G01X1455574Y907814D01*
X1455633Y907780D01*
G03X1453449Y907804I-1113J-1927D01*
G01X1453408Y907780D01*
G02X1451934I-737J1277D01*
G03X1451217Y908043I-1114J-1927D01*
G01X1448971Y909057D01*
G01X1523536Y907572D02*
X1520934D01*
X1520844Y907481D01*
G02X1520636Y907299I-1566J1580D01*
G02X1520384Y907130I-1363J1760D01*
G02X1518158I-1113J1927D01*
G03X1516684I-737J-1277D01*
G02X1514458I-1113J1927D01*
G03X1512984I-737J-1277D01*
G02X1510758I-1113J1927D01*
G03X1509284I-737J-1277D01*
G02X1507058I-1113J1927D01*
G03X1505584I-737J-1277D01*
G02X1503358I-1113J1927D01*
G03X1501884I-737J-1277D01*
G01X1501843Y907106D01*
G02X1499657Y907130I-1072J1951D01*
G03X1498183I-737J-1277D01*
G02X1495999Y907106I-1113J1927D01*
G01X1495958Y907130D01*
G03X1494484I-737J-1277D01*
G01X1494443Y907106D01*
G02X1492257Y907130I-1072J1951D01*
G03X1490783I-737J-1277D01*
G01X1490725Y907096D01*
G02X1488557Y907130I-1054J1961D01*
G03X1487083I-737J-1277D01*
G01X1487025Y907096D01*
G02X1484857Y907130I-1054J1961D01*
G03X1483383I-737J-1277D01*
G01X1483325Y907096D01*
G02X1481157Y907130I-1054J1961D01*
G03X1479683I-737J-1277D01*
G01X1479625Y907096D01*
G02X1477457Y907130I-1054J1961D01*
G03X1475983I-737J-1277D01*
G01X1475925Y907096D01*
G02X1473757Y907130I-1054J1961D01*
G03X1472283I-737J-1277D01*
G01X1472242Y907106D01*
G02X1470058Y907130I-1071J1951D01*
G03X1468584I-737J-1277D01*
G01X1468543Y907106D01*
G02X1466357Y907130I-1072J1951D01*
G03X1464883I-737J-1277D01*
G01X1464825Y907096D01*
G02X1462657Y907130I-1054J1961D01*
G03X1461183I-737J-1277D01*
G01X1461125Y907096D01*
G02X1458957Y907130I-1054J1961D01*
G03X1457483I-737J-1277D01*
G02X1455315Y907096I-1114J1927D01*
G01X1455257Y907130D01*
G03X1453783I-737J-1277D01*
G01X1453725Y907096D01*
G02X1451557Y907130I-1054J1961D01*
G03X1450083I-737J-1277D01*
G01X1450025Y907096D01*
X1447361Y907857D01*
X1445271Y909057D01*
G01X1520817Y912235D02*
X1518737D01*
X1517487Y910985D01*
X1516684D01*
G03X1514458I-1113J-1928D01*
G02X1512984I-737J1277D01*
G03X1510758I-1113J-1928D01*
G02X1509284I-737J1277D01*
G03X1507058I-1113J-1928D01*
G02X1505584I-737J1277D01*
G03X1503358I-1113J-1928D01*
G02X1501884I-737J1277D01*
G01X1501843Y911009D01*
G03X1499657Y910985I-1072J-1952D01*
G02X1498183I-737J1277D01*
G03X1495957I-1113J-1928D01*
G02X1494483I-737J1277D01*
G01X1494425Y911019D01*
G03X1492257Y910985I-1053J-1962D01*
G02X1490783I-737J1277D01*
G01X1490725Y911019D01*
G03X1488557Y910985I-1053J-1962D01*
G02X1487083I-737J1277D01*
G01X1487042Y911009D01*
G03X1484858Y910985I-1071J-1952D01*
G02X1483384I-737J1277D01*
G01X1483343Y911009D01*
G03X1481157Y910985I-1072J-1952D01*
G02X1479683I-737J1277D01*
G01X1479625Y911019D01*
G03X1477457Y910985I-1053J-1962D01*
G02X1475983I-737J1277D01*
G01X1475925Y911019D01*
G03X1473757Y910985I-1053J-1962D01*
G02X1472283I-737J1277D01*
G01X1472225Y911019D01*
G03X1470057Y910985I-1053J-1962D01*
G02X1468583I-737J1277D01*
G01X1468525Y911019D01*
G03X1466357Y910985I-1053J-1962D01*
G02X1464883I-737J1277D01*
G01X1464825Y911019D01*
G03X1462657Y910985I-1053J-1962D01*
G02X1461183I-737J1277D01*
G01X1461142Y911009D01*
G03X1458958Y910985I-1071J-1952D01*
G01X1458925Y910966D01*
G02X1457483Y910985I-704J1296D01*
G03X1455315Y911019I-1115J-1928D01*
G01X1455257Y910985D01*
X1452671Y909057D01*
G01X1518777Y939759D02*
X1518690D01*
X1518554Y939623D01*
X1515572D01*
G02X1515445Y939629I6J1476D01*
G02X1514834Y939823I130J1470D01*
G03X1512608I-1113J-1927D01*
G02X1511134I-737J1277D01*
G03X1508908I-1113J-1927D01*
G02X1507434I-737J1277D01*
G03X1505208I-1113J-1927D01*
G02X1503734I-737J1277D01*
G03X1501508I-1113J-1927D01*
G02X1500034I-737J1277D01*
G03X1497808I-1113J-1927D01*
G02X1496334I-737J1277D01*
G03X1494166Y939857I-1114J-1927D01*
G01X1494108Y939823D01*
G02X1492634I-737J1277D01*
G03X1490466Y939857I-1114J-1927D01*
G01X1490408Y939823D01*
G02X1488934I-737J1277D01*
G03X1486748Y939847I-1114J-1927D01*
G01X1486707Y939823D01*
G02X1485233I-737J1277D01*
G03X1483049Y939847I-1113J-1927D01*
G01X1483008Y939823D01*
G02X1481534I-737J1277D01*
G03X1479366Y939857I-1114J-1927D01*
G01X1479308Y939823D01*
G02X1477834I-737J1277D01*
G03X1475666Y939857I-1114J-1927D01*
G01X1475608Y939823D01*
G02X1474134I-737J1277D01*
G03X1471908I-1113J-1927D01*
G02X1470434I-737J1277D01*
G03X1468266Y939857I-1114J-1927D01*
G01X1468208Y939823D01*
G02X1466734I-737J1277D01*
G03X1464566Y939857I-1114J-1927D01*
G01X1464508Y939823D01*
G02X1463034I-737J1277D01*
G03X1460848Y939847I-1114J-1927D01*
G01X1460807Y939823D01*
G02X1458596Y941066I-737J1277D01*
G01Y941139D01*
G03X1455257Y943027I-2226J-40D01*
G01X1454512Y942623D01*
X1453865Y941975D01*
Y940220D01*
X1454440Y939645D01*
X1454954Y939349D01*
X1455083Y938870D01*
X1454520Y937896D01*
G01X1518777Y938739D02*
X1518690D01*
X1518555Y938874D01*
X1515571D01*
G02X1515378Y938882I-4J2226D01*
G02X1514458Y939173I195J2218D01*
G03X1512984I-737J-1277D01*
G02X1510758I-1113J1927D01*
G03X1509284I-737J-1277D01*
G02X1507058I-1113J1927D01*
G03X1505584I-737J-1277D01*
G02X1503358I-1113J1927D01*
G03X1501884I-737J-1277D01*
G02X1499658I-1113J1927D01*
G03X1498184I-737J-1277D01*
G01X1498143Y939149D01*
G02X1495957Y939173I-1072J1951D01*
G03X1494483I-737J-1277D01*
G01X1494425Y939139D01*
G02X1492257Y939173I-1054J1961D01*
G03X1490783I-737J-1277D01*
G01X1490725Y939139D01*
G02X1488557Y939173I-1054J1961D01*
G03X1487083I-737J-1277D01*
G02X1484857I-1113J1927D01*
G03X1483383I-737J-1277D01*
G01X1483325Y939139D01*
G02X1481157Y939173I-1054J1961D01*
G03X1479683I-737J-1277D01*
G01X1479625Y939139D01*
G02X1477457Y939173I-1054J1961D01*
G03X1475983I-737J-1277D01*
G01X1475942Y939149D01*
G02X1473758Y939173I-1071J1951D01*
G03X1472284I-737J-1277D01*
G01X1472243Y939149D01*
G02X1470057Y939173I-1072J1951D01*
G03X1468583I-737J-1277D01*
G01X1468525Y939139D01*
G02X1466357Y939173I-1054J1961D01*
G03X1464883I-737J-1277D01*
G01X1464825Y939139D01*
G02X1462657Y939173I-1054J1961D01*
G03X1461183I-737J-1277D01*
G02X1457845Y941061I-1113J1927D01*
G01Y941134D01*
G03X1455634Y942377I-1474J-34D01*
G01X1454965Y942015D01*
X1454614Y941664D01*
Y940531D01*
X1454900Y940245D01*
X1455328Y939998D01*
X1455807Y940124D01*
X1456371Y941100D01*
G01X1454520Y963530D02*
X1455650Y962400D01*
G01X1456371Y966735D02*
X1458973Y965626D01*
G02X1459334Y965458I-755J-2095D01*
G03X1460808I737J1277D01*
G01X1460866Y965492D01*
G02X1463034Y965458I1053J-1962D01*
G03X1464508I737J1277D01*
G01X1464566Y965492D01*
G02X1466734Y965458I1053J-1962D01*
G03X1468208I737J1277D01*
G02X1470392Y965482I1113J-1928D01*
G01X1470433Y965458D01*
G03X1471907I737J1277D01*
G01X1471948Y965482D01*
G02X1474134Y965458I1072J-1952D01*
G03X1475608I737J1277D01*
G02X1477792Y965482I1113J-1928D01*
G01X1477833Y965458D01*
G03X1479307I737J1277D01*
G01X1479348Y965482D01*
G02X1481534Y965458I1072J-1952D01*
G03X1483008I737J1277D01*
G01X1483066Y965492D01*
G02X1485234Y965458I1053J-1962D01*
G03X1486708I737J1277D01*
G01X1486766Y965492D01*
G02X1488934Y965458I1053J-1962D01*
G03X1490408I737J1277D01*
G01X1490466Y965492D01*
G02X1492634Y965458I1053J-1962D01*
G03X1494108I737J1277D01*
G02X1496292Y965482I1113J-1928D01*
G01X1496333Y965458D01*
G03X1497807I737J1277D01*
G01X1497848Y965482D01*
G02X1500034Y965458I1072J-1952D01*
G03X1501508I737J1277D01*
G02X1503734I1113J-1928D01*
G03X1505208I737J1277D01*
G01X1505266Y965492D01*
G02X1507434Y965458I1053J-1962D01*
G03X1508908I737J1277D01*
G02X1511134I1113J-1928D01*
G03X1512608I737J1277D01*
G03X1512914Y965692I-735J1278D01*
G01X1513641Y966419D01*
X1514567D01*
G01X1458220Y963529D02*
X1460045Y964252D01*
X1460758Y964558D01*
X1461183Y964807D01*
G02X1462657I737J-1277D01*
G03X1464825Y964773I1115J1928D01*
G01X1464883Y964807D01*
G02X1466357I737J-1277D01*
G03X1468543Y964783I1114J1928D01*
G01X1468584Y964807D01*
G02X1470058I737J-1277D01*
G01X1470099Y964783D01*
G03X1472283Y964807I1071J1952D01*
G02X1473757I737J-1277D01*
G03X1475943Y964783I1114J1928D01*
G01X1475984Y964807D01*
G02X1477458I737J-1277D01*
G01X1477499Y964783D01*
G03X1479683Y964807I1071J1952D01*
G02X1481157I737J-1277D01*
G03X1483325Y964773I1115J1928D01*
G01X1483383Y964807D01*
G02X1484857I737J-1277D01*
G03X1487025Y964773I1115J1928D01*
G01X1487083Y964807D01*
G02X1488557I737J-1277D01*
G03X1490725Y964773I1115J1928D01*
G01X1490783Y964807D01*
G02X1492257I737J-1277D01*
G03X1494443Y964783I1114J1928D01*
G01X1494484Y964807D01*
G02X1495958I737J-1277D01*
G01X1495999Y964783D01*
G03X1498183Y964807I1071J1952D01*
G02X1499657I737J-1277D01*
G03X1501843Y964783I1114J1928D01*
G01X1501884Y964807D01*
G02X1503358I737J-1277D01*
G03X1505542Y964783I1113J1928D01*
G01X1505583Y964807D01*
G02X1507057I737J-1277D01*
G03X1509243Y964783I1114J1928D01*
G01X1509284Y964807D01*
G02X1510758I737J-1277D01*
G03X1512942Y964783I1113J1928D01*
G01X1512983Y964807D01*
G02X1513721Y965007I742J-1276D01*
G01X1514467D01*
G01X1498247Y981028D02*
X1497071D01*
G03X1496334Y980829I3J-1475D01*
G02X1494108I-1113J1927D01*
G03X1492634I-737J-1277D01*
G02X1490466Y980795I-1114J1927D01*
G01X1490408Y980829D01*
G03X1488934I-737J-1277D01*
G02X1486748Y980805I-1114J1927D01*
G01X1486707Y980829D01*
G03X1485233I-737J-1277D01*
G02X1483049Y980805I-1113J1927D01*
G01X1483008Y980829D01*
G03X1481534I-737J-1277D01*
G02X1479366Y980795I-1114J1927D01*
G01X1479308Y980829D01*
G03X1477834I-737J-1277D01*
G02X1475666Y980795I-1114J1927D01*
G01X1475608Y980829D01*
G03X1474134I-737J-1277D01*
G02X1471966Y980795I-1114J1927D01*
G01X1471908Y980829D01*
G03X1470434I-737J-1277D01*
G02X1468208I-1113J1927D01*
G03X1466734I-737J-1277D01*
G02X1464566Y980795I-1114J1927D01*
G01X1464508Y980829D01*
G03X1463034I-737J-1277D01*
G02X1460848Y980805I-1114J1927D01*
G01X1460807Y980829D01*
G03X1459333I-737J-1277D01*
G02X1457149Y980805I-1113J1927D01*
G01X1457108Y980829D01*
G03X1455838Y980926I-736J-1277D01*
G01X1455755Y980619D01*
X1456371Y979552D01*
G01X1454520Y982756D02*
X1455136Y981689D01*
X1455487Y981595D01*
G02X1457425Y981513I884J-2043D01*
G01X1457483Y981479D01*
G03X1458957I737J1277D01*
G02X1461183I1113J-1927D01*
G03X1462657I737J1277D01*
G02X1464825Y981513I1114J-1927D01*
G01X1464883Y981479D01*
G03X1466357I737J1277D01*
G02X1468543Y981503I1114J-1927D01*
G01X1468584Y981479D01*
G03X1470058I737J1277D01*
G02X1472242Y981503I1113J-1927D01*
G01X1472283Y981479D01*
G03X1473757I737J1277D01*
G02X1475925Y981513I1114J-1927D01*
G01X1475983Y981479D01*
G03X1477457I737J1277D01*
G02X1479625Y981513I1114J-1927D01*
G01X1479683Y981479D01*
G03X1481157I737J1277D01*
G02X1483325Y981513I1114J-1927D01*
G01X1483383Y981479D01*
G03X1484857I737J1277D01*
G02X1487083I1113J-1927D01*
G03X1488557I737J1277D01*
G02X1490725Y981513I1114J-1927D01*
G01X1490783Y981479D01*
G03X1492257I737J1277D01*
G02X1494443Y981503I1114J-1927D01*
G01X1494484Y981479D01*
G03X1495958I737J1277D01*
G03X1496264Y981713I-735J1278D01*
G01X1497336Y982785D01*
G01X1456371Y973143D02*
X1458375Y972160D01*
G02X1459276Y971900I-153J-2221D01*
G01X1459334Y971866D01*
G03X1460808I737J1277D01*
G02X1462976Y971900I1114J-1927D01*
G01X1463034Y971866D01*
G03X1464508I737J1277D01*
G02X1466676Y971900I1114J-1927D01*
G01X1466734Y971866D01*
G03X1468208I737J1277D01*
G02X1470376Y971900I1114J-1927D01*
G01X1470434Y971866D01*
G03X1471908I737J1277D01*
G02X1474094Y971890I1114J-1927D01*
G01X1474135Y971866D01*
G03X1475609I737J1277D01*
G01X1475650Y971890D01*
G02X1477834Y971866I1071J-1951D01*
G03X1479308I737J1277D01*
G02X1481476Y971900I1114J-1927D01*
G01X1481534Y971866D01*
G03X1483008I737J1277D01*
G02X1485176Y971900I1114J-1927D01*
G01X1485234Y971866D01*
G03X1486708I737J1277D01*
G02X1488876Y971900I1114J-1927D01*
G01X1488934Y971866D01*
G03X1490408I737J1277D01*
G02X1492594Y971890I1114J-1927D01*
G01X1492635Y971866D01*
G03X1494109I737J1277D01*
G01X1494150Y971890D01*
G02X1496334Y971866I1071J-1951D01*
G03X1497808I737J1277D01*
G02X1499994Y971890I1114J-1927D01*
G01X1500035Y971866D01*
G03X1501509I737J1277D01*
G02X1502621Y972164I1112J-1926D01*
G01X1503218D01*
X1503734Y971866D01*
G03X1505208I737J1277D01*
G02X1507434I1113J-1927D01*
G03X1508800Y971809I737J1277D01*
G02X1509429Y971950I629J-1333D01*
G01X1510615D01*
X1510977Y971588D01*
G01X1501667Y975368D02*
X1500770D01*
G03X1499658Y975070I0J-2224D01*
G02X1498184I-737J1277D01*
G01X1498143Y975094D01*
G03X1495957Y975070I-1072J-1951D01*
G02X1494483I-737J1277D01*
G03X1492299Y975094I-1113J-1927D01*
G01X1492258Y975070D01*
G02X1490784I-737J1277D01*
G01X1490743Y975094D01*
G03X1488557Y975070I-1072J-1951D01*
G02X1487083I-737J1277D01*
G01X1487025Y975104D01*
G03X1484857Y975070I-1054J-1961D01*
G02X1483383I-737J1277D01*
G01X1483325Y975104D01*
G03X1481157Y975070I-1054J-1961D01*
G02X1479683I-737J1277D01*
G01X1479625Y975104D01*
G03X1477457Y975070I-1054J-1961D01*
G02X1475983I-737J1277D01*
G03X1473799Y975094I-1113J-1927D01*
G01X1473758Y975070D01*
G02X1472284I-737J1277D01*
G01X1472243Y975094D01*
G03X1470057Y975070I-1072J-1951D01*
G02X1468583I-737J1277D01*
G01X1468525Y975104D01*
G03X1466357Y975070I-1054J-1961D01*
G02X1464883I-737J1277D01*
G01X1464825Y975104D01*
G03X1462657Y975070I-1054J-1961D01*
G02X1461183I-737J1277D01*
G01X1461125Y975104D01*
G03X1458957Y975070I-1054J-1961D01*
G02X1457483I-737J1277D01*
G01X1457425Y975104D01*
G03X1456524Y975364I-1054J-1961D01*
G01X1454520Y976347D01*
G01X1456804Y1031727D02*
X1456188Y1030660D01*
X1456271Y1030353D01*
G03X1457541Y1030450I534J1374D01*
G01X1457582Y1030474D01*
G02X1459766Y1030450I1071J-1951D01*
G03X1461240I737J1277D01*
G01X1461281Y1030474D01*
G02X1463467Y1030450I1072J-1951D01*
G03X1464941I737J1277D01*
G01X1464999Y1030484D01*
G02X1467167Y1030450I1054J-1961D01*
G03X1468641I737J1277D01*
G01X1468682Y1030474D01*
G02X1470866Y1030450I1071J-1951D01*
G03X1472340I737J1277D01*
G01X1472381Y1030474D01*
G02X1474567Y1030450I1072J-1951D01*
G03X1476041I737J1277D01*
G01X1476099Y1030484D01*
G02X1478267Y1030450I1054J-1961D01*
G03X1479741I737J1277D01*
G01X1479799Y1030484D01*
G02X1481967Y1030450I1054J-1961D01*
G03X1483441I737J1277D01*
G01X1483499Y1030484D01*
G02X1485667Y1030450I1054J-1961D01*
G03X1487141I737J1277D01*
G01X1487199Y1030484D01*
G02X1489367Y1030450I1054J-1961D01*
G03X1490841I737J1277D01*
G01X1490899Y1030484D01*
G02X1493067Y1030450I1054J-1961D01*
G03X1494541I737J1277D01*
G01X1494582Y1030474D01*
G02X1496766Y1030450I1071J-1951D01*
G03X1498240I737J1277D01*
G01X1498281Y1030474D01*
G02X1500467Y1030450I1072J-1951D01*
G03X1501941I737J1277D01*
G01X1501999Y1030484D01*
G02X1504167Y1030450I1054J-1961D01*
G03X1505641I737J1277D01*
G01X1505682Y1030474D01*
G02X1507866Y1030450I1071J-1951D01*
G03X1509340I737J1277D01*
G02X1511566I1113J-1927D01*
G02X1511818Y1030281I-1111J-1929D01*
G02X1512026Y1030099I-1358J-1762D01*
G01X1513964Y1028159D01*
G01X1516041Y1015905D02*
Y1016764D01*
X1515224Y1017581D01*
X1514124D01*
X1513878Y1017335D01*
G02X1513417Y1016982I-1573J1577D01*
G02X1511231Y1016958I-1114J1928D01*
G01X1511190Y1016982D01*
G03X1509716I-737J-1277D01*
G02X1507490I-1113J1928D01*
G03X1506016I-737J-1277D01*
G01X1505975Y1016958D01*
G02X1503791Y1016982I-1071J1952D01*
G03X1502317I-737J-1277D01*
G01X1502276Y1016958D01*
G02X1500090Y1016982I-1072J1952D01*
G03X1498616I-737J-1277D01*
G01X1498575Y1016958D01*
G02X1496391Y1016982I-1071J1952D01*
G03X1494917I-737J-1277D01*
G01X1494876Y1016958D01*
G02X1492690Y1016982I-1072J1952D01*
G03X1491216I-737J-1277D01*
G01X1491158Y1016948D01*
G02X1488990Y1016982I-1053J1962D01*
G03X1487516I-737J-1277D01*
G02X1485290I-1113J1928D01*
G03X1483816I-737J-1277D01*
G01X1483758Y1016948D01*
G02X1481590Y1016982I-1053J1962D01*
G03X1480116I-737J-1277D01*
G01X1480075Y1016958D01*
G02X1477891Y1016982I-1071J1952D01*
G03X1476417I-737J-1277D01*
G01X1476376Y1016958D01*
G02X1474190Y1016982I-1072J1952D01*
G03X1472716I-737J-1277D01*
G01X1472675Y1016958D01*
G02X1470491Y1016982I-1071J1952D01*
G03X1469017I-737J-1277D01*
G01X1468976Y1016958D01*
G02X1466790Y1016982I-1072J1952D01*
G03X1465316I-737J-1277D01*
G01X1465258Y1016948D01*
G02X1463090Y1016982I-1053J1962D01*
G03X1461616I-737J-1277D01*
G01X1460053Y1016080D01*
G02X1458653Y1015705I-1400J2426D01*
G01X1445704Y1044544D02*
X1447720Y1043559D01*
G02X1448667Y1043267I-166J-2219D01*
G03X1450141I737J1277D01*
G01X1450199Y1043301D01*
G02X1452367Y1043267I1054J-1961D01*
G03X1453841I737J1277D01*
G01X1453899Y1043301D01*
G02X1456067Y1043267I1054J-1961D01*
G03X1457541I737J1277D01*
G01X1457599Y1043301D01*
G02X1459767Y1043267I1054J-1961D01*
G03X1461241I737J1277D01*
G01X1461299Y1043301D01*
G02X1463467Y1043267I1054J-1961D01*
G03X1464941I737J1277D01*
G01X1464999Y1043301D01*
G02X1467167Y1043267I1054J-1961D01*
G03X1468641I737J1277D01*
G01X1468699Y1043301D01*
G02X1470867Y1043267I1054J-1961D01*
G03X1472341I737J1277D01*
G02X1474525Y1043291I1113J-1927D01*
G01X1474566Y1043267D01*
G03X1476040I737J1277D01*
G01X1476081Y1043291D01*
G02X1478267Y1043267I1072J-1951D01*
G03X1479741I737J1277D01*
G01X1479799Y1043301D01*
G02X1481967Y1043267I1054J-1961D01*
G03X1483441I737J1277D01*
G01X1483499Y1043301D01*
G02X1485667Y1043267I1054J-1961D01*
G03X1487141I737J1277D01*
G01X1487199Y1043301D01*
G02X1489367Y1043267I1054J-1961D01*
G03X1490841I737J1277D01*
G01X1490899Y1043301D01*
G02X1493067Y1043267I1054J-1961D01*
G03X1494541I737J1277D01*
G01X1494599Y1043301D01*
G02X1496767Y1043267I1054J-1961D01*
G03X1498241I737J1277D01*
G02X1500425Y1043291I1113J-1927D01*
G01X1500466Y1043267D01*
G03X1501940I737J1277D01*
G01X1501981Y1043291D01*
G02X1504167Y1043267I1072J-1951D01*
G03X1505641I737J1277D01*
G01X1505699Y1043301D01*
G02X1507867Y1043267I1054J-1961D01*
G03X1509341I737J1277D01*
G02X1510453Y1043565I1112J-1926D01*
G01X1456804Y1038136D02*
X1459192Y1039181D01*
G03X1459766Y1039413I-539J2159D01*
G02X1461240I737J-1277D01*
G01X1461281Y1039389D01*
G03X1463467Y1039413I1072J1951D01*
G02X1464941I737J-1277D01*
G01X1464999Y1039379D01*
G03X1467167Y1039413I1054J1961D01*
G02X1468641I737J-1277D01*
G01X1468699Y1039379D01*
G03X1470867Y1039413I1054J1961D01*
G02X1472341I737J-1277D01*
G03X1474567I1113J1927D01*
G02X1476041I737J-1277D01*
G01X1476099Y1039379D01*
G03X1478267Y1039413I1054J1961D01*
G02X1479741I737J-1277D01*
G01X1479799Y1039379D01*
G03X1481967Y1039413I1054J1961D01*
G02X1483441I737J-1277D01*
G01X1483482Y1039389D01*
G03X1485666Y1039413I1071J1951D01*
G02X1487140I737J-1277D01*
G01X1487181Y1039389D01*
G03X1489367Y1039413I1072J1951D01*
G02X1490841I737J-1277D01*
G01X1490899Y1039379D01*
G03X1493067Y1039413I1054J1961D01*
G02X1494541I737J-1277D01*
G01X1494599Y1039379D01*
G03X1496767Y1039413I1054J1961D01*
G02X1498241I737J-1277D01*
G03X1500467I1113J1927D01*
G02X1501941I737J-1277D01*
G01X1501999Y1039379D01*
G03X1504167Y1039413I1054J1961D01*
G02X1505641I737J-1277D01*
G01X1505682Y1039389D01*
G03X1507866Y1039413I1071J1951D01*
G02X1509340I737J-1277D01*
G03X1511566I1113J1927D01*
G02X1512303Y1039612I740J-1276D01*
G01X1513265D01*
X1513747Y1040094D01*
X1515417D01*
G01X1454953Y1041340D02*
X1457916Y1040063D01*
G03X1459390I737J1277D01*
G02X1461616I1113J-1927D01*
G03X1463090I737J1277D01*
G02X1465258Y1040097I1114J-1927D01*
G01X1465316Y1040063D01*
G03X1466790I737J1277D01*
G02X1468958Y1040097I1114J-1927D01*
G01X1469016Y1040063D01*
G03X1470490I737J1277D01*
G02X1472676Y1040087I1114J-1927D01*
G01X1472717Y1040063D01*
G03X1474191I737J1277D01*
G02X1476375Y1040087I1113J-1927D01*
G01X1476416Y1040063D01*
G03X1477890I737J1277D01*
G02X1480058Y1040097I1114J-1927D01*
G01X1480116Y1040063D01*
G03X1481590I737J1277D01*
G02X1483758Y1040097I1114J-1927D01*
G01X1483816Y1040063D01*
G03X1485290I737J1277D01*
G02X1487516I1113J-1927D01*
G03X1488990I737J1277D01*
G02X1491158Y1040097I1114J-1927D01*
G01X1491216Y1040063D01*
G03X1492690I737J1277D01*
G02X1494858Y1040097I1114J-1927D01*
G01X1494916Y1040063D01*
G03X1496390I737J1277D01*
G02X1498576Y1040087I1114J-1927D01*
G01X1498617Y1040063D01*
G03X1500091I737J1277D01*
G02X1502275Y1040087I1113J-1927D01*
G01X1502316Y1040063D01*
G03X1503790I737J1277D01*
G02X1505958Y1040097I1114J-1927D01*
G01X1506016Y1040063D01*
G03X1507490I737J1277D01*
G02X1509716I1113J-1927D01*
G03X1511190I737J1277D01*
G02X1512303Y1040361I1112J-1927D01*
G01X1512867D01*
X1513687Y1041181D01*
G01X1515824Y1046491D02*
X1515400D01*
X1514410Y1045501D01*
X1510536D01*
G02X1509341Y1045821I0J2390D01*
G03X1507867I-737J-1277D01*
G02X1505699Y1045787I-1114J1927D01*
G01X1505641Y1045821D01*
G03X1504167I-737J-1277D01*
G02X1501981Y1045797I-1114J1927D01*
G01X1501940Y1045821D01*
G03X1500466I-737J-1277D01*
G02X1498282Y1045797I-1113J1927D01*
G01X1498241Y1045821D01*
G03X1496767I-737J-1277D01*
G02X1494599Y1045787I-1114J1927D01*
G01X1494541Y1045821D01*
G03X1493067I-737J-1277D01*
G02X1490899Y1045787I-1114J1927D01*
G01X1490841Y1045821D01*
G03X1489367I-737J-1277D01*
G02X1487199Y1045787I-1114J1927D01*
G01X1487141Y1045821D01*
G03X1485667I-737J-1277D01*
G02X1483499Y1045787I-1114J1927D01*
G01X1483441Y1045821D01*
G03X1481967I-737J-1277D01*
G02X1479799Y1045787I-1114J1927D01*
G01X1479741Y1045821D01*
G03X1478267I-737J-1277D01*
G02X1476081Y1045797I-1114J1927D01*
G01X1476040Y1045821D01*
G03X1474566I-737J-1277D01*
G02X1472382Y1045797I-1113J1927D01*
G01X1472341Y1045821D01*
G03X1470867I-737J-1277D01*
G02X1468699Y1045787I-1114J1927D01*
G01X1468641Y1045821D01*
G03X1467167I-737J-1277D01*
G02X1464999Y1045787I-1114J1927D01*
G01X1464941Y1045821D01*
G03X1463467I-737J-1277D01*
G02X1461299Y1045787I-1114J1927D01*
G01X1461241Y1045821D01*
G03X1459767I-737J-1277D01*
G01X1458204Y1044919D01*
G02X1456804Y1044544I-1400J2426D01*
G01X1449404D02*
G02X1451990Y1046471I9545J-10110D01*
G02X1454158Y1046505I1114J-1927D01*
G01X1454216Y1046471D01*
G03X1455690I737J1277D01*
G02X1457858Y1046505I1114J-1927D01*
G01X1457916Y1046471D01*
G03X1459390I737J1277D01*
G02X1461558Y1046505I1114J-1927D01*
G01X1461616Y1046471D01*
G03X1463090I737J1277D01*
G02X1465258Y1046505I1114J-1927D01*
G01X1465316Y1046471D01*
G03X1466790I737J1277D01*
G02X1468958Y1046505I1114J-1927D01*
G01X1469016Y1046471D01*
G03X1470490I737J1277D01*
G02X1472658Y1046505I1114J-1927D01*
G01X1472716Y1046471D01*
G03X1474190I737J1277D01*
G02X1476416I1113J-1927D01*
G03X1477890I737J1277D01*
G02X1480058Y1046505I1114J-1927D01*
G01X1480116Y1046471D01*
G03X1481590I737J1277D01*
G02X1483758Y1046505I1114J-1927D01*
G01X1483816Y1046471D01*
G03X1485290I737J1277D01*
G02X1487458Y1046505I1114J-1927D01*
G01X1487516Y1046471D01*
G03X1488990I737J1277D01*
G02X1491158Y1046505I1114J-1927D01*
G01X1491216Y1046471D01*
G03X1492690I737J1277D01*
G02X1494858Y1046505I1114J-1927D01*
G01X1494916Y1046471D01*
G03X1496390I737J1277D01*
G02X1498558Y1046505I1114J-1927D01*
G01X1498616Y1046471D01*
G03X1500090I737J1277D01*
G02X1502316I1113J-1927D01*
G03X1503790I737J1277D01*
G02X1505958Y1046505I1114J-1927D01*
G01X1506016Y1046471D01*
G03X1507490I737J1277D01*
G02X1509658Y1046505I1114J-1927D01*
G01X1509716Y1046471D01*
G03X1510453Y1046274I736J1277D01*
G01X1513409D01*
X1515170Y1048035D01*
X1515834D01*
G54D115*
G01X297087Y723842D02*
Y721249D01*
G01X1053749Y763399D02*
X1057749D01*
G01X1058383Y766798D02*
X1057749Y766164D01*
Y763399D01*
G01X1131434Y1257291D02*
X1130903Y1257822D01*
X1129494D01*
X1128616Y1256944D01*
G01X1132973Y1259862D02*
X1132659Y1259548D01*
X1132567D01*
X1131434Y1258415D01*
Y1257291D01*
G01X1228518Y134262D02*
X1226093D01*
G01X1220275Y134600D02*
X1225755D01*
X1226093Y134262D01*
G01X1263486Y739949D02*
X1262206D01*
X1259998Y737741D01*
Y735592D01*
G01X1263926Y742390D02*
X1263486Y741950D01*
Y739949D01*
G01X1259982Y741785D02*
X1261323D01*
X1261928Y742390D01*
X1263926D01*
G01X1327952Y201774D02*
Y201952D01*
G01D02*
X1330725Y204725D01*
Y204900D01*
G01X1656170Y1260352D02*
X1656810D01*
X1659266Y1257896D01*
Y1256944D01*
G01X1710034Y1235879D02*
X1708992D01*
X1707887Y1236984D01*
Y1240425D01*
X1709314Y1241852D01*
X1710950D01*
X1713322Y1244224D01*
Y1249552D01*
X1713888Y1250118D01*
Y1251144D01*
X1712367Y1254815D01*
X1710218Y1256964D01*
X1709013D01*
G54D22*
X37721Y760236D03*
Y757676D03*
X54847D03*
Y760236D03*
X1446071Y738216D03*
Y735656D03*
X1463197D03*
Y738216D03*
G54D13*
X19685Y-29134D03*
Y1803261D03*
X49280Y337402D03*
X41870Y1511291D03*
X441043Y1672205D03*
Y1718465D03*
X1416437Y1672204D03*
Y1718464D03*
X1808192Y1569255D03*
X1812980Y502472D03*
X1837795Y-29134D03*
Y1803261D03*
X2081889Y-29134D03*
Y1803261D03*
G54D106*
X1307199Y240916D03*
X1312149Y245866D03*
X1301906Y246041D03*
X1306856Y250991D03*
G54D31*
X57544Y397012D03*
X53738Y396986D03*
X60761Y435475D03*
X56722Y435542D03*
X61775Y1244977D03*
X65397Y381644D03*
X69998Y381753D03*
X73281Y693127D03*
X91123Y1244051D03*
X94700Y1539788D03*
X95876Y690719D03*
X125760Y653056D03*
X135950Y1254658D03*
X159197Y1234212D03*
X173865Y1240342D03*
X201360Y669758D03*
X219272Y759901D03*
X241160Y1245008D03*
X254122Y33886D03*
X246220Y33878D03*
X250220D03*
X242220D03*
X246859Y60602D03*
X250859Y60612D03*
X250457Y758101D03*
X254477Y758211D03*
X273046Y720185D03*
Y729980D03*
X273246Y749680D03*
X286720Y42878D03*
X277046Y720185D03*
X281046Y729980D03*
X277046D03*
Y740480D03*
X281046D03*
X285046D03*
X281046Y749480D03*
X277046D03*
X285046D03*
X275639Y863963D03*
X274693Y1252002D03*
X291520Y15253D03*
X302720Y42878D03*
X294720D03*
X298211Y177795D03*
X290953Y714341D03*
X292706Y749324D03*
X300839Y1308072D03*
X316345Y205140D03*
X318158Y228503D03*
X316656Y730304D03*
X320656D03*
X312656Y723304D03*
X307967Y723360D03*
X317967Y749831D03*
X334546Y738814D03*
X332656Y723304D03*
X324656D03*
X351946Y722988D03*
X348037Y722991D03*
X344440Y742288D03*
X355946Y722991D03*
X366902Y749324D03*
X374902D03*
X387810Y1660548D03*
X391880Y1660508D03*
X436514Y1636433D03*
X440280Y1636503D03*
X499590Y88258D03*
X498730Y122638D03*
X498630Y143248D03*
X503100Y81208D03*
X507310Y81178D03*
X503270Y122648D03*
X507320Y122698D03*
X503290Y143238D03*
X507360Y143208D03*
X525900Y104316D03*
X548609Y35378D03*
X545450Y88843D03*
X541370D03*
X563100Y52698D03*
X581520Y52778D03*
X576200Y52738D03*
X571580Y52698D03*
X598405D03*
X594097D03*
X592076Y747981D03*
X610970Y52708D03*
X606330Y52698D03*
X602350D03*
X614750Y750481D03*
X603276Y747981D03*
X620097Y52698D03*
X631060Y48808D03*
X619090Y42808D03*
X620814Y155492D03*
X617008Y155466D03*
X645083Y33622D03*
X635000Y51378D03*
X639000D03*
X633603Y163212D03*
X644335Y1253309D03*
X654196Y1244943D03*
X670080Y52698D03*
X678050D03*
X674080D03*
X667347Y758401D03*
X672537Y758461D03*
X694400Y52698D03*
X681980D03*
X682588Y87353D03*
X682440Y115886D03*
X689663Y404415D03*
X684705Y1248476D03*
X698597Y52698D03*
X707597D03*
X711867Y52738D03*
X702790Y52688D03*
X712000Y72178D03*
X700960Y128218D03*
X710433Y412375D03*
X702062Y1254510D03*
X712298Y1605818D03*
X708175Y1605827D03*
X704219Y1634867D03*
X705083Y1661009D03*
X728000Y78378D03*
X719967Y72178D03*
X723957D03*
X715990D03*
X714427Y1247591D03*
X720112Y1604249D03*
X731069Y1230732D03*
X730328Y1254514D03*
X734111Y1254535D03*
X744022Y1246023D03*
X748178Y404935D03*
X772570Y1246028D03*
X762670Y1666505D03*
X791685Y1254410D03*
X808220Y140078D03*
X808843Y425645D03*
X803116Y1244133D03*
X821120Y139478D03*
X819401Y1253010D03*
X820110Y1243628D03*
X841720Y212878D03*
X837500Y223168D03*
X840651Y1236902D03*
X847271Y1253739D03*
X849767Y1246806D03*
X922320Y1663878D03*
X918300Y1663916D03*
X932487Y486199D03*
X928958Y484554D03*
X939970Y520204D03*
X924761Y520055D03*
X928393Y518607D03*
X934020Y991088D03*
X938220Y1663778D03*
X926120Y1663878D03*
X933979Y1663843D03*
X929979Y1663878D03*
X943369Y505094D03*
X946100Y1663816D03*
X942100D03*
X950100D03*
X953900D03*
X964347Y503807D03*
X968355Y503754D03*
X965570Y1559276D03*
X985445Y175599D03*
X988219Y412912D03*
X984254D03*
X1004189Y401214D03*
X1012942Y295086D03*
X1008942D03*
X1017720Y307878D03*
X1013720D03*
X1009334Y401183D03*
X1013105Y401226D03*
X1037000Y293528D03*
X1052504Y1254177D03*
X1082030Y1254368D03*
X1111904Y1254211D03*
X1135339Y1234212D03*
X1135687Y1585254D03*
X1131687D03*
X1149903Y1247350D03*
X1145687Y1585254D03*
X1141687D03*
X1151687D03*
X1153467Y589038D03*
X1166077Y763341D03*
X1165095Y1585254D03*
X1155687D03*
X1161095D03*
X1160310Y1628276D03*
X1177677Y761011D03*
X1172649Y1254378D03*
X1179563Y1247507D03*
X1175095Y1585254D03*
X1171095D03*
X1200497Y765131D03*
X1195097D03*
Y756223D03*
X1199597Y756195D03*
X1199679Y1254665D03*
X1208537Y748321D03*
X1212537D03*
X1209247Y765121D03*
X1212937Y756821D03*
X1208937D03*
X1204497Y765131D03*
X1209315Y1247754D03*
X1223793Y1236902D03*
X1230681Y1246806D03*
X1223793Y1243902D03*
X1230681Y1254694D03*
X1242398Y751333D03*
X1246260Y760481D03*
X1262383Y103676D03*
X1260514Y221398D03*
X1259998Y732533D03*
X1263787Y732531D03*
X1252847Y745511D03*
X1250260Y760481D03*
X1276345Y99646D03*
X1279485Y110541D03*
X1274257Y740581D03*
X1276980Y1304133D03*
X1275856Y1352563D03*
X1272346D03*
X1291704Y103247D03*
X1295807Y112109D03*
X1295947Y732241D03*
X1289817Y741086D03*
X1303220Y107578D03*
X1310150Y129120D03*
X1309228Y122084D03*
X1314269Y122129D03*
X1303728Y127306D03*
X1300317Y737411D03*
X1308847Y749811D03*
X1305277D03*
X1328946Y131296D03*
X1319288Y122118D03*
X1327428Y123293D03*
X1317891Y129119D03*
X1323493Y129246D03*
X1322477Y176192D03*
X1330773Y198039D03*
X1322522Y189986D03*
X1321816Y726185D03*
X1330328Y738658D03*
X1320032Y749811D03*
X1316307D03*
X1332886Y126223D03*
X1336930Y124223D03*
X1334814Y198039D03*
X1335120Y209035D03*
X1338495Y749317D03*
X1334641Y749525D03*
X1445018Y724504D03*
X1458818D03*
X1449118D03*
X1453218D03*
X1459431Y1395911D03*
X1468947Y738651D03*
X1470656Y749317D03*
X1474656D03*
X1463249Y1395911D03*
X1482751Y749318D03*
X1502396Y731343D03*
X1507016Y734482D03*
X1499245Y749781D03*
X1494963Y749678D03*
X1510437Y313841D03*
X1521975Y749781D03*
X1517575D03*
X1534000Y126878D03*
X1527185Y749781D03*
X1561890Y198768D03*
X1562890Y240438D03*
X1573507Y749601D03*
X1577507D03*
X1590915Y765721D03*
X1582017Y893099D03*
Y907761D03*
X1602650Y1254739D03*
Y1247536D03*
X1616114Y1254060D03*
X1631545Y1245059D03*
X1654143Y1250701D03*
X1661120Y614178D03*
X1675414Y1254060D03*
X1690560Y427128D03*
X1699720Y490378D03*
X1694339Y491294D03*
X1702067Y695981D03*
X1705029Y1226326D03*
X1705013Y1253905D03*
X1690518Y1248096D03*
X1712820Y172296D03*
X1705720Y490378D03*
X1711720D03*
X1705896Y706463D03*
X1706017Y695981D03*
X1713606Y710953D03*
X1709013Y1253905D03*
X1705803Y1246953D03*
X1720183Y1249890D03*
X1734714Y1254160D03*
X1749690Y1245402D03*
X1769900Y40225D03*
X1762075D03*
X1770566Y300475D03*
X1764680Y306058D03*
X1764514Y1254060D03*
X1773791Y31370D03*
X1777754Y40385D03*
X1781990Y40271D03*
X1773554Y40225D03*
X1774537Y300560D03*
X1779319Y303696D03*
X1778789Y1247161D03*
X1787706Y50056D03*
X1791706D03*
X1797417Y1237906D03*
Y1244906D03*
X1816360Y1237777D03*
X1816612Y1253601D03*
X1810954Y1252880D03*
G54D40*
X158318Y1384286D03*
X155718D03*
X158318Y1387393D03*
X155718D03*
X160201Y1399732D03*
X157731D03*
Y1394132D03*
X160201D03*
X160918Y1384286D03*
X163518D03*
Y1387393D03*
X160918D03*
X169318Y1384286D03*
X166118D03*
X172262Y1384302D03*
Y1387409D03*
X163718Y1390500D03*
X161118D03*
X162631Y1399732D03*
Y1394132D03*
X172231Y1390532D03*
X170922Y1399255D03*
X166262D03*
X173252Y1400005D03*
X168592D03*
X208312Y576125D03*
Y581085D03*
Y578605D03*
X208056Y591665D03*
X208806Y589335D03*
X208056Y587005D03*
X208806Y584675D03*
X208312Y615085D03*
Y610125D03*
Y612605D03*
X208806Y618675D03*
X208056Y621005D03*
X208806Y623335D03*
X208056Y625665D03*
X208312Y649085D03*
Y644125D03*
Y646605D03*
X208056Y655005D03*
X208806Y657335D03*
Y652675D03*
X208056Y659665D03*
X207856Y686443D03*
X203043Y686483D03*
X207824Y681560D03*
X203044Y684036D03*
X207834Y684006D03*
X203237Y681549D03*
X201661Y1384286D03*
X193861D03*
X196461D03*
X199061D03*
X201661Y1387393D03*
X193861D03*
X196461D03*
X199061D03*
X204261Y1384286D03*
X207461D03*
X201861Y1390500D03*
X199261D03*
X195874Y1399732D03*
X198344D03*
X200774D03*
X195874Y1394132D03*
X198344D03*
X200774D03*
X206735Y1400005D03*
X209065Y1399255D03*
X204405D03*
X213912Y576125D03*
X220668Y574131D03*
X223775D03*
X213912Y578605D03*
Y581085D03*
X217556Y590575D03*
X217561Y582131D03*
Y579531D03*
X223775Y587731D03*
X223759Y590675D03*
X220652D03*
X223775Y584531D03*
X220668Y576731D03*
Y579331D03*
X223775Y581931D03*
Y579331D03*
Y576731D03*
X220668Y581931D03*
Y608131D03*
X223775D03*
X213912Y612605D03*
Y615085D03*
Y610125D03*
X217561Y616131D03*
Y613531D03*
X217556Y624575D03*
X223759Y624675D03*
X220652D03*
X223775Y618531D03*
X220668Y610731D03*
Y613331D03*
X223775Y615931D03*
Y613331D03*
Y610731D03*
X220668Y615931D03*
X223775Y621731D03*
X213912Y646605D03*
Y649085D03*
Y644125D03*
X217561Y650131D03*
Y647531D03*
X223775Y655731D03*
Y652531D03*
X220668Y644731D03*
Y647331D03*
Y642131D03*
X223775Y649931D03*
Y647331D03*
Y644731D03*
Y642131D03*
X220668Y649931D03*
X217556Y658575D03*
X223759Y658675D03*
X220652D03*
X210405Y1384302D03*
Y1387409D03*
X210374Y1390532D03*
X211395Y1400005D03*
X312301Y1345539D03*
Y1342432D03*
X309701Y1345539D03*
Y1342432D03*
X316655Y1352295D03*
X314175D03*
X311695D03*
X320101Y1342432D03*
X317701Y1348646D03*
X315101D03*
X314901Y1345539D03*
X317501D03*
X314901Y1342432D03*
X317501D03*
X320245Y1357401D03*
X316655Y1357895D03*
X311695D03*
X314175D03*
X322575Y1358151D03*
X326145Y1348651D03*
X326245Y1345555D03*
Y1342448D03*
X323301Y1342432D03*
X324905Y1357401D03*
X327235Y1358151D03*
X344429Y1322741D03*
X347029D03*
X341829D03*
X347029Y1319634D03*
X344429D03*
X341829D03*
X349629Y1322741D03*
Y1319634D03*
X352229D03*
X355429D03*
X346303Y1335097D03*
X343823D03*
Y1329497D03*
X346303D03*
X347229Y1325848D03*
X348783Y1329497D03*
X349829Y1325848D03*
X348783Y1335097D03*
X352373Y1334603D03*
X354703Y1335353D03*
X358373Y1322757D03*
Y1319650D03*
X358273Y1325853D03*
X357033Y1334603D03*
X359363Y1335353D03*
X373957Y1306208D03*
X381757D03*
X379157D03*
X376557D03*
X384357D03*
X387557D03*
X375951Y1321671D03*
X380911Y1316071D03*
X378431D03*
Y1321671D03*
X380911D03*
X373957Y1309315D03*
X381957Y1312422D03*
X381757Y1309315D03*
X379357Y1312422D03*
X379157Y1309315D03*
X376557D03*
X375951Y1316071D03*
X384501Y1321177D03*
X386831Y1321927D03*
X390501Y1306224D03*
X390401Y1312427D03*
X390501Y1309331D03*
X389161Y1321177D03*
X391491Y1321927D03*
X416485Y1306208D03*
X419685D03*
X413885D03*
X406085D03*
X411285D03*
X408685D03*
X414085Y1312422D03*
X413885Y1309315D03*
X411485Y1312422D03*
X408685Y1309315D03*
X406085D03*
X411285D03*
X413039Y1316071D03*
X408079D03*
X410559D03*
X413039Y1321671D03*
X408079D03*
X410559D03*
X416629Y1321177D03*
X418959Y1321927D03*
X422629Y1306224D03*
X422529Y1312427D03*
X422629Y1309331D03*
X421289Y1321177D03*
X423619Y1321927D03*
X448613Y1306208D03*
X446013D03*
X443413D03*
X440813D03*
X438213D03*
X451813D03*
X443613Y1312422D03*
X443413Y1309315D03*
X440813D03*
X438213D03*
X446213Y1312422D03*
X446013Y1309315D03*
X440207Y1316071D03*
X445167D03*
X442687D03*
X440207Y1321671D03*
X445167D03*
X442687D03*
X448757Y1321177D03*
X451087Y1321927D03*
X454757Y1306224D03*
X454657Y1312427D03*
X454757Y1309331D03*
X453417Y1321177D03*
X455747Y1321927D03*
X480741Y1306208D03*
X478141D03*
X475541D03*
X472941D03*
X470341D03*
X483941D03*
X472941Y1309315D03*
X478141D03*
X470341D03*
X478341Y1312422D03*
X475741D03*
X475541Y1309315D03*
X472335Y1316071D03*
X477295D03*
X474815D03*
X472335Y1321671D03*
X477295D03*
X474815D03*
X480885Y1321177D03*
X485545D03*
X483215Y1321927D03*
X486885Y1306224D03*
X486785Y1312427D03*
X486885Y1309331D03*
X487875Y1321927D03*
X516069Y1319634D03*
X502469D03*
Y1322741D03*
X512869Y1319634D03*
X510269D03*
X507669D03*
X505069D03*
X507669Y1322741D03*
X505069D03*
X510269D03*
X504463Y1329497D03*
Y1335097D03*
X509423Y1329497D03*
X506943D03*
X509423Y1335097D03*
X506943D03*
X510469Y1325848D03*
X507869D03*
X513013Y1334603D03*
X517673D03*
X515343Y1335353D03*
X519013Y1319650D03*
Y1322757D03*
X518913Y1325853D03*
X520003Y1335353D03*
X534597Y1345539D03*
Y1342432D03*
X548197D03*
X539997Y1348646D03*
X542397Y1345539D03*
X542597Y1348646D03*
X537197Y1342432D03*
X539797D03*
X542397D03*
X544997D03*
X537197Y1345539D03*
X539797D03*
X539071Y1352295D03*
X536591D03*
X541551D03*
X545141Y1357401D03*
X549801D03*
X541551Y1357895D03*
X536591D03*
X539071D03*
X547471Y1358151D03*
X551141Y1345555D03*
X551041Y1348651D03*
X551141Y1342448D03*
X552131Y1358151D03*
X677137Y1384311D03*
X674537D03*
X671937D03*
X669337D03*
X677137Y1387418D03*
X674537D03*
X671937D03*
X669337D03*
X679737Y1384311D03*
X677337Y1390525D03*
X674737D03*
X676250Y1399757D03*
X673820D03*
X671350D03*
X676250Y1394157D03*
X673820D03*
X671350D03*
X679881Y1399280D03*
X682937Y1384311D03*
X685881Y1384327D03*
Y1387434D03*
X685850Y1390557D03*
X684541Y1399280D03*
X682211Y1400030D03*
X686871D03*
X707480Y1384311D03*
X710080D03*
X707480Y1387418D03*
X710080D03*
X712680Y1384311D03*
Y1387418D03*
X709493Y1399757D03*
Y1394157D03*
X712880Y1390525D03*
X711963Y1399757D03*
Y1394157D03*
X715280Y1384311D03*
X717880D03*
X715280Y1387418D03*
X721080Y1384311D03*
X724024Y1384327D03*
Y1387434D03*
X715480Y1390525D03*
X723993Y1390557D03*
X714393Y1399757D03*
Y1394157D03*
X718024Y1399280D03*
X722684D03*
X720354Y1400030D03*
X725014D03*
X918532Y492445D03*
X927154Y492103D03*
X924623Y492097D03*
X918078Y495177D03*
X921189Y492086D03*
X918212Y497677D03*
X918131Y503330D03*
X921060Y506086D03*
X923783Y506076D03*
X918212Y500777D03*
X909984Y496330D03*
X926173Y512391D03*
X932373Y495175D03*
X932089Y492691D03*
X929654Y492103D03*
X932218Y499314D03*
X932089Y505986D03*
X932289Y502986D03*
X926637Y506069D03*
X929281Y506086D03*
X1131629Y1420615D03*
X1129029D03*
X1134229D03*
X1131629Y1423722D03*
X1129029D03*
X1134229D03*
X1131042Y1436061D03*
X1135942D03*
X1133512D03*
X1131042Y1430461D03*
X1135942D03*
X1133512D03*
X1134429Y1426829D03*
X1142629Y1420615D03*
X1145573Y1420631D03*
X1139429Y1420615D03*
X1136829D03*
X1145573Y1423738D03*
X1136829Y1423722D03*
X1145542Y1426861D03*
X1137029Y1426829D03*
X1146563Y1436334D03*
X1141903D03*
X1144233Y1435584D03*
X1139573D03*
X1167172Y1420615D03*
Y1423722D03*
X1183716Y1420631D03*
X1180772Y1420615D03*
X1174972D03*
X1177572D03*
X1172372D03*
X1169772D03*
X1183716Y1423738D03*
X1174972Y1423722D03*
X1172372D03*
X1169772D03*
X1174085Y1436061D03*
Y1430461D03*
X1171655Y1436061D03*
X1169185D03*
X1171655Y1430461D03*
X1169185D03*
X1183685Y1426861D03*
X1175172Y1426829D03*
X1172572D03*
X1184706Y1436334D03*
X1180046D03*
X1182376Y1435584D03*
X1177716D03*
X1197700Y1432672D03*
X1198010Y1441902D03*
X1198880Y1457162D03*
X1276745Y125850D03*
X1275807Y132922D03*
X1281600Y137962D03*
X1282568Y212722D03*
X1284930Y124922D03*
X1285793Y141562D03*
X1288258Y145501D03*
X1283781Y149115D03*
X1297605Y145824D03*
X1283781Y155788D03*
X1283397Y202085D03*
X1291205Y1345875D03*
X1286005Y1342768D03*
Y1345875D03*
X1296405Y1342768D03*
X1293805D03*
X1288605D03*
X1291205D03*
X1288605Y1345875D03*
X1293805D03*
X1291405Y1348982D03*
X1294005D03*
X1292916Y1352531D03*
X1290436D03*
X1287956D03*
X1292916Y1358131D03*
X1290436D03*
X1287956D03*
X1298836Y1358387D03*
X1296506Y1357637D03*
X1299605Y1342768D03*
X1302549Y1345891D03*
X1302520Y1348762D03*
X1302549Y1342784D03*
X1303496Y1358387D03*
X1301166Y1357637D03*
X1327920Y84418D03*
X1323958Y146227D03*
X1317970Y1322741D03*
Y1319634D03*
X1325770Y1322741D03*
X1323170D03*
X1331570Y1319634D03*
X1323170D03*
X1325770D03*
X1328370D03*
X1320570Y1322741D03*
Y1319634D03*
X1322444Y1329497D03*
X1324924D03*
X1319964D03*
X1322444Y1335097D03*
X1324924D03*
X1319964D03*
X1323370Y1325848D03*
X1325970D03*
X1328514Y1334603D03*
X1330844Y1335353D03*
X1333811Y235348D03*
X1334514Y1322757D03*
Y1319650D03*
X1334414Y1325853D03*
X1333174Y1334603D03*
X1335504Y1335353D03*
X1362793Y145262D03*
X1349704Y145385D03*
X1357888Y145893D03*
X1361111Y236448D03*
X1350098Y1306208D03*
X1352698D03*
X1355298D03*
X1360498D03*
X1363698D03*
X1357898D03*
X1352698Y1309315D03*
X1350098D03*
X1355498Y1312422D03*
X1358098D03*
X1355298Y1309315D03*
X1357898D03*
X1352092Y1316071D03*
Y1321671D03*
X1357052Y1316071D03*
X1354572D03*
X1357052Y1321671D03*
X1354572D03*
X1360593Y1321872D03*
X1363098Y1320951D03*
X1366868Y147341D03*
X1369593Y147462D03*
X1369916Y154132D03*
X1379969Y176330D03*
X1370586Y176366D03*
X1370405Y186938D03*
X1377597Y197604D03*
X1369479Y208384D03*
X1370636Y227292D03*
X1369410Y224504D03*
X1366642Y1306224D03*
X1366542Y1312427D03*
X1366642Y1309331D03*
X1365376Y1321938D03*
X1367635Y1320904D03*
X1386780Y197668D03*
X1395321D03*
X1382226Y1306208D03*
X1384826D03*
X1387426D03*
X1390026D03*
X1392626D03*
X1395826D03*
X1386700Y1321671D03*
X1389180D03*
X1382226Y1309315D03*
X1384826D03*
X1390226Y1312422D03*
X1387626D03*
X1390026Y1309315D03*
X1387426D03*
X1384220Y1316071D03*
Y1321671D03*
X1389180Y1316071D03*
X1386700D03*
X1392770Y1321177D03*
X1395100Y1321927D03*
X1404071Y197668D03*
X1412851D03*
X1398770Y1306224D03*
X1398670Y1312427D03*
X1398770Y1309331D03*
X1397430Y1321177D03*
X1399760Y1321927D03*
X1414354Y1306208D03*
X1416954D03*
X1419554D03*
X1422154D03*
X1424754D03*
X1427954D03*
X1418828Y1316071D03*
X1416348D03*
X1418828Y1321671D03*
X1416348D03*
X1421308Y1316071D03*
Y1321671D03*
X1414354Y1309315D03*
X1416954D03*
X1419554D03*
X1422354Y1312422D03*
X1419754D03*
X1422154Y1309315D03*
X1424898Y1321177D03*
X1427228Y1321927D03*
X1430898Y1306224D03*
X1430798Y1312427D03*
X1430898Y1309331D03*
X1429558Y1321177D03*
X1431888Y1321927D03*
X1446482Y1306208D03*
X1449082D03*
X1451682D03*
X1456882D03*
X1460082D03*
X1454282D03*
X1450956Y1321671D03*
X1448476D03*
X1453436Y1316071D03*
Y1321671D03*
X1446482Y1309315D03*
X1451882Y1312422D03*
X1449082Y1309315D03*
X1451682D03*
X1454482Y1312422D03*
X1454282Y1309315D03*
X1450956Y1316071D03*
X1448476D03*
X1457026Y1321177D03*
X1461686D03*
X1459356Y1321927D03*
X1463026Y1306224D03*
X1462926Y1312427D03*
X1463026Y1309331D03*
X1464016Y1321927D03*
X1486410Y1322741D03*
X1483810D03*
X1486410Y1319634D03*
X1483810D03*
X1481210Y1322741D03*
Y1319634D03*
X1492210D03*
X1489010D03*
X1478610Y1322741D03*
Y1319634D03*
X1484010Y1325848D03*
X1486610D03*
X1485564Y1335097D03*
X1483084D03*
X1485564Y1329497D03*
X1483084D03*
X1480604Y1335097D03*
Y1329497D03*
X1489154Y1334603D03*
X1493814D03*
X1491484Y1335353D03*
X1495154Y1322757D03*
Y1319650D03*
X1495054Y1325853D03*
X1496144Y1335353D03*
X1510738Y1345539D03*
Y1342432D03*
X1518538Y1345539D03*
Y1342432D03*
X1515938Y1345539D03*
Y1342432D03*
X1513338Y1345539D03*
Y1342432D03*
X1521138D03*
X1524338D03*
X1518738Y1348646D03*
X1516138D03*
X1515212Y1352295D03*
X1512732D03*
X1517692D03*
X1521282Y1357401D03*
X1525942D03*
X1515212Y1357895D03*
X1512732D03*
X1517692D03*
X1523612Y1358151D03*
X1527282Y1345555D03*
Y1342448D03*
X1527182Y1348651D03*
X1528272Y1358151D03*
X1636412Y638451D03*
X1636417Y630007D03*
X1640061Y639497D03*
X1636412Y641051D03*
X1630198Y638651D03*
Y636051D03*
Y641251D03*
X1633305Y638651D03*
Y641251D03*
X1630198Y632851D03*
X1630214Y629907D03*
X1633321D03*
X1640061Y644457D03*
Y641977D03*
X1630198Y643851D03*
X1633305Y646451D03*
Y643851D03*
X1630198Y646451D03*
X1636412Y672451D03*
X1636417Y664007D03*
X1640061Y673497D03*
X1630198Y672651D03*
Y670051D03*
X1633305Y672651D03*
X1630198Y666851D03*
X1630214Y663907D03*
X1633321D03*
X1640061Y678457D03*
Y675977D03*
X1636412Y675051D03*
X1630198Y677851D03*
Y675251D03*
X1633305Y680451D03*
Y675251D03*
Y677851D03*
X1630198Y680451D03*
X1636417Y698007D03*
X1636412Y706451D03*
X1630214Y697907D03*
X1633321D03*
X1630198Y704051D03*
Y706651D03*
X1633305D03*
X1630198Y700851D03*
X1640061Y707497D03*
Y712457D03*
Y709977D03*
X1636412Y709051D03*
X1633305Y711851D03*
Y709251D03*
X1630198D03*
Y711851D03*
X1633305Y714451D03*
X1630198D03*
X1633103Y1417907D03*
X1630503D03*
X1635703D03*
X1633103Y1421014D03*
X1630503D03*
X1635703D03*
X1638303Y1417907D03*
Y1421014D03*
X1635903Y1424121D03*
X1638503D03*
X1632516Y1427753D03*
Y1433353D03*
X1634986Y1427753D03*
Y1433353D03*
X1637416Y1427753D03*
Y1433353D03*
X1649149Y607022D03*
X1653929Y604546D03*
X1649139Y604576D03*
X1653736Y607033D03*
X1649117Y602139D03*
X1653930Y602099D03*
X1645661Y639497D03*
X1645917Y628917D03*
Y633577D03*
X1645167Y631247D03*
Y635907D03*
X1645661Y644457D03*
Y641977D03*
Y673497D03*
X1645917Y662917D03*
Y667577D03*
X1645167Y665247D03*
Y669907D03*
X1645661Y678457D03*
Y675977D03*
X1645167Y703907D03*
X1645917Y701577D03*
X1645167Y699247D03*
X1645917Y696917D03*
X1645661Y707497D03*
Y709977D03*
Y712457D03*
X1644103Y1417907D03*
X1647047Y1417923D03*
Y1421030D03*
X1640903Y1417907D03*
X1647016Y1424153D03*
X1641047Y1432876D03*
X1645707D03*
X1643377Y1433626D03*
X1648037D03*
X1668646Y1417907D03*
Y1421014D03*
X1671246Y1417907D03*
Y1421014D03*
X1670659Y1427753D03*
X1673129D03*
X1670659Y1433353D03*
X1673129D03*
X1685190Y1417923D03*
X1676446Y1417907D03*
X1679046D03*
X1682246D03*
X1676446Y1421014D03*
X1685190Y1421030D03*
X1673846Y1417907D03*
Y1421014D03*
X1676646Y1424121D03*
X1685159Y1424153D03*
X1675559Y1427753D03*
Y1433353D03*
X1674046Y1424121D03*
X1679190Y1432876D03*
X1683850D03*
X1681520Y1433626D03*
X1686180D03*
X1699457Y1439185D03*
Y1447805D03*
X1746970Y1451872D03*
X1750970Y1459172D03*
Y1456172D03*
X1760160Y1476032D03*
X1763730Y1483712D03*
Y1480712D03*
X1763830Y1490782D03*
Y1487782D03*
G54D125*
G01X54762Y444993D02*
X52758Y442989D01*
X50696D01*
G01X190827Y1403451D02*
Y1405651D01*
X190971Y1405795D01*
Y1407595D01*
G01X306667Y1361597D02*
Y1360553D01*
X306075Y1359961D01*
X302401D01*
G01X451048Y1404914D02*
X451849Y1405715D01*
Y1407229D01*
G01X467307Y1325373D02*
Y1324187D01*
X465137Y1322017D01*
X464191D01*
G01X704446Y1403476D02*
X703495Y1402525D01*
X702735D01*
X701830Y1401620D01*
G01X1164138Y1439780D02*
Y1442080D01*
X1164152Y1442094D01*
Y1442134D01*
X1164172Y1442154D01*
Y1443954D01*
G01X1279334Y1356089D02*
X1279801Y1355622D01*
X1282313D01*
G01X1311820Y1333018D02*
X1312014Y1332824D01*
X1314441D01*
G01X1426872Y1405811D02*
X1427988D01*
X1428990Y1406813D01*
Y1408229D01*
G01X1443448Y1325373D02*
Y1327565D01*
X1444293Y1328410D01*
Y1330312D01*
G01X1665612Y1437072D02*
Y1439352D01*
X1665666Y1439406D01*
Y1441206D01*
G54D116*
G01X24700Y765600D02*
Y770300D01*
X26907Y772507D01*
X40839D01*
G01X30680Y445519D02*
Y441130D01*
G01D02*
Y438142D01*
G01X36449Y1257262D02*
X37770Y1255941D01*
Y1254400D01*
G01X33674Y1256964D02*
X36151D01*
X36449Y1257262D01*
G01X56722Y435451D02*
X53800D01*
G01X64150Y434972D02*
X63738Y435384D01*
X60761D01*
G01X58658Y754145D02*
X57981Y754822D01*
X54847D01*
G01X65503Y443677D02*
X68365D01*
G01X76365Y699244D02*
X77121Y698488D01*
Y696156D01*
G01X71359Y754726D02*
X73759D01*
G01X71465Y763164D02*
X73865D01*
G01X71359Y759246D02*
X73759D01*
G01X93295Y762019D02*
X95779D01*
G01D02*
X99779D01*
G01X110527Y758869D02*
X107779D01*
G01X132967Y760525D02*
X133561Y761119D01*
X136029D01*
G01D02*
X140029D01*
G01X154414Y1253412D02*
Y1254857D01*
X154965Y1255408D01*
Y1256964D01*
G01X155100Y1720657D02*
Y1723262D01*
G01X171180Y401885D02*
X168562Y399267D01*
Y397578D01*
G01X238063Y34328D02*
Y37162D01*
G01X246859Y60511D02*
X245049D01*
X244300Y59762D01*
G01X250859Y60521D02*
X250738Y60642D01*
X246990D01*
X246859Y60511D01*
G01X244789Y1260093D02*
Y1257733D01*
X245066Y1257456D01*
G01X270322Y740207D02*
X268870Y741659D01*
Y743993D01*
G01X287952Y39984D02*
X286720Y41216D01*
Y42787D01*
G01X299427Y768265D02*
X295557Y772135D01*
Y791325D01*
X280187Y806695D01*
Y812555D01*
X275639Y817103D01*
Y863872D01*
G01X291520Y15162D02*
Y12762D01*
G01X298720Y42787D02*
Y40017D01*
G01X306720Y42787D02*
Y39982D01*
G01X349187Y715485D02*
X352527D01*
X354305Y713707D01*
Y710632D01*
G01X349187Y718112D02*
Y715485D01*
G01X344446Y739434D02*
Y742191D01*
X344440Y742197D01*
G01X359930Y732985D02*
X370647D01*
X374590Y736928D01*
G01D02*
X378902Y741240D01*
Y749233D01*
G01X387760Y1671092D02*
X383740Y1667072D01*
Y1663557D01*
G01X549540Y1069382D02*
X596650D01*
X601260Y1073992D01*
X608340D01*
X610820Y1076472D01*
Y1312572D01*
X618780Y1320532D01*
X632800D01*
X636140Y1323872D01*
Y1391132D01*
X641150Y1396142D01*
Y1494602D01*
X635270Y1500482D01*
X480220D01*
X473900Y1494162D01*
Y1448042D01*
X468360Y1442502D01*
Y1428452D01*
X471408Y1425404D01*
X476026D01*
X479646Y1421784D01*
Y1418684D01*
G01X455602Y1412334D02*
X454946Y1411678D01*
X453124D01*
G01X477882Y1398402D02*
X476840D01*
X475285Y1396847D01*
Y1395402D01*
G01X485236Y1417844D02*
X486684Y1416396D01*
X488570D01*
G01X499590Y88167D02*
X497002D01*
G01X498630Y143157D02*
Y140492D01*
G01X503100Y78402D02*
Y81117D01*
G01X510030Y78412D02*
X508450D01*
X507310Y79552D01*
Y81087D01*
G01X503290Y143147D02*
Y140492D01*
G01X507360Y143117D02*
Y140492D01*
G01X525900Y104225D02*
X528400D01*
G01X525900Y114275D02*
X528400D01*
G01X548609Y35287D02*
Y32500D01*
G01X542530Y120307D02*
X546370D01*
G01X549610Y120682D02*
X549235Y120307D01*
X546370D01*
G01X537360Y120522D02*
X536250Y119412D01*
Y112592D01*
G01X586137Y740985D02*
X585077D01*
X582530Y743532D01*
Y746622D01*
X583795Y747887D01*
X585431D01*
G01X589989Y745475D02*
X586487D01*
X585431Y746531D01*
Y747887D01*
G01X605830Y402782D02*
X608463Y400149D01*
X614882D01*
G01X610820Y472862D02*
X613520Y470162D01*
X615820D01*
X616645Y469337D01*
Y467862D01*
G01X612407Y769485D02*
X614352Y767540D01*
X614750D01*
G01X629002Y166162D02*
X624876D01*
X624831Y166207D01*
G01X631300Y167872D02*
X629590Y166162D01*
X629002D01*
G01X629220Y467862D02*
X629320Y467762D01*
Y465962D01*
X631645Y463637D01*
Y462862D01*
G01Y482862D02*
X629220D01*
G01X618114Y1258470D02*
X618549D01*
X619683Y1257336D01*
X623217D01*
G01X646645Y472862D02*
X644245D01*
G01X646645Y467862D02*
X644220D01*
G01X646645Y477862D02*
Y482862D01*
G01D02*
X644245D01*
G01X650599Y984318D02*
X651602Y985321D01*
X653488D01*
G01X676203Y444785D02*
X674628Y443210D01*
G01X671479Y430612D02*
X670911D01*
X669904Y431619D01*
Y432187D01*
G01X671479Y462108D02*
X670955D01*
X669904Y461057D01*
Y460533D01*
G01X688220Y388362D02*
X688247Y388335D01*
Y384730D01*
G01X684077Y414864D02*
Y414325D01*
X685113Y413289D01*
X685652D01*
G01X684077Y477856D02*
Y478459D01*
X685049Y479431D01*
X685652D01*
G01X688916Y1256964D02*
X689014Y1257062D01*
X691225D01*
G01X706673Y122762D02*
X706427D01*
X701062Y128127D01*
X700960D01*
G01X702838Y412255D02*
Y414727D01*
X702975Y414864D01*
G01X702560Y421540D02*
X705748D01*
X706125Y421163D01*
G01X708300Y421900D02*
X706862D01*
X706125Y421163D01*
G01X701400Y466832D02*
X699825Y468407D01*
G01X704537Y1587683D02*
X702112D01*
G01X725022Y414864D02*
Y414264D01*
X724047Y413289D01*
X723447D01*
G01X717622Y412269D02*
Y408385D01*
G01D02*
X717645Y408362D01*
G01X726597Y447935D02*
X728172Y449510D01*
G01X725022Y477856D02*
Y478380D01*
X723971Y479431D01*
X723447D01*
G01X717152Y1570093D02*
X717752Y1569493D01*
X719577D01*
G01X737621Y411714D02*
X738599Y412692D01*
X740415D01*
G01X731322Y430612D02*
X731900D01*
X732897Y431609D01*
Y432187D01*
G01X731322Y462108D02*
X731884D01*
X732897Y461095D01*
Y460533D01*
G01X740909Y763779D02*
X736909D01*
G01X737299Y766887D02*
Y765717D01*
X736909Y765327D01*
Y763779D01*
G01X750595Y74562D02*
X753074D01*
X754219Y75707D01*
G01X757464Y286632D02*
X754290D01*
G01X753137Y766625D02*
X753009Y766497D01*
Y763839D01*
G01D02*
X757009D01*
G01X748283Y1256964D02*
X748413Y1257094D01*
X750393D01*
X750525Y1256962D01*
Y1256822D01*
X750585Y1256762D01*
G01X763795Y418212D02*
X766195D01*
G01X762915Y464862D02*
X765315D01*
G01X775317Y764025D02*
Y759725D01*
X776705Y758337D01*
X778724D01*
G01X763747Y764335D02*
X763617Y764205D01*
Y762340D01*
X762832Y761555D01*
G01X792895Y271469D02*
X797443D01*
G01X780617Y296345D02*
X780731Y296231D01*
X787977D01*
G01X781410Y431822D02*
X780567Y432665D01*
X778888D01*
G01X777915Y474862D02*
X780340D01*
G01X801094Y312773D02*
X798620D01*
G01X803150Y408512D02*
X808843Y414205D01*
Y425554D01*
G01X802102Y759665D02*
X802300Y759863D01*
Y763717D01*
X802102Y763915D01*
G01D02*
X799927D01*
X799637Y763625D01*
G01X822500Y286625D02*
X827403D01*
G01X814800Y760922D02*
X815193Y761315D01*
X818724D01*
G01X822442Y762369D02*
X824292Y760519D01*
Y760215D01*
G01X824389Y764316D02*
X822442Y762369D01*
G01X829320Y296762D02*
X829571Y296511D01*
X835499D01*
G01X837499Y770144D02*
X837618Y770025D01*
X840322D01*
G01X836847Y762495D02*
X837807Y761535D01*
X840994D01*
G01X859100Y761685D02*
X854687D01*
G01X905010Y493862D02*
X903070D01*
X901110Y495822D01*
X900460D01*
G01X906127Y496343D02*
X905010Y495226D01*
Y493862D01*
G01X923322Y990227D02*
X920322Y993227D01*
X919300D01*
G01X918300Y1663825D02*
X922282D01*
X922320Y1663787D01*
G01D02*
Y1660953D01*
G01X930220Y193386D02*
X930020Y193186D01*
Y189386D01*
G01D02*
X927133D01*
G01X925320Y203399D02*
X927107Y201612D01*
X928350D01*
G01X937943Y505977D02*
Y501930D01*
X937938Y501925D01*
G01D02*
Y498114D01*
X937969Y498083D01*
G01X940596Y498648D02*
X940031Y498083D01*
X937969D01*
G01X938220Y1663687D02*
Y1661062D01*
G01X927122Y1661380D02*
X926120Y1662382D01*
Y1663787D01*
G01X946100Y1663725D02*
Y1661100D01*
G01X942100Y1663725D02*
X946100D01*
G01X960620Y506837D02*
Y509462D01*
G01X972379Y506866D02*
Y509303D01*
G01X985016Y344659D02*
X987184Y342491D01*
Y341799D01*
G01X1019935Y203333D02*
Y202894D01*
X1022735Y200094D01*
Y194609D01*
G01X1020069Y302988D02*
X1024099D01*
G01X1012543Y1257198D02*
X1013830Y1255911D01*
Y1254263D01*
G01X1009810Y1257810D02*
X1011931D01*
X1012543Y1257198D01*
G01X1036915Y290969D02*
Y293232D01*
X1037000Y293317D01*
Y293437D01*
G01X1035688Y393112D02*
Y394658D01*
X1033041Y397305D01*
G01X1033860Y400802D02*
X1033041Y399983D01*
Y397305D01*
G01X1043629Y375078D02*
Y372578D01*
G01X1049100Y390162D02*
X1047500Y388562D01*
Y387437D01*
G01X1096477Y744385D02*
Y747225D01*
X1098896Y749644D01*
Y760904D01*
G01D02*
X1102796D01*
G01X1101554Y1257102D02*
X1102408Y1257956D01*
X1105717D01*
G01X1098916Y1256944D02*
X1099074Y1257102D01*
X1101554D01*
G01X1117783Y766798D02*
X1119869Y764712D01*
Y764139D01*
G01X1115869D02*
Y764884D01*
X1117783Y766798D01*
G01X1153467Y588947D02*
Y586462D01*
G01X1170337Y607327D02*
X1164858D01*
G01X1158316Y1256944D02*
X1159138D01*
X1161065Y1258871D01*
G01D02*
X1161757Y1258179D01*
X1163891D01*
G01X1199027Y588714D02*
X1196348D01*
G01X1201533D02*
X1199027D01*
G01X1190966Y1258711D02*
X1191926Y1257751D01*
Y1256140D01*
G01X1188016Y1256944D02*
X1189199D01*
X1190966Y1258711D01*
G01X1206093Y120362D02*
X1206693Y120962D01*
X1208518D01*
G01X1211741Y1248688D02*
X1210716Y1247663D01*
X1209315D01*
G01X1216933Y1256789D02*
Y1257481D01*
X1218415Y1258963D01*
X1219145Y1259265D01*
X1220103D01*
X1220931Y1260093D01*
G01X1228704Y109137D02*
Y112122D01*
G01X1226093Y152792D02*
X1228868D01*
X1229048Y152612D01*
G01X1226145Y217862D02*
X1223720D01*
G01X1226145Y213862D02*
Y209862D01*
G01Y205862D02*
X1223720D01*
G01X1226145Y209862D02*
Y205862D01*
G01X1247333Y121999D02*
X1249441Y124107D01*
X1250011D01*
G01X1239018Y205462D02*
Y209462D01*
G01X1236593Y209562D02*
X1238918D01*
X1239018Y209462D01*
G01Y213462D02*
X1236520D01*
G01X1250101Y256098D02*
X1246444D01*
G01X1236583Y907349D02*
X1236719Y907485D01*
X1239702D01*
G01X1262383Y103585D02*
Y101517D01*
X1262800Y101100D01*
G01X1251636Y142282D02*
X1252816Y143462D01*
X1256093D01*
G01D02*
X1257663Y145032D01*
X1259745D01*
X1261012Y146299D01*
X1261784D01*
G01X1279485Y105752D02*
Y110450D01*
G01X1294354Y105912D02*
Y109706D01*
X1295807Y111159D01*
Y112018D01*
G01X1290005Y293768D02*
X1286189D01*
X1285189Y294768D01*
G01X1300454Y95302D02*
X1301945Y96793D01*
Y99262D01*
G01X1303220Y107487D02*
Y102262D01*
X1302120Y101162D01*
Y99437D01*
X1301945Y99262D01*
G01X1330273Y128373D02*
X1328946Y129700D01*
Y131205D01*
G01X1332886Y126132D02*
X1334886Y124132D01*
X1336930D01*
G01X1339280Y126175D02*
Y125850D01*
X1337562Y124132D01*
X1336930D01*
G01X1336187Y755635D02*
X1337637Y754185D01*
Y753234D01*
X1338495Y752376D01*
G01X1356223Y131569D02*
X1357736D01*
X1359137Y130168D01*
Y128285D01*
G01X1352560Y205549D02*
X1351013Y207096D01*
X1348241D01*
G01X1437177Y720965D02*
X1434597Y723545D01*
Y724612D01*
G01X1439715Y717132D02*
Y718427D01*
X1437177Y720965D01*
G01X1525420Y1069422D02*
X1572820D01*
X1578150Y1074752D01*
X1585270D01*
X1588330Y1077812D01*
Y1328972D01*
X1601190Y1341832D01*
Y1498062D01*
X1594180Y1505072D01*
X1454970D01*
X1448420Y1498522D01*
Y1428576D01*
X1455787Y1421209D01*
Y1418644D01*
G01X1437140Y1576012D02*
X1438685Y1574467D01*
Y1570772D01*
G01X1456295Y149362D02*
X1458720D01*
G01X1456295Y145362D02*
X1458720D01*
G01X1456295Y153362D02*
X1458720D01*
G01X1456295Y165862D02*
X1458720D01*
G01X1456295Y161862D02*
X1458720D01*
G01X1456295Y169862D02*
X1458720D01*
G01X1456295Y181862D02*
X1458720D01*
G01X1456295Y177862D02*
X1458720D01*
G01X1456295Y173862D02*
X1458720D01*
G01X1459057Y733545D02*
X1459800Y732802D01*
X1463197D01*
G01X1463282Y746305D02*
Y748110D01*
X1462291Y749101D01*
X1455983D01*
X1454287Y747405D01*
G01X1446372Y746305D02*
Y747730D01*
X1448237Y749595D01*
X1452097D01*
X1454287Y747405D01*
G01X1457597Y739035D02*
X1455687D01*
X1454287Y740435D01*
Y747405D01*
G01X1459431Y1395820D02*
X1463249D01*
G01X1467795Y145362D02*
X1470220D01*
G01X1474100Y735662D02*
X1475674D01*
X1478656Y738644D01*
Y749226D01*
G01X1465747Y1401405D02*
Y1397220D01*
X1464347Y1395820D01*
X1463249D01*
G01X1461377Y1417844D02*
X1464843D01*
X1465747Y1416940D01*
G01X1497770Y732502D02*
X1499020Y731252D01*
X1502396D01*
G01X1517575Y749690D02*
X1521975D01*
G01X1524505Y748912D02*
X1524031D01*
X1523253Y749690D01*
X1521975D01*
G01X1557560Y196912D02*
X1559325Y198677D01*
X1561890D01*
G01X1559860Y240002D02*
X1560205Y240347D01*
X1562890D01*
G01X1597041Y770144D02*
X1595677Y768780D01*
X1590915D01*
G01X1596444Y215526D02*
X1596402Y215568D01*
X1592173D01*
G01X1602650Y1254648D02*
X1606059D01*
X1606355Y1254944D01*
X1609439D01*
G01X1610150Y1257172D02*
Y1255655D01*
X1609439Y1254944D01*
G01X1632716Y1256944D02*
X1634968D01*
X1635688Y1257664D01*
G01D02*
X1636539Y1256813D01*
Y1254844D01*
G01X1654667Y762809D02*
X1658679D01*
G01X1651583Y766798D02*
X1654667Y763714D01*
Y762809D01*
G01X1662416Y1256944D02*
X1663436Y1257964D01*
X1665688D01*
G01D02*
X1666339Y1257313D01*
Y1255044D01*
G01X1703000Y96437D02*
X1699000D01*
G01D02*
X1695950D01*
G01X1697725Y202470D02*
X1700710Y199485D01*
Y196010D01*
X1704070Y192650D01*
X1709521D01*
G01X1697725Y205120D02*
Y202470D01*
G01X1696120Y506937D02*
X1697810Y508627D01*
X1699150D01*
G01X1698920Y698562D02*
Y697662D01*
X1700692Y695890D01*
X1702067D01*
G01X1706017D02*
X1702067D01*
G01X1702848Y763643D02*
X1706948D01*
G01X1698537Y766015D02*
X1700909Y763643D01*
X1702848D01*
G01X1692116Y1256944D02*
X1695068D01*
X1695188Y1257064D01*
G01D02*
X1695939Y1256313D01*
Y1254244D01*
G01X1714520Y37162D02*
X1713173Y35815D01*
Y34319D01*
G01X1708000Y96437D02*
Y99122D01*
G01X1717280Y174970D02*
X1717240Y175010D01*
Y179110D01*
X1714639Y181711D01*
Y185170D01*
G01X1712820Y172205D02*
X1714515D01*
X1717280Y174970D01*
G01X1706720Y703762D02*
X1705896Y704586D01*
Y706372D01*
G01X1721816Y1256944D02*
X1724368D01*
X1724588Y1257164D01*
G01D02*
X1725539Y1256213D01*
Y1254344D01*
G01X1751516Y1256944D02*
X1751836Y1257264D01*
X1754488D01*
G01X1769791Y34429D02*
X1769900Y34538D01*
Y37732D01*
G01D02*
X1772670D01*
X1773554Y38616D01*
Y40134D01*
G01X1769900Y37732D02*
X1768490D01*
X1767074Y36316D01*
X1763066D01*
X1762075Y37307D01*
Y40134D01*
G01X1754488Y1257264D02*
X1755039Y1256713D01*
Y1254344D01*
G01X1771029Y295164D02*
Y297364D01*
X1770566Y297827D01*
Y300384D01*
G01D02*
X1774452D01*
X1774537Y300469D01*
G01X1781216Y1256944D02*
X1783468D01*
X1784188Y1257664D01*
G01D02*
X1785239Y1256613D01*
Y1254744D01*
G01X1803245Y1256426D02*
X1800107D01*
G01X1795484Y1496401D02*
X1792395Y1499490D01*
Y1505652D01*
G01X1819054Y1253986D02*
X1818578Y1253510D01*
X1816612D01*
G54D107*
X1343332Y175405D03*
G54D23*
X40839Y769449D03*
X74169Y381709D03*
X77121Y693098D03*
X80971D03*
X90396Y692430D03*
X109200Y637379D03*
X105400Y639579D03*
X99516Y690740D03*
X99779Y758961D03*
X103779D03*
X107779D03*
X95779D03*
X112497Y513781D03*
X112900Y637979D03*
X126092Y638660D03*
X136029Y758061D03*
X140029D03*
X140104Y1554594D03*
X144029Y758061D03*
X148029D03*
X144120Y1355829D03*
X153789Y1394443D03*
X155100Y1717599D03*
X168562Y394520D03*
X191602Y759382D03*
X187602D03*
X183602D03*
X182727Y1355718D03*
X190332Y1394418D03*
X190971Y1407687D03*
X205320Y673879D03*
X207602Y759382D03*
X203602D03*
X195602D03*
X199602D03*
X209220Y673879D03*
X211602Y759382D03*
X214580Y1355711D03*
X238063Y31270D03*
X248442Y769424D03*
X257342Y768724D03*
X245066Y1254398D03*
X269046Y720186D03*
X265043D03*
X269046Y729981D03*
X273000Y740521D03*
X268870Y744085D03*
X286046Y720186D03*
X282120Y720084D03*
X288646Y749381D03*
X295520Y15254D03*
X298720Y42879D03*
X290720D03*
X294687Y704587D03*
X301038Y720841D03*
Y713702D03*
X297087Y723934D03*
X304602Y730511D03*
X296706Y749325D03*
X300839Y1315708D03*
X306207Y1352564D03*
X302401Y1360053D03*
X306720Y42879D03*
X320656Y723305D03*
X316656D03*
X317967Y740851D03*
X338161Y715307D03*
X327096Y738815D03*
X328656Y723305D03*
X335126Y730815D03*
X336446Y749325D03*
X328620Y1305069D03*
X338300Y1329766D03*
X336179Y1337035D03*
X340446Y749325D03*
X344446D03*
X370902D03*
X362902D03*
X358902D03*
X368391Y1322448D03*
X382902Y749325D03*
X378902D03*
X386902D03*
X372428Y1316440D03*
X383740Y1660499D03*
X390820Y1278379D03*
X400462Y1322109D03*
X405156Y1316805D03*
X416127Y1408182D03*
X431728Y1322084D03*
X424320Y1402079D03*
X430910Y1402089D03*
X432851Y1618354D03*
X436701Y1316246D03*
X450294Y1417486D03*
X440270Y1619289D03*
X444600Y1619449D03*
X460800Y380079D03*
X468831Y1278008D03*
X468790Y1316208D03*
X464191Y1322109D03*
X473013Y1030141D03*
X499510Y81139D03*
X490963Y1277961D03*
X496319Y1335535D03*
X501013Y1329615D03*
X488570Y1413338D03*
X503150Y71489D03*
X507310Y71509D03*
X529720Y35379D03*
X525900Y111217D03*
X530052Y1312623D03*
X533423Y1352564D03*
X528929Y1358608D03*
X539720Y35379D03*
X534720D03*
X542530Y117249D03*
X546370D03*
X554720Y35379D03*
X572500D03*
X568500D03*
X590100Y56879D03*
X597220Y88379D03*
X592220D03*
X595597Y747947D03*
X608250Y749982D03*
X611760Y743987D03*
X599763Y747963D03*
X614750Y757482D03*
Y764482D03*
X608225Y757547D03*
X607340Y883614D03*
X631130Y55799D03*
X624831Y163149D03*
X629002Y163104D03*
X639000Y60379D03*
X635000D03*
X633673Y1253265D03*
X649047Y33627D03*
X664342Y774624D03*
X661942Y1401752D03*
X671942Y770224D03*
X667408Y1394468D03*
X685968Y52699D03*
X690220D03*
X686588Y87354D03*
X696760Y128249D03*
X688247Y381672D03*
X692247D03*
X694720Y486504D03*
X690720D03*
X693310Y757178D03*
X688967Y787509D03*
X696860Y1355997D03*
X707500Y75379D03*
X708110Y82629D03*
X703500Y75379D03*
X712100Y82629D03*
X701362Y757178D03*
X697336D03*
X705388D03*
X710688D03*
X701830Y1401712D03*
X703951Y1394443D03*
X708219Y1634868D03*
X724644Y52062D03*
X729293D03*
X719949D03*
X723400Y82579D03*
X728909Y760721D03*
X714688Y757178D03*
X718688D03*
X728199Y1355736D03*
X724452Y1584035D03*
X724392Y1604280D03*
X716202Y1604263D03*
X737595Y52062D03*
X741377D03*
X733642D03*
X745474D03*
X732501Y74965D03*
X736601D03*
X745220Y511379D03*
X736909Y760721D03*
X745009Y760781D03*
X732909Y760721D03*
X740909D03*
X749477Y52062D03*
X751220Y511379D03*
X753009Y760781D03*
X749009D03*
X757009D03*
X758758Y1666458D03*
X765188Y1585218D03*
X768714Y1666458D03*
X808797Y433442D03*
X808297Y1588300D03*
X833445Y223235D03*
X849767Y1239993D03*
X850415Y1587764D03*
X898087Y462929D03*
X902875D03*
X907420Y466079D03*
X905010Y490804D03*
X892332Y1588160D03*
X911520Y466079D03*
X916111Y509044D03*
X921149Y520073D03*
X919350Y979549D03*
X919300Y990169D03*
X914500Y1663917D03*
X937643Y511867D03*
X926380Y979699D03*
X961445Y381271D03*
X972379Y503808D03*
X960620Y503779D03*
X980092Y412913D03*
X992345D03*
X994956Y424419D03*
X1020069Y299930D03*
X1009000Y380379D03*
X1024099Y299930D03*
X1035688Y390054D03*
X1047500Y384379D03*
X1053749Y760341D03*
X1057749D03*
X1065749D03*
X1061749D03*
X1087196Y760996D03*
X1083296D03*
X1091096D03*
X1098896D03*
X1102796D03*
X1094996D03*
X1115869Y761081D03*
X1106696Y760996D03*
X1119869Y761081D03*
X1110680Y761158D03*
X1105717Y1254898D03*
X1117420Y1392330D03*
X1127869Y761081D03*
X1123869D03*
X1121753Y1438096D03*
X1127100Y1430772D03*
X1126100Y1444799D03*
X1149467Y589039D03*
X1145467D03*
X1142921Y1254694D03*
X1151687Y1577255D03*
X1141687D03*
X1145687D03*
X1153537Y603029D03*
X1153477Y596059D03*
X1163891Y1255121D03*
X1156552Y1392302D03*
X1163643Y1430747D03*
X1164172Y1444046D03*
X1161095Y1577255D03*
X1155687D03*
X1165095D03*
X1172742Y770924D03*
X1179842Y778824D03*
X1171095Y1577255D03*
X1175095D03*
X1197396Y595838D03*
Y602853D03*
X1187891Y1392041D03*
X1228704Y106079D03*
X1228860Y761282D03*
X1222707Y760442D03*
X1249122Y752924D03*
X1242260Y760482D03*
X1235360D03*
X1258195Y126354D03*
X1260544Y228039D03*
X1256193Y730682D03*
X1252847Y738312D03*
X1263937Y742482D03*
X1266723Y103677D03*
X1280291Y242631D03*
X1277257Y733502D03*
X1273257Y733582D03*
X1280797Y740482D03*
X1274198Y747608D03*
X1276980Y1311769D03*
X1282313Y1352564D03*
X1280192Y1359833D03*
X1297821Y100105D03*
X1283485Y112072D03*
X1287641D03*
X1291704Y112111D03*
X1284120Y241659D03*
X1295947Y725242D03*
X1292007Y727252D03*
X1294937Y749482D03*
X1284797Y742202D03*
X1299890Y127259D03*
X1313597Y742312D03*
X1301487Y749812D03*
X1303761Y1313069D03*
X1314441Y1329766D03*
X1312320Y1337035D03*
X1322501Y183116D03*
X1328020Y176238D03*
X1317567Y742322D03*
X1330888Y749526D03*
X1346604Y146449D03*
X1342525D03*
X1343012Y203560D03*
X1334298Y738669D03*
X1344532Y1322448D03*
X1353850Y137189D03*
X1348241Y204038D03*
X1348569Y1316440D03*
X1367420Y1278579D03*
X1381297Y1316805D03*
X1406963Y1402062D03*
X1412842Y1316246D03*
X1426435Y1417486D03*
X1444852Y1278478D03*
X1444931Y1316208D03*
X1449443Y1029830D03*
X1455734Y1395912D03*
X1469067Y731372D03*
X1466984Y1278431D03*
X1477154Y1329615D03*
X1472460Y1335535D03*
X1465747Y1413882D03*
X1478656Y749318D03*
X1490992Y749681D03*
X1486741Y749319D03*
X1503645Y749782D03*
X1509564Y1352564D03*
X1505070Y1358608D03*
X1517575Y741447D03*
X1584000Y749879D03*
X1582000Y756879D03*
X1590915Y758562D03*
X1582017Y900582D03*
X1602788Y758712D03*
X1594997Y758532D03*
X1606788Y758712D03*
X1618788D03*
X1610788D03*
X1614788D03*
X1622077Y1437033D03*
X1638928Y758712D03*
X1630928D03*
X1634928D03*
X1628600Y1428144D03*
X1653220Y615179D03*
X1654667Y759751D03*
X1662276Y540478D03*
X1658679Y759751D03*
X1666686D03*
X1662656D03*
X1658026Y1388743D03*
X1665117Y1428039D03*
X1665666Y1441298D03*
X1685686Y479170D03*
X1703000Y93379D03*
X1699000D03*
X1699150Y505569D03*
X1702848Y760585D03*
X1689565Y1388482D03*
X1710025Y18409D03*
X1713173Y31261D03*
X1708000Y93379D03*
X1708680Y172267D03*
X1707160Y204217D03*
X1710057Y695982D03*
X1709486Y711004D03*
X1714955Y760593D03*
X1710915D03*
X1706948Y760585D03*
X1769791Y31371D03*
X1758075Y40226D03*
X1755378Y228045D03*
X1779575Y13739D03*
X1774435Y13759D03*
G54D41*
X164686Y394320D03*
D03*
Y391170D03*
Y397470D03*
X753835Y309670D03*
Y306520D03*
Y312820D03*
Y309670D03*
X1288020Y267477D03*
Y270627D03*
G54D32*
X57544Y399979D03*
X53738Y399953D03*
X60761Y438442D03*
X56722Y438509D03*
X61775Y1247944D03*
X65397Y384611D03*
X69998Y384720D03*
X73281Y696094D03*
X91123Y1247018D03*
X94700Y1542755D03*
X95876Y693686D03*
X125760Y656023D03*
X135950Y1257625D03*
X159197Y1237179D03*
X173865Y1243309D03*
X201360Y672725D03*
X219272Y762868D03*
X241160Y1247975D03*
X254122Y36853D03*
X246220Y36845D03*
X250220D03*
X242220D03*
X246859Y63569D03*
X250859Y63579D03*
X250457Y761068D03*
X254477Y761178D03*
X273046Y723152D03*
Y732947D03*
X273246Y752647D03*
X286720Y45845D03*
X281046Y732947D03*
X277046Y723152D03*
Y732947D03*
Y743447D03*
X281046D03*
X285046D03*
X281046Y752447D03*
X277046D03*
X285046D03*
X275639Y866930D03*
X274693Y1254969D03*
X291520Y18220D03*
X302720Y45845D03*
X294720D03*
X298211Y180762D03*
X290953Y717308D03*
X292706Y752291D03*
X300839Y1311039D03*
X316345Y208107D03*
X318158Y231470D03*
X316656Y733271D03*
X320656D03*
X312656Y726271D03*
X307967Y726327D03*
X317967Y752798D03*
X332656Y726271D03*
X324656D03*
X334546Y741781D03*
X351946Y725955D03*
X348037Y725958D03*
X344440Y745255D03*
X355946Y725958D03*
X366902Y752291D03*
X374902D03*
X387810Y1663515D03*
X391880Y1663475D03*
X436514Y1639400D03*
X440280Y1639470D03*
X499590Y91225D03*
X498730Y125605D03*
X498630Y146215D03*
X503100Y84175D03*
X507310Y84145D03*
X503270Y125615D03*
X507320Y125665D03*
X503290Y146205D03*
X507360Y146175D03*
X525900Y107283D03*
X548609Y38345D03*
X545450Y91810D03*
X541370D03*
X563100Y55665D03*
X581520Y55745D03*
X576200Y55705D03*
X571580Y55665D03*
X598405D03*
X594097D03*
X592076Y750948D03*
X610970Y55675D03*
X606330Y55665D03*
X602350D03*
X614750Y753448D03*
X603276Y750948D03*
X620097Y55665D03*
X631060Y51775D03*
X619090Y45775D03*
X620814Y158459D03*
X617008Y158433D03*
X645083Y36589D03*
X635000Y54345D03*
X639000D03*
X633603Y166179D03*
X644335Y1256276D03*
X654196Y1247910D03*
X670080Y55665D03*
X678050D03*
X674080D03*
X667347Y761368D03*
X672537Y761428D03*
X694400Y55665D03*
X681980D03*
X682588Y90320D03*
X682440Y118853D03*
X689663Y407382D03*
X684705Y1251443D03*
X698597Y55665D03*
X707597D03*
X711867Y55705D03*
X702790Y55655D03*
X712000Y75145D03*
X700960Y131185D03*
X710433Y415342D03*
X702062Y1257477D03*
X712298Y1608785D03*
X708175Y1608794D03*
X704219Y1637834D03*
X705083Y1663976D03*
X728000Y81345D03*
X719967Y75145D03*
X723957D03*
X715990D03*
X714427Y1250558D03*
X720112Y1607216D03*
X731069Y1233699D03*
X730328Y1257481D03*
X734111Y1257502D03*
X744022Y1248990D03*
X748178Y407902D03*
X772570Y1248995D03*
X762670Y1669472D03*
X791685Y1257377D03*
X808220Y143045D03*
X808843Y428612D03*
X803116Y1247100D03*
X821120Y142445D03*
X819401Y1255977D03*
X820110Y1246595D03*
X841720Y215845D03*
X837500Y226135D03*
X840651Y1239869D03*
X847271Y1256706D03*
X849767Y1249773D03*
X922320Y1666845D03*
X918300Y1666883D03*
X932487Y489166D03*
X928958Y487521D03*
X939970Y523171D03*
X924761Y523022D03*
X928393Y521574D03*
X934020Y994055D03*
X938220Y1666745D03*
X926120Y1666845D03*
X933979Y1666810D03*
X929979Y1666845D03*
X943369Y508061D03*
X946100Y1666783D03*
X942100D03*
X950100D03*
X953900D03*
X964347Y506774D03*
X968355Y506721D03*
X965570Y1562243D03*
X985445Y178566D03*
X988219Y415879D03*
X984254D03*
X1004189Y404181D03*
X1012942Y298053D03*
X1008942D03*
X1017720Y310845D03*
X1013720D03*
X1009334Y404150D03*
X1013105Y404193D03*
X1037000Y296495D03*
X1052504Y1257144D03*
X1082030Y1257335D03*
X1111904Y1257178D03*
X1135339Y1237179D03*
X1135687Y1588221D03*
X1131687D03*
X1149903Y1250317D03*
X1145687Y1588221D03*
X1141687D03*
X1151687D03*
X1153467Y592005D03*
X1166077Y766308D03*
X1165095Y1588221D03*
X1155687D03*
X1161095D03*
X1160310Y1631243D03*
X1177677Y763978D03*
X1172649Y1257345D03*
X1179563Y1250474D03*
X1175095Y1588221D03*
X1171095D03*
X1200497Y768098D03*
X1195097D03*
Y759190D03*
X1199597Y759162D03*
X1199679Y1257632D03*
X1208537Y751288D03*
X1212537D03*
X1209247Y768088D03*
X1212937Y759788D03*
X1208937D03*
X1204497Y768098D03*
X1209315Y1250721D03*
X1223793Y1239869D03*
X1230681Y1249773D03*
X1223793Y1246869D03*
X1230681Y1257661D03*
X1242398Y754300D03*
X1246260Y763448D03*
X1262383Y106643D03*
X1260514Y224365D03*
X1259998Y735500D03*
X1263787Y735498D03*
X1252847Y748478D03*
X1250260Y763448D03*
X1276345Y102613D03*
X1279485Y113508D03*
X1274257Y743548D03*
X1276980Y1307100D03*
X1275856Y1355530D03*
X1272346D03*
X1295807Y115076D03*
X1291704Y106214D03*
X1295947Y735208D03*
X1289817Y744053D03*
X1303220Y110545D03*
X1310150Y132087D03*
X1309228Y125051D03*
X1314269Y125096D03*
X1303728Y130273D03*
X1308847Y752778D03*
X1305277D03*
X1300317Y740378D03*
X1328946Y134263D03*
X1319288Y125085D03*
X1327428Y126260D03*
X1317891Y132086D03*
X1323493Y132213D03*
X1322477Y179159D03*
X1330773Y201006D03*
X1322522Y192953D03*
X1321816Y729152D03*
X1320032Y752778D03*
X1316307D03*
X1330328Y741625D03*
X1332886Y129190D03*
X1336930Y127190D03*
X1334814Y201006D03*
X1335120Y212002D03*
X1338495Y752284D03*
X1334641Y752492D03*
X1445018Y727471D03*
X1458818D03*
X1449118D03*
X1453218D03*
X1459431Y1398878D03*
X1470656Y752284D03*
X1474656D03*
X1468947Y741618D03*
X1463249Y1398878D03*
X1482751Y752285D03*
X1502396Y734310D03*
X1507016Y737449D03*
X1499245Y752748D03*
X1494963Y752645D03*
X1510437Y316808D03*
X1521975Y752748D03*
X1517575D03*
X1534000Y129845D03*
X1527185Y752748D03*
X1561890Y201735D03*
X1562890Y243405D03*
X1573507Y752568D03*
X1577507D03*
X1590915Y768688D03*
X1582017Y896066D03*
Y910728D03*
X1602650Y1257706D03*
Y1250503D03*
X1616114Y1257027D03*
X1631545Y1248026D03*
X1654143Y1253668D03*
X1661120Y617145D03*
X1675414Y1257027D03*
X1690560Y430095D03*
X1699720Y493345D03*
X1694339Y494261D03*
X1702067Y698948D03*
X1705029Y1229293D03*
X1705013Y1256872D03*
X1690518Y1251063D03*
X1712820Y175263D03*
X1705720Y493345D03*
X1711720D03*
X1706017Y698948D03*
X1705896Y709430D03*
X1713606Y713920D03*
X1709013Y1256872D03*
X1705803Y1249920D03*
X1720183Y1252857D03*
X1734714Y1257127D03*
X1749690Y1248369D03*
X1769900Y43192D03*
X1762075D03*
X1770566Y303442D03*
X1764680Y309025D03*
X1764514Y1257027D03*
X1773791Y34337D03*
X1777754Y43352D03*
X1781990Y43238D03*
X1773554Y43192D03*
X1774537Y303527D03*
X1779319Y306663D03*
X1778789Y1250128D03*
X1787706Y53023D03*
X1791706D03*
X1797417Y1240873D03*
Y1247873D03*
X1816360Y1240744D03*
X1816612Y1256568D03*
X1810954Y1255847D03*
G54D50*
X238780Y1681456D03*
X230906Y1677519D03*
Y1682244D03*
X238780Y1686180D03*
Y1695629D03*
X230906Y1691692D03*
Y1696417D03*
X238780Y1700354D03*
Y1709803D03*
Y1714527D03*
X230906Y1705866D03*
Y1710590D03*
X238780Y1723976D03*
Y1728700D03*
X230906Y1720039D03*
Y1724763D03*
X254528Y1681456D03*
X246654Y1677519D03*
Y1682244D03*
X254528Y1686180D03*
Y1695629D03*
X246654Y1691692D03*
Y1696417D03*
X254528Y1700354D03*
Y1709803D03*
Y1714527D03*
X246654Y1705866D03*
Y1710590D03*
X254528Y1723976D03*
Y1728700D03*
X246654Y1720039D03*
Y1724763D03*
X270276Y1653110D03*
Y1657834D03*
Y1681456D03*
X262402Y1677519D03*
Y1682244D03*
X270276Y1686180D03*
Y1695629D03*
X262402Y1691692D03*
Y1696417D03*
X270276Y1700354D03*
Y1709803D03*
Y1714527D03*
X262402Y1705866D03*
Y1710590D03*
X270276Y1723976D03*
Y1728700D03*
X262402Y1720039D03*
Y1724763D03*
X286024Y1653110D03*
Y1657834D03*
Y1667283D03*
Y1672007D03*
Y1681456D03*
X278150Y1677519D03*
Y1682244D03*
X286024Y1686180D03*
Y1695629D03*
X278150Y1691692D03*
Y1696417D03*
X286024Y1700354D03*
Y1709803D03*
Y1714527D03*
X278150Y1705866D03*
Y1710590D03*
X286024Y1723976D03*
Y1728700D03*
X278150Y1720039D03*
Y1724763D03*
X297835Y1677519D03*
Y1682244D03*
X305709Y1681456D03*
Y1686180D03*
X297835Y1691692D03*
Y1696417D03*
X305709Y1695629D03*
Y1700354D03*
X297835Y1705866D03*
Y1710590D03*
X305709Y1709803D03*
Y1714527D03*
X297835Y1720039D03*
Y1724763D03*
X305709Y1723976D03*
Y1728700D03*
X313583Y1677519D03*
Y1682244D03*
X321457Y1681456D03*
Y1686180D03*
X313583Y1691692D03*
Y1696417D03*
X321457Y1695629D03*
Y1700354D03*
X313583Y1705866D03*
Y1710590D03*
X321457Y1709803D03*
Y1714527D03*
X313583Y1720039D03*
Y1724763D03*
X321457Y1723976D03*
Y1728700D03*
X329331Y1677519D03*
Y1682244D03*
X337205Y1681456D03*
Y1686180D03*
X329331Y1691692D03*
Y1696417D03*
X337205Y1695629D03*
Y1700354D03*
X329331Y1705866D03*
Y1710590D03*
X337205Y1709803D03*
Y1714527D03*
X329331Y1720039D03*
Y1724763D03*
X337205Y1723976D03*
Y1728700D03*
X345079Y1677519D03*
Y1682244D03*
X352953Y1681456D03*
Y1686180D03*
X345079Y1691692D03*
Y1696417D03*
X352953Y1695629D03*
Y1700354D03*
X345079Y1705866D03*
Y1710590D03*
X352953Y1709803D03*
Y1714527D03*
X345079Y1720039D03*
Y1724763D03*
X352953Y1723976D03*
Y1728700D03*
X495079Y1677519D03*
Y1682244D03*
Y1691692D03*
Y1696417D03*
Y1705866D03*
Y1710590D03*
Y1720039D03*
Y1724763D03*
X510827Y1677519D03*
X502953Y1681456D03*
X510827Y1682244D03*
X502953Y1686180D03*
X510827Y1691692D03*
X502953Y1695629D03*
X510827Y1696417D03*
X502953Y1700354D03*
X510827Y1705866D03*
X502953Y1709803D03*
X510827Y1710590D03*
X502953Y1714527D03*
X510827Y1720039D03*
X502953Y1723976D03*
X510827Y1724763D03*
X502953Y1728700D03*
X526575Y1677519D03*
X518701Y1681456D03*
X526575Y1682244D03*
X534449Y1681456D03*
X518701Y1686180D03*
X534449D03*
X526575Y1691692D03*
X518701Y1695629D03*
X526575Y1696417D03*
X534449Y1695629D03*
X518701Y1700354D03*
X534449D03*
X526575Y1705866D03*
X518701Y1709803D03*
X526575Y1710590D03*
X534449Y1709803D03*
X518701Y1714527D03*
X534449D03*
X526575Y1720039D03*
X518701Y1723976D03*
X526575Y1724763D03*
X534449Y1723976D03*
X518701Y1728700D03*
X534449D03*
X542323Y1677519D03*
Y1682244D03*
X550197Y1681456D03*
Y1686180D03*
X542323Y1691692D03*
Y1696417D03*
X550197Y1695629D03*
Y1700354D03*
X542323Y1705866D03*
Y1710590D03*
X550197Y1709803D03*
Y1714527D03*
X542323Y1720039D03*
Y1724763D03*
X550197Y1723976D03*
Y1728700D03*
X562008Y1677519D03*
Y1682244D03*
Y1691692D03*
Y1696417D03*
Y1705866D03*
Y1710590D03*
Y1720039D03*
Y1724763D03*
X577756Y1677519D03*
X569882Y1681456D03*
X577756Y1682244D03*
X569882Y1686180D03*
X577756Y1691692D03*
X569882Y1695629D03*
X577756Y1696417D03*
X569882Y1700354D03*
X577756Y1705866D03*
X569882Y1709803D03*
X577756Y1710590D03*
X569882Y1714527D03*
X577756Y1720039D03*
X569882Y1723976D03*
X577756Y1724763D03*
X569882Y1728700D03*
X593504Y1677519D03*
X585630Y1681456D03*
X593504Y1682244D03*
X585630Y1686180D03*
X593504Y1691692D03*
X585630Y1695629D03*
X593504Y1696417D03*
X585630Y1700354D03*
X593504Y1705866D03*
X585630Y1709803D03*
X593504Y1710590D03*
X585630Y1714527D03*
X593504Y1720039D03*
X585630Y1723976D03*
X593504Y1724763D03*
X585630Y1728700D03*
X609252Y1677519D03*
X601378Y1681456D03*
X609252Y1682244D03*
X601378Y1686180D03*
X609252Y1691692D03*
X601378Y1695629D03*
X609252Y1696417D03*
X601378Y1700354D03*
X609252Y1705866D03*
X601378Y1709803D03*
X609252Y1710590D03*
X601378Y1714527D03*
X609252Y1720039D03*
X601378Y1723976D03*
X609252Y1724763D03*
X601378Y1728700D03*
X617126Y1681456D03*
Y1686180D03*
Y1695629D03*
Y1700354D03*
Y1709803D03*
Y1714527D03*
Y1723976D03*
Y1728700D03*
X1238780Y1677519D03*
Y1682244D03*
X1246654Y1681456D03*
Y1686180D03*
X1238780Y1691692D03*
Y1696417D03*
X1246654Y1695629D03*
Y1700354D03*
X1238780Y1705866D03*
Y1710590D03*
X1246654Y1709803D03*
Y1714527D03*
X1238780Y1720039D03*
Y1724763D03*
X1246654Y1723976D03*
Y1728700D03*
X1254528Y1677519D03*
Y1682244D03*
X1262402Y1681456D03*
Y1686180D03*
X1254528Y1691692D03*
Y1696417D03*
X1262402Y1695629D03*
Y1700354D03*
X1254528Y1705866D03*
Y1710590D03*
X1262402Y1709803D03*
Y1714527D03*
X1254528Y1720039D03*
Y1724763D03*
X1262402Y1723976D03*
Y1728700D03*
X1270276Y1677519D03*
Y1682244D03*
X1278150Y1681456D03*
Y1686180D03*
X1270276Y1691692D03*
Y1696417D03*
X1278150Y1695629D03*
Y1700354D03*
X1270276Y1705866D03*
Y1710590D03*
X1278150Y1709803D03*
Y1714527D03*
X1270276Y1720039D03*
Y1724763D03*
X1278150Y1723976D03*
Y1728700D03*
X1286024Y1677519D03*
Y1682244D03*
X1293898Y1681456D03*
Y1686180D03*
X1286024Y1691692D03*
Y1696417D03*
X1293898Y1695629D03*
Y1700354D03*
X1286024Y1705866D03*
Y1710590D03*
X1293898Y1709803D03*
Y1714527D03*
X1286024Y1720039D03*
Y1724763D03*
X1293898Y1723976D03*
Y1728700D03*
X1305709Y1677519D03*
Y1682244D03*
X1313583Y1681456D03*
Y1686180D03*
X1305709Y1691692D03*
Y1696417D03*
X1313583Y1695629D03*
Y1700354D03*
X1305709Y1705866D03*
Y1710590D03*
X1313583Y1709803D03*
Y1714527D03*
X1305709Y1720039D03*
Y1724763D03*
X1313583Y1723976D03*
Y1728700D03*
X1321457Y1677519D03*
Y1682244D03*
X1329331Y1681456D03*
Y1686180D03*
X1321457Y1691692D03*
Y1696417D03*
X1329331Y1695629D03*
Y1700354D03*
X1321457Y1705866D03*
Y1710590D03*
X1329331Y1709803D03*
Y1714527D03*
X1321457Y1720039D03*
Y1724763D03*
X1329331Y1723976D03*
Y1728700D03*
X1337205Y1677519D03*
Y1682244D03*
X1345079Y1681456D03*
Y1686180D03*
X1337205Y1691692D03*
Y1696417D03*
X1345079Y1695629D03*
Y1700354D03*
X1337205Y1705866D03*
Y1710590D03*
X1345079Y1709803D03*
Y1714527D03*
X1337205Y1720039D03*
Y1724763D03*
X1345079Y1723976D03*
Y1728700D03*
X1352953Y1677519D03*
Y1682244D03*
X1360827Y1681456D03*
Y1686180D03*
X1352953Y1691692D03*
Y1696417D03*
X1360827Y1695629D03*
Y1700354D03*
X1352953Y1705866D03*
Y1710590D03*
X1360827Y1709803D03*
Y1714527D03*
X1352953Y1720039D03*
Y1724763D03*
X1360827Y1723976D03*
Y1728700D03*
X1502953Y1677519D03*
Y1682244D03*
X1510827Y1681456D03*
Y1686180D03*
X1502953Y1691692D03*
Y1696417D03*
X1510827Y1695629D03*
Y1700354D03*
X1502953Y1705866D03*
Y1710590D03*
X1510827Y1709803D03*
Y1714527D03*
X1502953Y1720039D03*
Y1724763D03*
X1510827Y1723976D03*
Y1728700D03*
X1518701Y1677519D03*
Y1682244D03*
X1526575Y1681456D03*
Y1686180D03*
X1518701Y1691692D03*
Y1696417D03*
X1526575Y1695629D03*
Y1700354D03*
X1518701Y1705866D03*
Y1710590D03*
X1526575Y1709803D03*
Y1714527D03*
X1518701Y1720039D03*
Y1724763D03*
X1526575Y1723976D03*
Y1728700D03*
X1534449Y1677519D03*
Y1682244D03*
X1542323Y1681456D03*
Y1686180D03*
X1534449Y1691692D03*
Y1696417D03*
X1542323Y1695629D03*
Y1700354D03*
X1534449Y1705866D03*
Y1710590D03*
X1542323Y1709803D03*
Y1714527D03*
X1534449Y1720039D03*
Y1724763D03*
X1542323Y1723976D03*
Y1728700D03*
X1550197Y1677519D03*
Y1682244D03*
X1558071Y1681456D03*
Y1686180D03*
X1550197Y1691692D03*
Y1696417D03*
X1558071Y1695629D03*
Y1700354D03*
X1550197Y1705866D03*
Y1710590D03*
X1558071Y1709803D03*
Y1714527D03*
X1550197Y1720039D03*
Y1724763D03*
X1558071Y1723976D03*
Y1728700D03*
X1569882Y1677519D03*
Y1682244D03*
Y1691692D03*
Y1696417D03*
Y1705866D03*
Y1710590D03*
Y1720039D03*
Y1724763D03*
X1585630Y1677519D03*
X1577756Y1681456D03*
X1585630Y1682244D03*
X1577756Y1686180D03*
X1585630Y1691692D03*
X1577756Y1695629D03*
X1585630Y1696417D03*
X1577756Y1700354D03*
X1585630Y1705866D03*
X1577756Y1709803D03*
X1585630Y1710590D03*
X1577756Y1714527D03*
X1585630Y1720039D03*
X1577756Y1723976D03*
X1585630Y1724763D03*
X1577756Y1728700D03*
X1601378Y1677519D03*
X1593504Y1681456D03*
X1601378Y1682244D03*
X1593504Y1686180D03*
X1601378Y1691692D03*
X1593504Y1695629D03*
X1601378Y1696417D03*
X1593504Y1700354D03*
X1601378Y1705866D03*
X1593504Y1709803D03*
X1601378Y1710590D03*
X1593504Y1714527D03*
X1601378Y1720039D03*
X1593504Y1723976D03*
X1601378Y1724763D03*
X1593504Y1728700D03*
X1617126Y1677519D03*
X1609252Y1681456D03*
X1617126Y1682244D03*
X1609252Y1686180D03*
X1617126Y1691692D03*
X1609252Y1695629D03*
X1617126Y1696417D03*
X1609252Y1700354D03*
X1617126Y1705866D03*
X1609252Y1709803D03*
X1617126Y1710590D03*
X1609252Y1714527D03*
X1617126Y1720039D03*
X1609252Y1723976D03*
X1617126Y1724763D03*
X1609252Y1728700D03*
X1625000Y1681456D03*
Y1686180D03*
Y1695629D03*
Y1700354D03*
Y1709803D03*
Y1714527D03*
Y1723976D03*
Y1728700D03*
G54D14*
X32370Y147842D03*
X46480Y1574922D03*
X928900Y1185132D03*
X1726300Y1710102D03*
X1796240Y126972D03*
G54D126*
G01X159587Y1403924D02*
X156957D01*
X153789Y1400756D01*
Y1397501D01*
G01X152684Y1403451D02*
Y1406659D01*
X151565Y1407778D01*
G01X162257Y1406594D02*
X159587Y1403924D01*
G01X187711Y1397670D02*
X187905Y1397476D01*
X190332D01*
G01D02*
Y1399131D01*
X195876Y1404675D01*
X197460D01*
G01X204610Y571097D02*
X206716D01*
X207687Y570126D01*
Y567638D01*
X206115Y566066D01*
Y565982D01*
G01X197460Y1404675D02*
X198481D01*
X200492Y1406686D01*
G01X303723Y1355853D02*
X305941D01*
X306172Y1355622D01*
X306207D01*
G01X310608Y1361189D02*
X306573Y1357154D01*
Y1356023D01*
X306207Y1355657D01*
Y1355622D01*
G01X316579Y1364585D02*
X314707Y1362713D01*
X312132D01*
X310608Y1361189D01*
G01X334973Y1333353D02*
X335344D01*
X335873Y1332824D01*
X338300D01*
G01X342289Y1338168D02*
X338300Y1334179D01*
Y1332824D01*
G01X338795Y1338799D02*
X337869Y1337873D01*
X337109D01*
X336179Y1336943D01*
G01X348707Y1341787D02*
X346273Y1339353D01*
X343474D01*
X342289Y1338168D01*
G01X367807Y1319592D02*
X367901Y1319498D01*
X372428D01*
G01X375030Y1325211D02*
X372827Y1323008D01*
Y1319897D01*
X372428Y1319498D01*
G01X380835Y1328361D02*
X379077Y1326603D01*
X376422D01*
X375030Y1325211D01*
G01X399935Y1319592D02*
X400206Y1319863D01*
X405156D01*
G01X403051Y1325373D02*
Y1324131D01*
X401923Y1323003D01*
X401448D01*
X400462Y1322017D01*
G01X408339Y1325927D02*
X408048D01*
X405156Y1323035D01*
Y1319863D01*
G01X412963Y1328361D02*
X410529Y1325927D01*
X408339D01*
G01X432063Y1319592D02*
X432351Y1319304D01*
X436701D01*
G01X439104Y1324785D02*
X436701Y1322382D01*
Y1319304D01*
G01X445091Y1328361D02*
X442657Y1325927D01*
X440246D01*
X439104Y1324785D01*
G01X464191Y1319592D02*
X464517Y1319266D01*
X468790D01*
G01X471545Y1325025D02*
X468790Y1322270D01*
Y1319266D01*
G01X477219Y1328361D02*
X475371Y1326513D01*
X473033D01*
X471545Y1325025D01*
G01X496319Y1333043D02*
X496689Y1332673D01*
X501013D01*
G01X503218Y1337798D02*
X501013Y1335593D01*
Y1332673D01*
G01X496319Y1335443D02*
X497373D01*
X499435Y1337505D01*
Y1338799D01*
G01X509347Y1341787D02*
X506913Y1339353D01*
X504773D01*
X503218Y1337798D01*
G01X528447Y1355816D02*
X533229D01*
X533423Y1355622D01*
G01X535339Y1361318D02*
X533423Y1359402D01*
Y1355622D01*
G01X531563Y1361597D02*
Y1360279D01*
X530487Y1359203D01*
X529616D01*
X528929Y1358516D01*
G01X541475Y1364585D02*
X539543Y1362653D01*
X536674D01*
X535339Y1361318D01*
G01X666303Y1403476D02*
X664579Y1401752D01*
X662034D01*
X661942Y1401660D01*
G01X672773Y1404136D02*
X673362Y1404725D01*
X673982D01*
X675876Y1406619D01*
G01X667408Y1397526D02*
Y1400781D01*
X670763Y1404136D01*
X672773D01*
G01X701330Y1397695D02*
X701524Y1397501D01*
X703951D01*
G01X708126Y1403331D02*
X703951Y1399156D01*
Y1397501D01*
G01X714019Y1406619D02*
X712100Y1404700D01*
X709495D01*
X708126Y1403331D01*
G01X1127100Y1433830D02*
Y1437085D01*
X1129999Y1439984D01*
X1131721D01*
G01D02*
X1132766Y1441029D01*
X1133674D01*
X1135568Y1442923D01*
G01X1125995Y1439780D02*
X1124311Y1438096D01*
X1121845D01*
X1121753Y1438004D01*
G01X1161022Y1433999D02*
X1161216Y1433805D01*
X1163643D01*
G01D02*
Y1435460D01*
X1167818Y1439635D01*
X1170670D01*
G01D02*
X1172033D01*
X1173711Y1441313D01*
Y1442923D01*
G01X1282313Y1355622D02*
Y1357257D01*
X1287207Y1362151D01*
X1288000D01*
G01D02*
X1288658D01*
X1289979Y1363472D01*
X1291607D01*
Y1363588D01*
X1292840Y1364821D01*
G01X1320786Y1339353D02*
X1319335D01*
X1314441Y1334459D01*
Y1332824D01*
G01X1314936Y1338799D02*
X1313901Y1337764D01*
X1313141D01*
X1312320Y1336943D01*
G01X1324848Y1341787D02*
X1323735Y1340674D01*
X1322107D01*
X1320786Y1339353D01*
G01X1343948Y1319592D02*
X1344042Y1319498D01*
X1348569D01*
G01X1347397Y1325320D02*
Y1324836D01*
X1345985Y1323424D01*
X1345600D01*
X1344532Y1322356D01*
G01X1351554Y1325594D02*
X1348569Y1322609D01*
Y1319498D01*
G01X1356976Y1328361D02*
X1354542Y1325927D01*
X1351887D01*
X1351554Y1325594D01*
G01X1376076Y1319592D02*
X1376347Y1319863D01*
X1381297D01*
G01X1379192Y1325373D02*
Y1327330D01*
X1380153Y1328291D01*
Y1330133D01*
G01X1381297Y1319863D02*
Y1322175D01*
X1384638Y1325516D01*
G01D02*
X1386116Y1326994D01*
X1387737D01*
X1389104Y1328361D01*
G01X1408204Y1319592D02*
X1408492Y1319304D01*
X1412842D01*
G01X1411320Y1325373D02*
Y1329103D01*
X1412316Y1330099D01*
Y1330159D01*
G01X1412842Y1319304D02*
X1413697Y1320159D01*
Y1323237D01*
X1416387Y1325927D01*
X1418030D01*
G01D02*
X1418798D01*
X1421232Y1328361D01*
G01X1440332Y1319592D02*
X1440658Y1319266D01*
X1444931D01*
G01D02*
Y1321740D01*
X1448586Y1325395D01*
G01D02*
X1450095Y1326904D01*
X1451903D01*
X1453360Y1328361D01*
G01X1472460Y1333043D02*
X1472830Y1332673D01*
X1477154D01*
G01X1480320Y1338759D02*
X1477154Y1335593D01*
Y1332673D01*
G01X1475576Y1338799D02*
Y1337515D01*
X1473504Y1335443D01*
X1472460D01*
G01X1485488Y1341787D02*
X1483935Y1340234D01*
X1481795D01*
X1480320Y1338759D01*
G01X1504588Y1355816D02*
X1509370D01*
X1509564Y1355622D01*
G01X1511357Y1361195D02*
X1509564Y1359402D01*
Y1355622D01*
G01X1507704Y1361597D02*
Y1359882D01*
X1506338Y1358516D01*
X1505070D01*
G01X1517616Y1364585D02*
X1515795Y1362764D01*
X1512926D01*
X1511357Y1361195D01*
G01X1627469Y1437072D02*
X1627204Y1436807D01*
X1624237D01*
X1624103Y1436941D01*
X1622077D01*
G01X1636200Y1436862D02*
Y1439373D01*
X1637042Y1440215D01*
G01X1628600Y1431202D02*
Y1434403D01*
X1631059Y1436862D01*
X1636200D01*
G01X1652351Y639573D02*
X1649917Y642007D01*
Y644418D01*
X1648722Y645613D01*
G01X1643582Y652601D02*
X1643294Y652313D01*
Y647963D01*
G01X1648722Y645613D02*
X1647227Y647108D01*
X1644149D01*
X1643294Y647963D01*
G01X1649363Y649485D02*
X1647257D01*
X1646315Y650427D01*
Y653649D01*
X1646223Y653741D01*
G01X1652351Y673573D02*
X1649917Y676007D01*
Y678418D01*
X1648722Y679613D01*
G01X1643582Y686601D02*
X1643294Y686313D01*
Y681963D01*
G01X1648722Y679613D02*
X1647227Y681108D01*
X1644149D01*
X1643294Y681963D01*
G01X1649363Y683485D02*
X1647257D01*
X1646315Y684427D01*
Y687650D01*
X1646223Y687742D01*
G01X1643582Y720601D02*
X1643294Y720313D01*
Y715963D01*
G01D02*
X1644149Y715108D01*
X1647227D01*
X1649455Y712880D01*
Y711844D01*
G01D02*
Y710469D01*
X1652351Y707573D01*
G01X1649363Y717485D02*
X1647257D01*
X1646341Y718401D01*
Y721761D01*
G01X1662496Y1431291D02*
X1662690Y1431097D01*
X1665117D01*
G01D02*
Y1432752D01*
X1670661Y1438296D01*
X1671870D01*
G01D02*
X1673266D01*
X1675185Y1440215D01*
G54D117*
G01X27300Y764200D02*
Y766600D01*
X28300Y767600D01*
X37100D01*
X38857Y769357D01*
X40839D01*
G01X27699Y1258727D02*
X29845D01*
X30524Y1258048D01*
Y1256964D01*
G01X67681Y360702D02*
Y372261D01*
X66120Y373822D01*
X48720D01*
X43020Y379522D01*
Y382942D01*
G01X43143Y722374D02*
X43974D01*
X45700Y724100D01*
G01X43143Y726874D02*
X45800D01*
G01X40839Y769357D02*
Y767739D01*
X37721Y764621D01*
Y763090D01*
G01X68315Y763164D02*
X66999D01*
X65628Y764535D01*
X60808D01*
X59363Y763090D01*
X54847D01*
G01X57399Y1258727D02*
X59575D01*
X60224Y1258078D01*
Y1256964D01*
G01X80971Y696156D02*
X77121D01*
G01X78080Y701832D02*
X74810D01*
X73281Y700303D01*
Y696186D01*
G01X68315Y765664D02*
Y763164D01*
G01X66189Y1257488D02*
X67702Y1255975D01*
Y1254593D01*
G01X63374Y1256964D02*
X65665D01*
X66189Y1257488D01*
G01X84470Y668702D02*
X84580D01*
X84650Y668772D01*
X85729D01*
X86549Y667952D01*
X86965D01*
G01X85095Y722164D02*
Y724832D01*
X85903Y725640D01*
G01X91610Y721414D02*
X89073Y723951D01*
Y724436D01*
X89053Y724456D01*
Y725640D01*
G01X93074Y1256964D02*
X95551D01*
X95849Y1257262D01*
G01X87099Y1258727D02*
X88161D01*
X89924Y1256964D01*
G01X94700Y1542847D02*
X95230Y1543377D01*
Y1544847D01*
X96570Y1546187D01*
G01X104875Y490980D02*
Y493474D01*
G01Y505374D02*
Y509374D01*
G01X102384Y505374D02*
X104875D01*
G01Y513374D02*
X102152D01*
G01X111087Y520052D02*
X112497Y518642D01*
Y516839D01*
G01X102120Y688650D02*
X101514D01*
X99516Y690648D01*
G01X95849Y1257262D02*
X97137Y1255974D01*
Y1254464D01*
G01X101680Y1530482D02*
X102130Y1530932D01*
G01X126092Y638568D02*
Y636130D01*
X129437Y632785D01*
X131721D01*
X133467Y634531D01*
G01X125183Y667700D02*
X126988Y669505D01*
Y670794D01*
X128794Y672600D01*
X131190D01*
X132640Y671150D01*
Y667050D01*
X131330Y665740D01*
G01X125412Y1257102D02*
X126603Y1255911D01*
Y1254528D01*
G01X122774Y1256964D02*
X125274D01*
X125412Y1257102D01*
G01X116799Y1258727D02*
X118875D01*
X119624Y1257978D01*
Y1256964D01*
G01X149557Y494353D02*
X147835D01*
X147122Y493640D01*
G01Y505550D02*
X148382Y506810D01*
X149472D01*
G01X150800Y512021D02*
X153117D01*
X154043Y511095D01*
G01X147073Y522771D02*
X149518Y522810D01*
G01X147072Y514980D02*
X147242Y514810D01*
X149512D01*
G01X148029Y757969D02*
X150877D01*
G01X154965Y1256964D02*
X155135Y1257134D01*
G01X152474Y1256964D02*
X154965D01*
G01X146499Y1258727D02*
X147561D01*
X149324Y1256964D01*
G01X150974Y1252964D02*
X150927Y1252917D01*
Y1246719D01*
G01X150974Y1252964D02*
Y1253989D01*
X149324Y1255639D01*
Y1256964D01*
G01X148415Y1407778D02*
X147307Y1406670D01*
Y1404745D01*
G01X191945Y681062D02*
X190420D01*
X188000Y678642D01*
Y673982D01*
X189710Y672272D01*
X193110D01*
G01X183602Y759290D02*
X185835Y757057D01*
G01X188978Y756855D02*
Y757914D01*
X187602Y759290D01*
G01X191602D02*
Y756839D01*
G01X184923Y1258871D02*
X186179Y1257615D01*
Y1255943D01*
G01X182174Y1256964D02*
X183016D01*
X184923Y1258871D01*
G01X176199Y1258727D02*
X178225D01*
X179024Y1257928D01*
Y1256964D01*
G01X207620Y671262D02*
Y671687D01*
X205520Y673787D01*
X205320D01*
G01Y676937D02*
X205229Y676846D01*
X204264D01*
X201360Y673942D01*
Y672817D01*
G01X198420Y672662D02*
X198906Y673148D01*
X201029D01*
X201360Y672817D01*
G01X193110Y672272D02*
X193815D01*
X196600Y669487D01*
X198495D01*
G01D02*
X200020D01*
X200200Y669667D01*
X201360D01*
G01X209220Y676937D02*
X205320D01*
G01X197086Y686326D02*
X197769D01*
X199541Y684554D01*
G01D02*
Y683359D01*
X197244Y681062D01*
X195095D01*
G01X207602Y759290D02*
Y756855D01*
G01X199602Y759290D02*
Y756855D01*
G01X195602Y759290D02*
Y756839D01*
G01X203602Y759290D02*
Y756855D01*
G01X205899Y1258727D02*
X207675D01*
X208724Y1257678D01*
Y1256964D01*
G01X210320Y671262D02*
Y672487D01*
X209220Y673587D01*
Y673787D01*
G01X220033Y756844D02*
X219272Y757605D01*
Y759810D01*
G01X211602Y759290D02*
Y756855D01*
G01X214824Y1258711D02*
X216063Y1257472D01*
Y1255944D01*
G01X211874Y1256964D02*
X213077D01*
X214824Y1258711D01*
G01X235599Y1258727D02*
X236870Y1257456D01*
X238292D01*
G01X253057Y755345D02*
X250457Y757945D01*
Y758010D01*
G01X254477Y758120D02*
Y756765D01*
X253057Y755345D01*
G01X241442Y1257456D02*
X244079Y1260093D01*
X244789D01*
G01X251187Y1255025D02*
X253561D01*
X254292Y1255756D01*
G01X268597Y1264509D02*
Y1261045D01*
X265657Y1258105D01*
X255792D01*
X254292Y1256605D01*
Y1255756D01*
G01X273046Y733039D02*
Y735662D01*
G01X270100Y727262D02*
X271737Y725625D01*
Y725025D01*
X273046Y723716D01*
Y723244D01*
G01X264000Y726262D02*
Y724287D01*
X265043Y723244D01*
G01X266700Y730962D02*
X267000D01*
X268073Y729889D01*
X269046D01*
G01X273000Y743579D02*
X271570Y745009D01*
Y746422D01*
G01D02*
Y747913D01*
X273246Y749589D01*
G01X284287Y716015D02*
X282120Y718182D01*
Y719887D01*
G01Y719992D02*
Y719887D01*
G01D02*
X282327Y720094D01*
X286046D01*
G01X279507Y727025D02*
Y728350D01*
X281046Y729889D01*
G01X287607Y754962D02*
Y753478D01*
X288646Y752439D01*
G01X295520Y15162D02*
Y12762D01*
G01X290720Y42787D02*
Y40017D01*
G01X294720Y42787D02*
Y40017D01*
G01X291600Y705162D02*
X292267Y704495D01*
X294687D01*
G01X298273Y715400D02*
X298662D01*
X300452Y713610D01*
X301038D01*
G01X304602Y730419D02*
Y727968D01*
G01X300839Y1307981D02*
X303647D01*
G01X316656Y733363D02*
Y735006D01*
X317875Y736225D01*
X319557D01*
G01X320656Y733363D02*
X316656D01*
G01X319557Y736225D02*
X319517Y736265D01*
Y739209D01*
X317967Y740759D01*
G01X338161Y715215D02*
X335677D01*
G01X335467Y725335D02*
X335030Y725772D01*
X333771D01*
X333180Y726363D01*
X332656D01*
G01X335126Y730723D02*
Y728323D01*
G01X327096Y738723D02*
Y736005D01*
G01X336446Y749233D02*
Y746486D01*
G01X354572Y705965D02*
X360470D01*
G01X348037Y726050D02*
Y728735D01*
G01X355946Y726050D02*
Y728800D01*
G01X359790Y729835D02*
X372113D01*
X386902Y744624D01*
Y749233D01*
G01X358902Y739755D02*
X366727D01*
X370902Y743930D01*
Y749233D01*
G01X358902D02*
X362902D01*
G01X358902Y746405D02*
Y749233D01*
G01X393334Y1404085D02*
X390934D01*
G01X392517Y1419015D02*
Y1417308D01*
X393334Y1416491D01*
G01X400991Y1417264D02*
X402219Y1418492D01*
X403329D01*
G01X393334Y1407605D02*
X390934D01*
G01X390180Y1668212D02*
X387810Y1665842D01*
Y1663607D01*
G01X432628Y1327845D02*
Y1326042D01*
X431728Y1325142D01*
G01X435344Y1420659D02*
X437879D01*
G01X434974Y1420289D02*
X435344Y1420659D01*
G01X458441Y1414893D02*
X458237Y1414689D01*
X452575D01*
X450294Y1416970D01*
Y1417394D01*
G01X456619Y1431189D02*
X454468D01*
X452720Y1429441D01*
Y1427528D01*
X449545Y1424353D01*
Y1424269D01*
G01X451080Y1433740D02*
X449545Y1432205D01*
Y1427968D01*
G01X448181Y1614401D02*
X445175Y1617407D01*
Y1618782D01*
X444600Y1619357D01*
G01X549336Y1067332D02*
X597500D01*
X602110Y1071942D01*
X609190D01*
X612870Y1075622D01*
Y1311722D01*
X619630Y1318482D01*
X633650D01*
X638190Y1323022D01*
Y1390282D01*
X643200Y1395292D01*
Y1495452D01*
X636120Y1502532D01*
X479370D01*
X471850Y1495012D01*
Y1448892D01*
X466310Y1443352D01*
Y1427602D01*
X470570Y1423342D01*
X472510D01*
X474246Y1421606D01*
Y1418684D01*
G01X459550Y1401348D02*
X457021D01*
X456955Y1401282D01*
G01X477882Y1398402D02*
Y1395926D01*
X479361Y1394447D01*
G01X474983Y1400385D02*
Y1401145D01*
X476202Y1402364D01*
X477848D01*
G01X503150Y71397D02*
X500685D01*
X499580Y72502D01*
Y78442D01*
G01D02*
X499510Y78512D01*
Y81047D01*
G01X498730Y125697D02*
Y128592D01*
G01X507310Y71417D02*
X503170D01*
X503150Y71397D01*
G01X503270Y125707D02*
Y128592D01*
G01X507320Y125757D02*
Y128592D01*
G01X542530Y117157D02*
X546370D01*
G01X539475Y118772D02*
X541090Y117157D01*
X542530D01*
G01X548464Y456534D02*
X554502Y450496D01*
Y397544D01*
X546758Y389800D01*
Y360502D01*
G01X568500Y35287D02*
Y32862D01*
G01X592307Y94262D02*
Y91524D01*
X592220Y91437D01*
G01X597287Y94262D02*
Y91504D01*
X597220Y91437D01*
G01X598693Y742072D02*
X597576Y740955D01*
X596297D01*
G01X595597Y747855D02*
X599747D01*
X599763Y747871D01*
G01X616645Y447862D02*
X614220D01*
G01X620870Y762072D02*
Y759660D01*
X614750Y753540D01*
G01X600460Y744912D02*
X599763Y745609D01*
Y747871D01*
G01X613047Y741492D02*
Y742608D01*
X611760Y743895D01*
G01X608250Y749890D02*
Y745862D01*
X610217Y743895D01*
X611760D01*
G01X620899Y770144D02*
X616331Y774712D01*
X613213D01*
G01X616675Y34652D02*
Y31777D01*
G01X629000Y67362D02*
X632925Y63437D01*
X635000D01*
G01X628590Y58622D02*
Y59547D01*
X626865Y61272D01*
G01X631130Y58857D02*
X630895Y58622D01*
X628590D01*
G01X631645Y431062D02*
X628912D01*
X628900Y431050D01*
G01X629931Y1258727D02*
X629695Y1258491D01*
X627835D01*
X626680Y1257336D01*
X626367D01*
G01X639000Y63437D02*
X635000D01*
G01X643170Y171362D02*
X642710Y170902D01*
X637140D01*
X633603Y167365D01*
Y166271D01*
G01X644000Y438862D02*
X646645D01*
G01Y462862D02*
X644220D01*
G01X634213Y1258679D02*
X633673Y1258139D01*
Y1256323D01*
G01X649047Y33535D02*
X651943D01*
G01X659299Y970932D02*
X657804D01*
X656304Y972432D01*
Y973428D01*
G01X652577Y1000775D02*
Y992465D01*
X653488Y991554D01*
Y989241D01*
G01X659546Y1257664D02*
X658846Y1256964D01*
X656574D01*
G01X650599Y1258727D02*
X651661D01*
X653424Y1256964D01*
G01X661942Y1404810D02*
X663687Y1406555D01*
Y1407279D01*
G01X677820Y89462D02*
X678340D01*
X679290Y90412D01*
X682588D01*
G01X674628Y430612D02*
X673054Y432186D01*
Y432187D01*
G01X676203Y447935D02*
X674628Y449510D01*
G01Y462108D02*
X673054Y460534D01*
Y460533D01*
G01X669778Y759929D02*
X668714Y758865D01*
X667902D01*
X667347Y758310D01*
G01X672537Y758370D02*
X671337D01*
X669778Y759929D01*
G01X676046Y1257964D02*
X674046Y1255964D01*
X673992D01*
X673960Y1255932D01*
G01X690220Y55757D02*
X685968D01*
G01D02*
Y58157D01*
G01X684077Y418013D02*
X685651Y416439D01*
X685652D01*
G01X684077Y474707D02*
X685651Y476281D01*
X685652D01*
G01X697336Y757086D02*
X693310D01*
G01D02*
X692776D01*
X690807Y759055D01*
Y766265D01*
X691627Y767085D01*
Y779977D01*
G01X688967Y787417D02*
X691627Y784757D01*
Y779977D01*
G01X686274Y1256964D02*
X688916D01*
G01X680299Y1258727D02*
X681361D01*
X683124Y1256964D01*
G01X706370Y46782D02*
Y48012D01*
X702790Y51592D01*
Y52597D01*
G01X712290Y106722D02*
X713060D01*
X714690Y105092D01*
Y100702D01*
X712100Y98112D01*
Y85687D01*
G01X723400Y85637D02*
X721375Y87662D01*
X716900D01*
X714925Y85687D01*
X712100D01*
G01X708300Y418750D02*
X706862D01*
X706125Y418013D01*
G01X704550Y466832D02*
X706125Y468407D01*
G01X714087Y745865D02*
Y751775D01*
X710688Y755174D01*
Y757086D01*
G01X704000Y740862D02*
X708037Y744899D01*
Y749325D01*
X705388Y751974D01*
Y757086D01*
G01X714688D02*
X710688D01*
G01X705388D02*
X701362D01*
G01D02*
X697336D01*
G01X709999Y1258727D02*
X711061D01*
X712824Y1256964D01*
G01X708219Y1634776D02*
X709246D01*
X710540Y1636070D01*
G01X714071Y1663842D02*
X711671D01*
G01X725022Y418013D02*
X723448Y416439D01*
X723447D01*
G01X726597Y444785D02*
X728172Y443210D01*
G01X729747Y432187D02*
X728172Y430612D01*
G01X729747Y460533D02*
X728172Y462108D01*
G01X725022Y474707D02*
X723448Y476281D01*
X723447D01*
G01X717220Y516852D02*
X715997D01*
X713942Y514797D01*
Y507120D01*
X717220Y503842D01*
G01X718688Y757086D02*
X714688D01*
G01X737609Y744282D02*
X735487Y746404D01*
Y750455D01*
X728909Y757033D01*
Y760629D01*
G01X715974Y1256964D02*
X716074Y1257064D01*
X719046D01*
G01D02*
X718944Y1256962D01*
Y1253356D01*
G01X745220Y514437D02*
Y516852D01*
G01X744538Y746524D02*
X745009Y746995D01*
Y760689D01*
G01X742676Y1257681D02*
X742768Y1257589D01*
Y1252553D01*
X741124Y1250909D01*
X738712D01*
X736096Y1248293D01*
X734537D01*
X732360Y1246116D01*
Y1243588D01*
X733985Y1241963D01*
X734521D01*
G01X742676Y1257681D02*
X742633Y1257638D01*
X741850D01*
X740761Y1258727D01*
X739699D01*
G01D02*
X734634D01*
X734328Y1258421D01*
Y1257811D01*
X734111Y1257594D01*
G01X730190Y1566340D02*
X729827Y1566703D01*
G01D02*
Y1569493D01*
G01X760614Y286632D02*
X760805Y286823D01*
X769895D01*
G01X758720Y283262D02*
Y283862D01*
X760614Y285756D01*
Y286632D01*
G01X764977Y311585D02*
X759637D01*
G01X756642Y496522D02*
X757778Y497658D01*
X759782D01*
G01D02*
X759770Y497670D01*
Y501662D01*
G01X751220Y514437D02*
Y516852D01*
G01X745826Y1257681D02*
X746543Y1256964D01*
X748283D01*
G01X758165Y1620182D02*
X750504Y1612521D01*
G01X767723Y1629740D02*
X758165Y1620182D01*
G01X763795Y413212D02*
Y408212D01*
G01X766195Y413212D02*
X763795D01*
G01Y423212D02*
X766195D01*
G01X765335Y469552D02*
X765025Y469862D01*
X762915D01*
G01X774765Y488862D02*
X774733Y488830D01*
Y484802D01*
G01X772365Y488862D02*
X774765D01*
G01X769337Y760775D02*
X768557Y761555D01*
X765982D01*
G01X771724Y763455D02*
X767882D01*
X765982Y761555D01*
G01X775374Y1256964D02*
X777246D01*
X777546Y1257264D01*
X778346D01*
G01X769399Y1258727D02*
X770461D01*
X772224Y1256964D01*
G01X767723Y1651718D02*
Y1629740D01*
G01X770544Y1654539D02*
X767723Y1651718D01*
G01X768714Y1669516D02*
X773621D01*
X774506Y1668631D01*
Y1658501D01*
X770544Y1654539D01*
G01X792680Y120947D02*
X793570Y121837D01*
Y131962D01*
X790120Y135412D01*
G01D02*
Y138062D01*
X791320Y139262D01*
X798945D01*
G01X782553Y150031D02*
X788322Y144262D01*
X798945D01*
G01X789102Y759655D02*
X791140Y761693D01*
G01D02*
X789807Y763026D01*
Y763150D01*
X789102Y763855D01*
G01X778346Y1257264D02*
X778293Y1257211D01*
Y1253277D01*
G01X798945Y144262D02*
X798920Y144287D01*
Y146962D01*
X800710Y148752D01*
X819260D01*
X820900Y147112D01*
G01X804244Y312773D02*
X805393Y313922D01*
X808559D01*
X810616Y311865D01*
X812499D01*
G01X806450Y310362D02*
X804244Y312568D01*
Y312773D01*
G01X810850Y761315D02*
X807852D01*
X805252Y763915D01*
G01Y759665D02*
Y763915D01*
G01X807000Y757562D02*
X806455D01*
X805252Y758765D01*
Y759665D01*
G01X805074Y1256964D02*
X805774Y1257664D01*
X808046D01*
G01D02*
Y1255736D01*
X807758Y1255448D01*
Y1253512D01*
G01X799099Y1258727D02*
X800161D01*
X801924Y1256964D01*
G01X820900Y147112D02*
X821120Y146892D01*
Y142537D01*
G01X878192Y879910D02*
X867352D01*
X856987Y890275D01*
Y1006175D01*
X854317Y1008845D01*
X815789D01*
G01X837500Y226227D02*
Y229642D01*
G01X827539Y764316D02*
Y760312D01*
X827442Y760215D01*
G01X829420Y758422D02*
X829400Y758402D01*
X829255D01*
X827442Y760215D01*
G01X833120Y761535D02*
X830496D01*
X827715Y764316D01*
X827539D01*
G01X841997Y773085D02*
X843472Y771610D01*
Y770025D01*
G01X837846Y1256964D02*
X839295Y1255515D01*
Y1255057D01*
X839746Y1254606D01*
Y1252463D01*
X839675Y1252392D01*
X839295D01*
G01X834774Y1256964D02*
X837846D01*
G01X831624D02*
Y1255298D01*
X833207Y1253715D01*
Y1249409D01*
G01X828799Y1258727D02*
X829861D01*
X831624Y1256964D01*
G01X867528Y231788D02*
Y226970D01*
X855933Y215375D01*
G01X850133Y271049D02*
X845722D01*
X845500Y271271D01*
G01X849454Y769165D02*
X844332D01*
X843472Y770025D01*
G01X854620Y1242125D02*
X853397D01*
X851173Y1239901D01*
X849767D01*
G01X889453Y458926D02*
X893364Y462837D01*
X898087D01*
G01X892406Y506875D02*
X890192D01*
X881595Y498278D01*
Y482153D01*
X892105Y471643D01*
Y469521D01*
X889051Y466467D01*
Y459328D01*
X889453Y458926D01*
G01X918264Y506011D02*
X916111Y508164D01*
Y508952D01*
G01X911720Y511662D02*
X915671D01*
X916111Y512102D01*
G01X914838Y985989D02*
X914818Y985969D01*
Y985684D01*
X917895Y982607D01*
X919350D01*
G01X924920Y196199D02*
X925620D01*
X927033Y197612D01*
X928350D01*
G01X939872Y495813D02*
X937964Y493905D01*
Y493701D01*
G01X932089Y492691D02*
Y489656D01*
X932487Y489258D01*
G01X932089Y505986D02*
X932098Y505977D01*
X934793D01*
G01X932289Y502986D02*
X933350Y501925D01*
X934788D01*
G01X953900Y1666875D02*
X956600D01*
G01X963856Y394202D02*
X963880Y394178D01*
X966281D01*
G01D02*
Y390302D01*
G01X963856Y398302D02*
X961110Y395556D01*
Y390838D01*
X965759Y386189D01*
X966214D01*
G01X966281Y398138D02*
X966225Y398194D01*
Y402017D01*
G01X966281Y398138D02*
X964020D01*
X963856Y398302D01*
G01X964347Y506866D02*
Y509462D01*
G01X968355Y506813D02*
X968302Y506866D01*
X964347D01*
G01X988908Y373392D02*
X997221D01*
X1000425Y376596D01*
Y380862D01*
G01X983760Y424292D02*
X985560D01*
X987304Y422548D01*
Y421961D01*
G01X980092Y415971D02*
Y421289D01*
G01X984254Y415971D02*
Y418379D01*
G01X1006232Y343983D02*
X1004078Y341829D01*
X1002634D01*
G01X991506Y400607D02*
X990600Y399701D01*
Y396117D01*
G01X994322Y404090D02*
X993110D01*
X991506Y402486D01*
Y400607D01*
G01X991770Y418835D02*
X992345Y418260D01*
Y415971D01*
G01X993387Y429827D02*
Y429046D01*
X994956Y427477D01*
G01X1004821Y422682D02*
X1007249D01*
G01X1009009Y419948D02*
X1008223Y419162D01*
X1004821D01*
G01X1003831Y1259077D02*
X1005393D01*
X1006660Y1257810D01*
G01X1021419Y305704D02*
X1019939Y304224D01*
Y303118D01*
X1020069Y302988D01*
G01X1017720Y310937D02*
X1020720D01*
G01X1013720D02*
X1017720D01*
G01X1018838Y420548D02*
X1021259D01*
G01X1018838Y416974D02*
X1021239D01*
G01X1033541Y1258727D02*
X1034583D01*
X1036366Y1256944D01*
G01X1042331Y1257488D02*
X1043332Y1256487D01*
Y1254713D01*
G01X1039516Y1256944D02*
X1040060Y1257488D01*
X1042331D01*
G01X1055205Y744853D02*
X1055535D01*
X1065749Y755067D01*
Y760249D01*
G01X1063241Y1258727D02*
X1064283D01*
X1066066Y1256944D01*
G01X1084637Y744635D02*
Y748435D01*
X1083296Y749776D01*
Y760904D01*
G01X1087196D02*
X1083296D01*
G01X1093497Y744655D02*
X1091096Y747056D01*
Y760904D01*
G01D02*
X1094996D01*
G01X1092941Y1258727D02*
X1093983D01*
X1095766Y1256944D01*
G01X1113207Y744455D02*
Y749415D01*
X1110680Y751942D01*
Y761066D01*
G01D02*
X1110518Y760904D01*
X1106696D01*
G01X1122980Y741312D02*
Y753257D01*
X1127869Y758146D01*
Y760989D01*
G01X1127972Y747250D02*
X1135917Y755195D01*
Y782479D01*
X1141900Y788462D01*
Y980862D01*
X1144900Y983862D01*
Y989262D01*
X1150900Y995262D01*
Y1004862D01*
X1158900Y1012862D01*
X1167925D01*
X1171425Y1016362D01*
G01X1125466Y1256944D02*
X1123683Y1258727D01*
X1122641D01*
G01X1127069Y1246719D02*
Y1253273D01*
X1125466Y1254876D01*
Y1256944D01*
G01X1122641Y1258727D02*
X1121363Y1257449D01*
X1119982D01*
G01X1121753Y1441154D02*
X1123379Y1442780D01*
Y1443583D01*
G01X1142127Y586452D02*
X1142467Y586112D01*
X1147967D01*
X1149467Y587612D01*
Y588947D01*
G01X1155962Y746193D02*
Y753135D01*
X1166077Y763250D01*
G01X1152341Y1258727D02*
X1153383D01*
X1155166Y1256944D01*
G01X1177677Y760920D02*
Y758269D01*
X1173020Y753612D01*
Y745972D01*
G01X1181850Y1260192D02*
Y1259812D01*
X1184718Y1256944D01*
X1184866D01*
G01X1186058Y589827D02*
X1189373D01*
X1190486Y588714D01*
X1193198D01*
G01Y586172D02*
Y588714D01*
G01X1206757Y744455D02*
X1205247D01*
X1198497Y751205D01*
Y754096D01*
X1199597Y755196D01*
Y756104D01*
G01D02*
X1199569Y756132D01*
X1195097D01*
G01X1208537Y748230D02*
X1212537D01*
G01X1211277Y744265D02*
X1212537Y745525D01*
Y748230D01*
G01X1223793Y1246961D02*
X1223087Y1246255D01*
X1219303D01*
X1216149Y1249409D01*
G01X1208830Y1256692D02*
X1209532Y1255990D01*
Y1253180D01*
X1209315Y1252963D01*
Y1250813D01*
G01D02*
X1210919D01*
X1211533Y1251427D01*
X1214131D01*
X1216149Y1249409D01*
G01X1224614Y116962D02*
X1227518D01*
G01X1219534Y116492D02*
X1219110Y116916D01*
Y121002D01*
G01X1223100Y127300D02*
X1221431D01*
X1221073Y126942D01*
X1220308D01*
G01X1240728Y136198D02*
X1234492Y129962D01*
X1231668D01*
G01X1222890Y157002D02*
Y157892D01*
X1224310Y159312D01*
X1228038D01*
X1229048Y158302D01*
Y156672D01*
G01X1226093Y168162D02*
Y172962D01*
G01D02*
X1225864D01*
X1222724Y176102D01*
G01X1228320Y758598D02*
X1228860Y759138D01*
Y761190D01*
G01X1236220Y189362D02*
X1239145Y192287D01*
Y193362D01*
G01X1245486Y203000D02*
X1243948Y201462D01*
X1242168D01*
G01X1239045Y221562D02*
Y224062D01*
G01X1249122Y752832D02*
X1252195D01*
X1252578Y752449D01*
G01X1242260Y757602D02*
X1242398Y757464D01*
Y754392D01*
G01X1242260Y760390D02*
Y757602D01*
G01X1250010Y120107D02*
Y117121D01*
G01X1264663Y158946D02*
X1263724Y158007D01*
Y155087D01*
X1264119Y154692D01*
G01X1254994Y157382D02*
Y158716D01*
X1256465Y160187D01*
G01X1260544Y227947D02*
X1263229D01*
X1264584Y226592D01*
G01D02*
X1262449Y224457D01*
X1260514D01*
G01X1252847Y748570D02*
Y752180D01*
X1252578Y752449D01*
G01X1255520Y747362D02*
X1254291Y748591D01*
X1252868D01*
X1252847Y748570D01*
G01X1263926Y742390D02*
X1263937D01*
G01X1266722Y101005D02*
X1266723Y101006D01*
Y103585D01*
G01X1270018Y229462D02*
X1267593D01*
G01X1282293Y248962D02*
X1284120Y247135D01*
Y244717D01*
G01X1279493Y248662D02*
Y246487D01*
X1280291Y245689D01*
G01X1275576Y730879D02*
X1276644Y731947D01*
Y732797D01*
X1277257Y733410D01*
G01X1273257Y733490D02*
X1274217Y732530D01*
Y732238D01*
X1275576Y730879D01*
G01X1276980Y1304042D02*
X1279788D01*
G01X1275856Y1355622D02*
Y1358098D01*
G01X1271990Y1358079D02*
X1272346Y1357723D01*
Y1355622D01*
G01X1280192Y1362891D02*
X1276891D01*
G01X1291704Y109427D02*
Y106306D01*
G01Y112019D02*
Y109427D01*
G01X1282824Y108872D02*
Y111319D01*
X1283485Y111980D01*
G01X1290005Y290268D02*
X1286089D01*
X1285189Y289368D01*
G01X1295947Y725150D02*
X1294017D01*
X1292007Y727160D01*
G01X1289936Y732539D02*
X1289737Y732340D01*
Y728740D01*
X1291317Y727160D01*
X1292007D01*
G01X1294937Y749390D02*
Y746965D01*
G01X1290520Y746562D02*
Y744848D01*
X1289817Y744145D01*
G01X1329891Y99455D02*
X1330149Y99713D01*
X1332031D01*
X1333332Y98412D01*
Y93511D01*
X1322456Y82635D01*
X1318069D01*
X1313976Y78542D01*
X1310857D01*
G01X1302964Y124633D02*
X1303728Y125397D01*
Y127215D01*
G01X1300990Y121812D02*
Y122812D01*
X1299890Y123912D01*
Y127167D01*
G01X1313033Y174099D02*
X1312547Y174585D01*
Y177016D01*
G01X1305187Y735630D02*
X1303497Y737320D01*
X1300317D01*
G01X1317567Y742230D02*
X1313607D01*
X1313597Y742220D01*
G01X1315020Y739862D02*
X1313597Y741285D01*
Y742220D01*
G01X1315352Y195474D02*
X1315331Y195453D01*
X1315480Y195304D01*
G01D02*
Y193257D01*
X1315735Y193002D01*
G01X1328530Y747702D02*
X1329156D01*
X1330888Y749434D01*
G01X1330328Y741717D02*
X1330318Y741707D01*
X1326358D01*
G01X1325210Y744322D02*
X1326358Y743174D01*
Y741707D01*
G01X1349017Y124718D02*
X1345166D01*
G01X1344631Y127244D02*
X1345166Y126709D01*
Y124718D01*
G01X1349220Y140362D02*
X1346604Y142978D01*
Y146357D01*
G01X1342525D02*
X1346604D01*
G01X1334252Y176574D02*
X1334034Y176792D01*
Y179062D01*
G01X1346147Y209248D02*
X1343156Y212239D01*
X1342209D01*
G01X1343012Y206618D02*
X1343517D01*
X1346147Y209248D01*
G01X1366714Y109506D02*
X1365800D01*
X1359137Y116169D01*
Y124123D01*
G01X1362587Y128285D02*
Y128067D01*
X1359137Y124617D01*
Y124123D01*
G01X1353850Y140247D02*
X1349335D01*
X1349220Y140362D01*
G01X1376820Y860993D02*
Y858762D01*
G01X1376666Y1402778D02*
X1377026Y1403138D01*
Y1406454D01*
G01X1376686Y1399758D02*
X1375042D01*
X1373541Y1401259D01*
Y1402334D01*
G01X1367316Y1399053D02*
Y1403458D01*
G01X1370391Y1402334D02*
Y1405619D01*
X1371226Y1406454D01*
G01X1367316Y1403458D02*
Y1407458D01*
G01X1370891Y1410306D02*
X1369475Y1411722D01*
Y1412791D01*
G01X1378417Y1415292D02*
X1379870D01*
X1381370Y1413792D01*
G01X1367316Y1407458D02*
X1370222D01*
X1371226Y1406454D01*
G01X1390600Y248262D02*
X1390080Y247742D01*
Y235188D01*
G01X1384220Y860993D02*
Y859162D01*
G01X1411485Y1420659D02*
X1411115Y1420289D01*
G01X1414020Y1420659D02*
X1411485D01*
G01X1422594Y1383301D02*
Y1385308D01*
X1425256Y1391734D01*
X1434567Y1401045D01*
X1437677D01*
X1440207Y1403575D01*
Y1406975D01*
X1438167Y1409015D01*
Y1412984D01*
X1443112Y1417929D01*
G01X1434312Y1415197D02*
X1433913Y1414798D01*
X1429031D01*
X1426435Y1417394D01*
G01X1433750Y1429208D02*
X1432516Y1430442D01*
X1430466D01*
X1428769Y1428745D01*
Y1425312D01*
X1427706Y1424249D01*
X1425556D01*
G01X1424930Y1433850D02*
Y1431063D01*
X1425556Y1430437D01*
Y1427948D01*
G01X1433418Y729104D02*
X1431685Y730837D01*
Y732212D01*
G01X1524330Y1067372D02*
X1573670D01*
X1579000Y1072702D01*
X1586120D01*
X1590380Y1076962D01*
Y1328122D01*
X1603240Y1340982D01*
Y1498912D01*
X1595030Y1507122D01*
X1454120D01*
X1446370Y1499372D01*
Y1427725D01*
X1450388Y1423707D01*
Y1420312D01*
X1450387Y1420311D01*
Y1418644D01*
G01X1437443Y1406289D02*
Y1405830D01*
X1435848Y1404235D01*
X1434162D01*
X1431875Y1401948D01*
G01X1431717Y1409125D02*
X1429251Y1411591D01*
Y1412108D01*
G01X1444468Y1570610D02*
X1444306Y1570772D01*
X1441835D01*
G01X1456295Y157862D02*
X1458720D01*
G01X1449118Y727563D02*
X1453218D01*
G01X1456237Y726945D02*
X1453836D01*
X1453218Y727563D01*
G01X1457620Y736195D02*
X1454747D01*
X1451487Y739455D01*
Y745565D01*
X1450747Y746305D01*
X1449522D01*
G01X1460187Y729805D02*
X1466047D01*
X1467522Y731280D01*
X1469067D01*
G01X1446071Y741070D02*
X1446823D01*
X1448767Y743014D01*
Y745550D01*
X1449522Y746305D01*
G01X1457714Y741622D02*
X1456816Y742520D01*
Y745244D01*
X1457877Y746305D01*
X1460132D01*
G01X1463197Y741070D02*
X1462093D01*
X1460132Y743031D01*
Y746305D01*
G01X1485387Y1420002D02*
X1475986D01*
X1471547Y1415563D01*
Y1394265D01*
X1470017Y1392735D01*
X1457234D01*
X1455734Y1394235D01*
Y1395820D01*
G01X1451176Y1399026D02*
X1450067Y1397917D01*
Y1396591D01*
X1450838Y1395820D01*
X1455734D01*
G01X1467795Y169862D02*
X1470220D01*
G01X1470841Y721493D02*
X1476857Y723985D01*
X1486741Y733869D01*
Y749227D01*
G01X1468947Y741710D02*
X1467081D01*
X1466441Y741070D01*
X1463197D01*
G01X1473020Y860993D02*
Y859062D01*
G01X1486741Y749227D02*
X1490630D01*
X1490992Y749589D01*
G01X1509638Y738627D02*
X1508552Y737541D01*
X1507016D01*
G01X1505551Y741315D02*
X1509350D01*
G01X1503645Y749690D02*
X1504683Y748652D01*
Y747357D01*
X1504747Y747293D01*
G01D02*
X1502694Y745240D01*
X1502417D01*
G01X1534000Y129937D02*
X1536925D01*
G01X1557320Y203297D02*
X1558790Y201827D01*
X1561890D01*
G01X1559722Y243110D02*
X1560109Y243497D01*
X1562890D01*
G01X1571577Y747145D02*
X1573507Y749075D01*
Y749510D01*
G01D02*
X1577507D01*
G01X1594997Y758440D02*
X1594967Y758470D01*
X1590915D01*
G01D02*
Y755793D01*
G01X1592153Y211526D02*
X1603706D01*
G01X1592137Y231490D02*
X1604270D01*
G01X1606788Y758620D02*
Y756199D01*
G01X1602788Y758620D02*
Y756199D01*
G01X1606481Y1258649D02*
X1605630Y1257798D01*
X1602650D01*
G01X1610788Y758620D02*
Y756199D01*
G01X1614788Y758620D02*
Y756199D01*
G01X1618788Y758620D02*
Y756199D01*
G01X1622077Y1440091D02*
X1622861Y1440875D01*
X1624853D01*
G01X1638928Y758620D02*
Y756199D01*
G01X1630928Y758620D02*
Y756199D01*
G01X1634928Y758620D02*
Y756199D01*
G01X1626741Y1258727D02*
X1628153Y1257315D01*
X1629195D01*
X1629566Y1256944D01*
G01X1654718Y522176D02*
X1654306Y521764D01*
Y519657D01*
X1653380Y517421D01*
G01X1654654Y540071D02*
X1651931D01*
G01X1654654Y532071D02*
Y536071D01*
G01X1651851Y532057D02*
X1651865Y532071D01*
X1654654D01*
G01X1653220Y615087D02*
X1657736D01*
X1658736Y614087D01*
X1661120D01*
G01X1653220Y618237D02*
Y620662D01*
G01X1651635Y651836D02*
X1651435Y652036D01*
X1651078D01*
X1649373Y653741D01*
G01X1657755Y517910D02*
Y517911D01*
X1657868Y518024D01*
Y522176D01*
G01X1660866Y546749D02*
X1662276Y545339D01*
Y543536D01*
G01X1664410Y617953D02*
X1663694Y617237D01*
X1661120D01*
G01Y614087D02*
X1669374D01*
X1669397Y614064D01*
G01X1666686Y759659D02*
Y757162D01*
G01X1684940Y463030D02*
Y463752D01*
X1685573Y464385D01*
Y466421D01*
X1686102Y466950D01*
G01X1688244Y502279D02*
X1688826Y501697D01*
X1691129D01*
G01X1686141Y1258727D02*
X1687123Y1257745D01*
X1688165D01*
X1688966Y1256944D01*
G01X1703995Y199720D02*
Y203275D01*
X1703145Y204125D01*
G01X1707160D02*
X1703145D01*
G01D02*
X1702490Y204780D01*
G01X1696851Y521507D02*
X1699265D01*
G01X1696851Y537507D02*
X1699291D01*
G01X1696851Y541507D02*
X1699666D01*
G01X1699251Y533642D02*
X1696986D01*
X1696851Y533507D01*
G01X1733354Y490869D02*
Y502448D01*
X1704886Y530916D01*
Y534564D01*
G01X1704973Y753019D02*
X1712507D01*
X1714955Y755467D01*
Y760501D01*
G01X1719530Y162950D02*
X1720060Y163480D01*
Y167000D01*
X1718030Y169030D01*
X1709690D01*
X1708680Y170040D01*
Y172175D01*
G01X1712824Y696476D02*
X1712238Y695890D01*
X1710057D01*
G01X1713606Y714012D02*
Y716676D01*
X1714745Y717815D01*
Y726927D01*
X1713450Y728222D01*
G01X1718666Y1256944D02*
X1717098Y1258512D01*
X1713620D01*
G01D02*
X1710561D01*
X1709013Y1256964D01*
G01X1721936Y472252D02*
Y469263D01*
G01X1733354Y490869D02*
Y486869D01*
G01X1745541Y1258727D02*
X1746493Y1257775D01*
X1747535D01*
X1748366Y1256944D01*
G01X1754620Y39062D02*
X1755692Y40134D01*
X1758075D01*
G01X1767400Y39915D02*
X1767619Y40134D01*
X1769900D01*
G01X1761936Y310709D02*
X1763528Y309117D01*
X1764680D01*
G01X1777754Y40294D02*
Y37746D01*
G01D02*
Y37596D01*
X1774587Y34429D01*
X1773791D01*
G01X1781990Y40180D02*
X1781876Y40294D01*
X1777754D01*
G01X1775241Y1258727D02*
X1776283Y1257685D01*
X1777325D01*
X1778066Y1256944D01*
G01X1797417Y1247965D02*
X1800267D01*
X1800427Y1248125D01*
G01D02*
X1802087D01*
X1804303Y1245909D01*
X1809349D01*
G01X1817257Y204413D02*
X1831995D01*
X1835760Y200648D01*
Y185772D01*
G01X1804941Y1258727D02*
X1806395Y1257273D01*
Y1256426D01*
G01X1848435Y172187D02*
X1838785D01*
X1836166Y174806D01*
Y185366D01*
X1835760Y185772D01*
G54D24*
X40839Y772416D03*
X74169Y384676D03*
X77121Y696065D03*
X80971D03*
X90396Y695397D03*
X109200Y640346D03*
X105400Y642546D03*
X99516Y693707D03*
X99779Y761928D03*
X103779D03*
X107779D03*
X95779D03*
X112497Y516748D03*
X112900Y640946D03*
X126092Y641627D03*
X136029Y761028D03*
X140029D03*
X140104Y1557561D03*
X144029Y761028D03*
X148029D03*
X144120Y1358796D03*
X153789Y1397410D03*
X155100Y1720566D03*
X168562Y397487D03*
X191602Y762349D03*
X187602D03*
X183602D03*
X182727Y1358685D03*
X190332Y1397385D03*
X190971Y1410654D03*
X205320Y676846D03*
X207602Y762349D03*
X203602D03*
X195602D03*
X199602D03*
X209220Y676846D03*
X211602Y762349D03*
X214580Y1358678D03*
X238063Y34237D03*
X248442Y772391D03*
X257342Y771691D03*
X245066Y1257365D03*
X269046Y732948D03*
Y723153D03*
X265043D03*
X273000Y743488D03*
X268870Y747052D03*
X286046Y723153D03*
X282120Y723051D03*
X288646Y752348D03*
X295520Y18221D03*
X298720Y45846D03*
X290720D03*
X301038Y716669D03*
X294687Y707554D03*
X297087Y726901D03*
X301038Y723808D03*
X304602Y733478D03*
X296706Y752292D03*
X300839Y1318675D03*
X306207Y1355531D03*
X302401Y1363020D03*
X306720Y45846D03*
X320656Y726272D03*
X316656D03*
X317967Y743818D03*
X338161Y718274D03*
X328656Y726272D03*
X335126Y733782D03*
X327096Y741782D03*
X336446Y752292D03*
X328620Y1308036D03*
X338300Y1332733D03*
X336179Y1340002D03*
X340446Y752292D03*
X344446D03*
X370902D03*
X362902D03*
X358902D03*
X368391Y1325415D03*
X382902Y752292D03*
X378902D03*
X386902D03*
X372428Y1319407D03*
X383740Y1663466D03*
X390820Y1281346D03*
X400462Y1325076D03*
X405156Y1319772D03*
X416127Y1411149D03*
X431728Y1325051D03*
X424320Y1405046D03*
X430910Y1405056D03*
X432851Y1621321D03*
X436701Y1319213D03*
X450294Y1420453D03*
X440270Y1622256D03*
X444600Y1622416D03*
X460800Y383046D03*
X468831Y1280975D03*
X468790Y1319175D03*
X464191Y1325076D03*
X473013Y1033108D03*
X499510Y84106D03*
X490963Y1280928D03*
X496319Y1338502D03*
X501013Y1332582D03*
X488570Y1416305D03*
X503150Y74456D03*
X507310Y74476D03*
X529720Y38346D03*
X525900Y114184D03*
X530052Y1315590D03*
X533423Y1355531D03*
X528929Y1361575D03*
X539720Y38346D03*
X534720D03*
X542530Y120216D03*
X546370D03*
X554720Y38346D03*
X572500D03*
X568500D03*
X590100Y59846D03*
X597220Y91346D03*
X592220D03*
X595597Y750914D03*
X608250Y752949D03*
X611760Y746954D03*
X599763Y750930D03*
X614750Y760449D03*
Y767449D03*
X608225Y760514D03*
X607340Y886581D03*
X631130Y58766D03*
X624831Y166116D03*
X629002Y166071D03*
X639000Y63346D03*
X635000D03*
X633673Y1256232D03*
X649047Y36594D03*
X664342Y777591D03*
X661942Y1404719D03*
X671942Y773191D03*
X667408Y1397435D03*
X685968Y55666D03*
X690220D03*
X686588Y90321D03*
X696760Y131216D03*
X688247Y384639D03*
X692247D03*
X694720Y489471D03*
X690720D03*
X693310Y760145D03*
X688967Y790476D03*
X696860Y1358964D03*
X707500Y78346D03*
X708110Y85596D03*
X703500Y78346D03*
X712100Y85596D03*
X701362Y760145D03*
X697336D03*
X705388D03*
X710688D03*
X701830Y1404679D03*
X703951Y1397410D03*
X708219Y1637835D03*
X724644Y55029D03*
X729293D03*
X719949D03*
X723400Y85546D03*
X728909Y763688D03*
X714688Y760145D03*
X718688D03*
X728199Y1358703D03*
X724452Y1587002D03*
X724392Y1607247D03*
X716202Y1607230D03*
X737595Y55029D03*
X741377D03*
X733642D03*
X745474D03*
X732501Y77932D03*
X736601D03*
X745220Y514346D03*
X736909Y763688D03*
X745009Y763748D03*
X732909Y763688D03*
X740909D03*
X749477Y55029D03*
X751220Y514346D03*
X753009Y763748D03*
X749009D03*
X757009D03*
X758758Y1669425D03*
X765188Y1588185D03*
X768714Y1669425D03*
X808797Y436409D03*
X808297Y1591267D03*
X833445Y226202D03*
X849767Y1242960D03*
X850415Y1590731D03*
X898087Y465896D03*
X902875D03*
X907420Y469046D03*
X905010Y493771D03*
X892332Y1591127D03*
X911520Y469046D03*
X916111Y512011D03*
X921149Y523040D03*
X919350Y982516D03*
X919300Y993136D03*
X914500Y1666884D03*
X937643Y514834D03*
X926380Y982666D03*
X961445Y384238D03*
X972379Y506775D03*
X960620Y506746D03*
X980092Y415880D03*
X992345D03*
X994956Y427386D03*
X1020069Y302897D03*
X1009000Y383346D03*
X1024099Y302897D03*
X1035688Y393021D03*
X1047500Y387346D03*
X1053749Y763308D03*
X1057749D03*
X1065749D03*
X1061749D03*
X1087196Y763963D03*
X1083296D03*
X1091096D03*
X1098896D03*
X1102796D03*
X1094996D03*
X1115869Y764048D03*
X1106696Y763963D03*
X1119869Y764048D03*
X1110680Y764125D03*
X1105717Y1257865D03*
X1117420Y1395297D03*
X1127869Y764048D03*
X1123869D03*
X1127100Y1433739D03*
X1121753Y1441063D03*
X1126100Y1447766D03*
X1149467Y592006D03*
X1145467D03*
X1142921Y1257661D03*
X1151687Y1580222D03*
X1141687D03*
X1145687D03*
X1153537Y605996D03*
X1153477Y599026D03*
X1163891Y1258088D03*
X1156552Y1395269D03*
X1163643Y1433714D03*
X1164172Y1447013D03*
X1161095Y1580222D03*
X1155687D03*
X1165095D03*
X1172742Y773891D03*
X1179842Y781791D03*
X1171095Y1580222D03*
X1175095D03*
X1197396Y598805D03*
Y605820D03*
X1187891Y1395008D03*
X1228704Y109046D03*
X1228860Y764249D03*
X1222707Y763409D03*
X1249122Y755891D03*
X1242260Y763449D03*
X1235360D03*
X1258195Y129321D03*
X1260544Y231006D03*
X1256193Y733649D03*
X1252847Y741279D03*
X1263937Y745449D03*
X1266723Y106644D03*
X1280291Y245598D03*
X1277257Y736469D03*
X1273257Y736549D03*
X1280797Y743449D03*
X1274198Y750575D03*
X1276980Y1314736D03*
X1282313Y1355531D03*
X1280192Y1362800D03*
X1297821Y103072D03*
X1283485Y115039D03*
X1287641D03*
X1291704Y115078D03*
X1284120Y244626D03*
X1295947Y728209D03*
X1292007Y730219D03*
X1294937Y752449D03*
X1284797Y745169D03*
X1299890Y130226D03*
X1313597Y745279D03*
X1301487Y752779D03*
X1303761Y1316036D03*
X1314441Y1332733D03*
X1312320Y1340002D03*
X1328020Y179205D03*
X1322501Y186083D03*
X1317567Y745289D03*
X1330888Y752493D03*
X1346604Y149416D03*
X1342525D03*
X1343012Y206527D03*
X1334298Y741636D03*
X1344532Y1325415D03*
X1353850Y140156D03*
X1348241Y207005D03*
X1348569Y1319407D03*
X1367420Y1281546D03*
X1381297Y1319772D03*
X1406963Y1405029D03*
X1412842Y1319213D03*
X1426435Y1420453D03*
X1444852Y1281445D03*
X1444931Y1319175D03*
X1449443Y1032797D03*
X1455734Y1398879D03*
X1469067Y734339D03*
X1466984Y1281398D03*
X1477154Y1332582D03*
X1472460Y1338502D03*
X1465747Y1416849D03*
X1478656Y752285D03*
X1490992Y752648D03*
X1486741Y752286D03*
X1503645Y752749D03*
X1509564Y1355531D03*
X1505070Y1361575D03*
X1517575Y744414D03*
X1584000Y752846D03*
X1582000Y759846D03*
X1590915Y761529D03*
X1582017Y903549D03*
X1602788Y761679D03*
X1594997Y761499D03*
X1606788Y761679D03*
X1618788D03*
X1610788D03*
X1614788D03*
X1622077Y1440000D03*
X1638928Y761679D03*
X1630928D03*
X1634928D03*
X1628600Y1431111D03*
X1653220Y618146D03*
X1654667Y762718D03*
X1662276Y543445D03*
X1658679Y762718D03*
X1666686D03*
X1662656D03*
X1658026Y1391710D03*
X1665117Y1431006D03*
X1665666Y1444265D03*
X1685686Y482137D03*
X1703000Y96346D03*
X1699000D03*
X1699150Y508536D03*
X1702848Y763552D03*
X1689565Y1391449D03*
X1710025Y21376D03*
X1713173Y34228D03*
X1708000Y96346D03*
X1708680Y175234D03*
X1707160Y207184D03*
X1710057Y698949D03*
X1709486Y713971D03*
X1714955Y763560D03*
X1710915D03*
X1706948Y763552D03*
X1769791Y34338D03*
X1758075Y43193D03*
X1755378Y231012D03*
X1779575Y16706D03*
X1774435Y16726D03*
G54D108*
X1340763Y173921D03*
G54D60*
X417650Y1635132D03*
X410170D03*
X417580Y1643304D03*
X410100D03*
X937566Y382223D03*
X933830Y967442D03*
X941310D03*
X945046Y382223D03*
X1026552Y405913D03*
X1034032D03*
G54D51*
X230906Y1734212D03*
X297835D03*
X495079D03*
X562008D03*
X1238780D03*
X1305709D03*
X1502953D03*
X1569882D03*
G54D15*
G01X122575Y671930D02*
X122033Y671388D01*
Y667700D01*
G01X140104Y1557652D02*
Y1560136D01*
G01X323420Y205049D02*
Y207549D01*
G01X327650Y205049D02*
Y206098D01*
X326168Y207580D01*
G01X445294Y1430415D02*
Y1429069D01*
X446395Y1427968D01*
G01X611870Y512560D02*
Y509870D01*
X609100Y507100D01*
Y483600D01*
X597220Y471720D01*
Y458688D01*
G01X1272550Y1347922D02*
X1272346Y1348126D01*
Y1352472D01*
G01D02*
X1275856D01*
G01X1282313D02*
X1280536D01*
Y1352828D01*
X1279812Y1353552D01*
G01D02*
X1278732Y1352472D01*
X1275856D01*
G01X1311820Y1330518D02*
X1312664Y1329674D01*
X1314441D01*
G01X1332262Y211099D02*
X1333257Y212094D01*
X1335120D01*
G01X1332262Y207399D02*
X1333807Y208944D01*
X1335120D01*
G01X1343948Y1317092D02*
X1344692Y1316348D01*
X1348569D01*
G01X1376076Y1317092D02*
X1376455Y1316713D01*
X1381297D01*
G01X1408204Y1317092D02*
X1409142Y1316154D01*
X1412842D01*
G01X1440332Y1317092D02*
X1441308Y1316116D01*
X1444931D01*
G01X1472460Y1330493D02*
X1472485D01*
X1473455Y1329523D01*
X1477154D01*
G01X1504588Y1353316D02*
X1505432Y1352472D01*
X1509564D01*
G01X1641082Y652601D02*
X1640144Y651663D01*
Y647963D01*
G01X1641082Y686601D02*
X1640144Y685663D01*
Y681963D01*
G01Y715963D02*
Y717577D01*
X1638039Y719682D01*
Y722018D01*
X1638713Y722692D01*
G01X1641082Y720601D02*
Y722211D01*
X1640601Y722692D01*
X1638713D01*
G01X1669222Y604490D02*
X1666380Y607332D01*
X1665025D01*
G01X1689095Y462640D02*
X1689252Y462797D01*
Y466950D01*
X27699Y770144D03*
Y783530D03*
Y776837D03*
Y800263D03*
Y793570D03*
Y820341D03*
Y813648D03*
Y806955D03*
Y830381D03*
Y850459D03*
Y843766D03*
Y837074D03*
Y867192D03*
Y857152D03*
Y880577D03*
Y873885D03*
Y893963D03*
Y887270D03*
Y917389D03*
Y910696D03*
Y904003D03*
Y930774D03*
Y924081D03*
Y947507D03*
Y940814D03*
Y964239D03*
Y954200D03*
Y977625D03*
Y970932D03*
Y991011D03*
Y984318D03*
Y1031168D03*
Y1024475D03*
Y1017782D03*
Y1044554D03*
Y1037861D03*
Y1057940D03*
Y1051247D03*
Y1078018D03*
Y1071326D03*
Y1064633D03*
Y1094751D03*
Y1088058D03*
Y1108137D03*
Y1101444D03*
Y1124869D03*
Y1114829D03*
Y1144948D03*
Y1138255D03*
Y1131562D03*
Y1161680D03*
Y1151641D03*
Y1175066D03*
Y1168373D03*
Y1188452D03*
Y1181759D03*
Y1205184D03*
Y1198491D03*
Y1225263D03*
Y1218570D03*
Y1211877D03*
Y1241995D03*
Y1235302D03*
Y1248688D03*
Y1258727D03*
Y1255381D03*
Y1265420D03*
Y1262074D03*
X43841Y766798D03*
X36399Y770144D03*
X43841Y780184D03*
Y773491D03*
X36399Y783530D03*
Y776837D03*
X43841Y803609D03*
Y796916D03*
Y790223D03*
X36399Y800263D03*
Y793570D03*
X43841Y816995D03*
Y810302D03*
X36399Y820341D03*
Y813648D03*
Y806955D03*
X43841Y833727D03*
Y827034D03*
X36399Y830381D03*
X43841Y847113D03*
Y840420D03*
X36399Y850459D03*
Y843766D03*
Y837074D03*
X43841Y863845D03*
Y853806D03*
X36399Y867192D03*
Y857152D03*
X43841Y883924D03*
Y877231D03*
Y870538D03*
X36399Y880577D03*
Y873885D03*
X43841Y900656D03*
Y890617D03*
X36399Y893963D03*
Y887270D03*
X43841Y914042D03*
Y907349D03*
X36399Y917389D03*
Y910696D03*
Y904003D03*
X43841Y927428D03*
Y920735D03*
X36399Y930774D03*
Y924081D03*
X43841Y944160D03*
Y937467D03*
X36399Y947507D03*
Y940814D03*
X43841Y960892D03*
Y950853D03*
X36399Y964239D03*
Y954200D03*
X43841Y980971D03*
Y974278D03*
Y967585D03*
X36399Y977625D03*
Y970932D03*
X43841Y987664D03*
X36399Y991011D03*
Y984318D03*
X43841Y994357D03*
Y1027822D03*
Y1017782D03*
X36399Y1031168D03*
Y1024475D03*
Y1017782D03*
X43841Y1047900D03*
Y1041207D03*
Y1034515D03*
X36399Y1044554D03*
Y1037861D03*
X43841Y1061286D03*
Y1054593D03*
X36399Y1057940D03*
Y1051247D03*
X43841Y1074672D03*
Y1067979D03*
X36399Y1078018D03*
Y1071326D03*
Y1064633D03*
X43841Y1091404D03*
Y1084711D03*
X36399Y1094751D03*
Y1088058D03*
X43841Y1111483D03*
Y1104790D03*
Y1098097D03*
X36399Y1108137D03*
Y1101444D03*
X43841Y1128215D03*
Y1121522D03*
X36399Y1124869D03*
Y1114829D03*
X43841Y1141601D03*
Y1134908D03*
X36399Y1144948D03*
Y1138255D03*
Y1131562D03*
X43841Y1158333D03*
Y1148294D03*
X36399Y1161680D03*
Y1151641D03*
X43841Y1171719D03*
Y1165026D03*
X36399Y1175066D03*
Y1168373D03*
X43841Y1185105D03*
Y1178412D03*
X36399Y1188452D03*
Y1181759D03*
X43841Y1208530D03*
Y1201837D03*
Y1195144D03*
X36399Y1205184D03*
Y1198491D03*
X43841Y1221916D03*
Y1215223D03*
X36399Y1225263D03*
Y1218570D03*
Y1211877D03*
X43841Y1238648D03*
Y1231955D03*
X36399Y1241995D03*
Y1235302D03*
X43841Y1245341D03*
X36399Y1248688D03*
X36449Y1257262D03*
X43841Y1255381D03*
Y1258727D03*
Y1252034D03*
X33546Y1273364D03*
X30746D03*
X43841Y1262074D03*
Y1265420D03*
X57399Y770144D03*
X52541Y766798D03*
X57299D03*
X57399Y783530D03*
Y776837D03*
X52541Y780184D03*
Y773491D03*
X57399Y800263D03*
Y793570D03*
X52541Y803609D03*
Y796916D03*
Y790223D03*
X57399Y820341D03*
Y813648D03*
Y806955D03*
X52541Y816995D03*
Y810302D03*
X57399Y830381D03*
X52541Y833727D03*
Y827034D03*
X57399Y850459D03*
Y843766D03*
Y837074D03*
X52541Y847113D03*
Y840420D03*
X57399Y867192D03*
Y857152D03*
X52541Y863845D03*
Y853806D03*
X57399Y880577D03*
Y873885D03*
X52541Y883924D03*
Y877231D03*
Y870538D03*
X57399Y893963D03*
Y887270D03*
X52541Y900656D03*
Y890617D03*
X57399Y917389D03*
Y910696D03*
Y904003D03*
X52541Y914042D03*
Y907349D03*
X57399Y930774D03*
Y924081D03*
X52541Y927428D03*
Y920735D03*
X57399Y947507D03*
Y940814D03*
X52541Y944160D03*
Y937467D03*
X57399Y964239D03*
Y954200D03*
X52541Y960892D03*
Y950853D03*
Y957546D03*
Y954200D03*
X57399Y977625D03*
Y970932D03*
X52541Y980971D03*
Y974278D03*
Y967585D03*
X57399Y991011D03*
Y984318D03*
X52541Y987664D03*
X57399Y1031168D03*
Y1024475D03*
Y1017782D03*
X52541Y1027822D03*
Y1017782D03*
X57399Y1044554D03*
Y1037861D03*
X52541Y1047900D03*
Y1041207D03*
Y1034515D03*
X57399Y1057940D03*
Y1051247D03*
X52541Y1061286D03*
Y1054593D03*
X57399Y1078018D03*
Y1071326D03*
Y1064633D03*
X52541Y1074672D03*
Y1067979D03*
X57399Y1094751D03*
Y1088058D03*
X52541Y1091404D03*
Y1084711D03*
X57399Y1108137D03*
Y1101444D03*
X52541Y1111483D03*
Y1104790D03*
Y1098097D03*
X57399Y1124869D03*
Y1114829D03*
X52541Y1128215D03*
Y1121522D03*
X57399Y1144948D03*
Y1138255D03*
Y1131562D03*
X52541Y1141601D03*
Y1134908D03*
X57399Y1161680D03*
Y1151641D03*
X52541Y1158333D03*
Y1148294D03*
X57399Y1175066D03*
Y1168373D03*
X52541Y1171719D03*
Y1165026D03*
X57399Y1188452D03*
Y1181759D03*
X52541Y1185105D03*
Y1178412D03*
X57399Y1205184D03*
Y1198491D03*
X52541Y1208530D03*
Y1201837D03*
Y1195144D03*
X57399Y1225263D03*
Y1218570D03*
Y1211877D03*
X52541Y1221916D03*
Y1215223D03*
X57399Y1241995D03*
Y1235302D03*
X52541Y1238648D03*
Y1231955D03*
Y1248688D03*
X57399D03*
X52541Y1245341D03*
X57399Y1258727D03*
X52820Y1253862D03*
X60446Y1273364D03*
X49546D03*
X46746D03*
X57399Y1265420D03*
Y1262074D03*
X73541Y766798D03*
X66099Y770144D03*
X73541Y780184D03*
Y773491D03*
X66099Y783530D03*
Y776837D03*
X73541Y803609D03*
Y796916D03*
Y790223D03*
X66099Y800263D03*
Y793570D03*
X73541Y816995D03*
Y810302D03*
X66099Y820341D03*
Y813648D03*
Y806955D03*
X73541Y833727D03*
Y827034D03*
X66099Y830381D03*
X73541Y847113D03*
Y840420D03*
X66099Y850459D03*
Y843766D03*
Y837074D03*
X73541Y863845D03*
Y853806D03*
X66099Y867192D03*
Y857152D03*
X73541Y883924D03*
Y877231D03*
Y870538D03*
X66099Y880577D03*
Y873885D03*
X73541Y900656D03*
Y890617D03*
X66099Y893963D03*
Y887270D03*
X73541Y914042D03*
Y907349D03*
X66099Y917389D03*
Y910696D03*
Y904003D03*
X73541Y927428D03*
Y920735D03*
X66099Y930774D03*
Y924081D03*
X73541Y944160D03*
Y937467D03*
X66099Y947507D03*
Y940814D03*
X73541Y960892D03*
Y950853D03*
X66099Y964239D03*
Y954200D03*
X73541Y980971D03*
Y974278D03*
Y967585D03*
X66099Y977625D03*
Y970932D03*
X73541Y987664D03*
X66099Y991011D03*
Y984318D03*
X73541Y1027822D03*
Y1017782D03*
X66099Y1031168D03*
Y1024475D03*
Y1017782D03*
X73541Y1047900D03*
Y1041207D03*
Y1034515D03*
X66099Y1044554D03*
Y1037861D03*
X73541Y1061286D03*
Y1054593D03*
X66099Y1057940D03*
Y1051247D03*
Y1061286D03*
X73541Y1074672D03*
Y1067979D03*
X66099Y1078018D03*
Y1071326D03*
Y1064633D03*
X73541Y1091404D03*
Y1084711D03*
X66099Y1094751D03*
Y1088058D03*
X73541Y1111483D03*
Y1104790D03*
Y1098097D03*
X66099Y1108137D03*
Y1101444D03*
X73541Y1128215D03*
Y1121522D03*
X66099Y1124869D03*
Y1114829D03*
X73541Y1141601D03*
Y1134908D03*
X66099Y1144948D03*
Y1138255D03*
Y1131562D03*
X73541Y1158333D03*
Y1148294D03*
X66099Y1161680D03*
Y1151641D03*
X73541Y1171719D03*
Y1165026D03*
X66099Y1175066D03*
Y1168373D03*
X73541Y1185105D03*
Y1178412D03*
X66099Y1188452D03*
Y1181759D03*
X73541Y1208530D03*
Y1201837D03*
Y1195144D03*
X66099Y1205184D03*
Y1198491D03*
X73541Y1221916D03*
Y1215223D03*
X66099Y1225263D03*
Y1218570D03*
Y1211877D03*
X73541Y1238648D03*
Y1231955D03*
X66099Y1241995D03*
Y1235302D03*
X66189Y1257488D03*
X73541Y1245341D03*
X66099Y1248688D03*
X73541Y1255381D03*
Y1258727D03*
Y1252034D03*
X76446Y1273364D03*
X63246D03*
X73541Y1265420D03*
Y1262074D03*
X87099Y770144D03*
X82241Y766798D03*
X86999D03*
X87099Y783530D03*
Y776837D03*
X82241Y780184D03*
Y773491D03*
X87099Y800263D03*
Y793570D03*
X82241Y803609D03*
Y796916D03*
Y790223D03*
X87099Y820341D03*
Y813648D03*
Y806955D03*
X82241Y816995D03*
Y810302D03*
X87099Y830381D03*
X82241Y833727D03*
Y827034D03*
X87099Y850459D03*
Y843766D03*
Y837074D03*
X82241Y847113D03*
Y840420D03*
X87099Y867192D03*
Y857152D03*
X82241Y863845D03*
Y853806D03*
X87099Y880577D03*
Y873885D03*
X82241Y883924D03*
Y877231D03*
Y870538D03*
X87099Y893963D03*
Y887270D03*
X82241Y900656D03*
Y890617D03*
X87099Y917389D03*
Y910696D03*
Y904003D03*
X82241Y914042D03*
Y907349D03*
X87099Y930774D03*
Y924081D03*
X82241Y927428D03*
Y920735D03*
X87099Y947507D03*
Y940814D03*
X82241Y944160D03*
Y937467D03*
X87099Y964239D03*
Y954200D03*
X82241Y960892D03*
Y950853D03*
Y957546D03*
Y954200D03*
X87099Y977625D03*
Y970932D03*
X82241Y980971D03*
Y974278D03*
Y967585D03*
X87099Y991011D03*
Y984318D03*
X82241Y987664D03*
Y994357D03*
X87099Y1031168D03*
Y1024475D03*
Y1017782D03*
X82241Y1027822D03*
Y1017782D03*
X87099Y1044554D03*
Y1037861D03*
X82241Y1047900D03*
Y1041207D03*
Y1034515D03*
X87099Y1057940D03*
Y1051247D03*
X82241Y1061286D03*
Y1054593D03*
X87099Y1078018D03*
Y1071326D03*
Y1064633D03*
X82241Y1074672D03*
Y1067979D03*
X87099Y1094751D03*
Y1088058D03*
X82241Y1091404D03*
Y1084711D03*
X87099Y1108137D03*
Y1101444D03*
X82241Y1111483D03*
Y1104790D03*
Y1098097D03*
X87099Y1124869D03*
Y1114829D03*
X82241Y1128215D03*
Y1121522D03*
X87099Y1144948D03*
Y1138255D03*
Y1131562D03*
X82241Y1141601D03*
Y1134908D03*
X87099Y1161680D03*
Y1151641D03*
X82241Y1158333D03*
Y1148294D03*
X87099Y1175066D03*
Y1168373D03*
X82241Y1171719D03*
Y1165026D03*
X87099Y1188452D03*
Y1181759D03*
X82241Y1185105D03*
Y1178412D03*
X87099Y1205184D03*
Y1198491D03*
X82241Y1208530D03*
Y1201837D03*
Y1195144D03*
X87099Y1225263D03*
Y1218570D03*
Y1211877D03*
X82241Y1221916D03*
Y1215223D03*
X87099Y1241995D03*
Y1235302D03*
X82241Y1238648D03*
Y1231955D03*
X87099Y1248688D03*
X82241Y1245341D03*
X87099Y1258727D03*
X82241Y1248688D03*
X84334Y1254263D03*
X92946Y1273364D03*
X90146D03*
X79246D03*
X87099Y1265420D03*
Y1262074D03*
X103241Y766798D03*
X95799Y770144D03*
X103241Y780184D03*
Y773491D03*
X95799Y783530D03*
Y776837D03*
X103241Y803609D03*
Y796916D03*
Y790223D03*
X95799Y800263D03*
Y793570D03*
X103241Y816995D03*
Y810302D03*
X95799Y820341D03*
Y813648D03*
Y806955D03*
X103241Y833727D03*
Y827034D03*
X95799Y830381D03*
X103241Y847113D03*
Y840420D03*
X95799Y850459D03*
Y843766D03*
Y837074D03*
X103241Y863845D03*
Y853806D03*
X95799Y867192D03*
Y857152D03*
X103241Y883924D03*
Y877231D03*
Y870538D03*
X95799Y880577D03*
Y873885D03*
X103241Y900656D03*
Y890617D03*
X95799Y893963D03*
Y887270D03*
X103241Y914042D03*
Y907349D03*
X95799Y917389D03*
Y910696D03*
Y904003D03*
X103241Y927428D03*
Y920735D03*
X95799Y930774D03*
Y924081D03*
X103241Y944160D03*
Y937467D03*
X95799Y947507D03*
Y940814D03*
X103241Y960892D03*
Y950853D03*
X95799Y964239D03*
Y954200D03*
X103241Y980971D03*
Y974278D03*
Y967585D03*
X95799Y977625D03*
Y970932D03*
X103241Y987664D03*
X95799Y991011D03*
Y984318D03*
X103241Y994357D03*
Y1027822D03*
Y1017782D03*
X95799Y1031168D03*
Y1024475D03*
Y1017782D03*
X103241Y1047900D03*
Y1041207D03*
Y1034515D03*
X95799Y1044554D03*
Y1037861D03*
X103241Y1061286D03*
Y1054593D03*
X95799Y1057940D03*
Y1051247D03*
X103241Y1074672D03*
Y1067979D03*
X95799Y1078018D03*
Y1071326D03*
Y1064633D03*
X103241Y1091404D03*
Y1084711D03*
X95799Y1094751D03*
Y1088058D03*
X103241Y1111483D03*
Y1104790D03*
Y1098097D03*
X95799Y1108137D03*
Y1101444D03*
X103241Y1128215D03*
Y1121522D03*
X95799Y1124869D03*
Y1114829D03*
X103241Y1141601D03*
Y1134908D03*
X95799Y1144948D03*
Y1138255D03*
Y1131562D03*
X103241Y1158333D03*
Y1148294D03*
X95799Y1161680D03*
Y1151641D03*
X103241Y1171719D03*
Y1165026D03*
X95799Y1175066D03*
Y1168373D03*
X103241Y1185105D03*
Y1178412D03*
X95799Y1188452D03*
Y1181759D03*
X103241Y1208530D03*
Y1201837D03*
Y1195144D03*
X95799Y1205184D03*
Y1198491D03*
X103241Y1221916D03*
Y1215223D03*
X95799Y1225263D03*
Y1218570D03*
Y1211877D03*
X103241Y1238648D03*
Y1231955D03*
X95799Y1241995D03*
Y1235302D03*
X95849Y1257262D03*
X103241Y1245341D03*
X95799Y1248688D03*
X103241Y1255381D03*
Y1258727D03*
Y1252034D03*
X108946Y1273364D03*
X106146D03*
X103241Y1265420D03*
Y1262074D03*
X125499Y770144D03*
X116799D03*
X111941Y766798D03*
X116567Y766775D03*
X125499Y783530D03*
X116799D03*
X125499Y776837D03*
X116799D03*
X111941Y780184D03*
Y773491D03*
X125499Y800263D03*
X116799D03*
X125499Y793570D03*
X116799D03*
X111941Y803609D03*
Y796916D03*
Y790223D03*
X125499Y820341D03*
X116799D03*
X125499Y813648D03*
X116799D03*
X125499Y806955D03*
X116799D03*
X111941Y816995D03*
Y810302D03*
X125499Y830381D03*
X116799D03*
X111941Y833727D03*
Y827034D03*
X125499Y850459D03*
X116799D03*
X125499Y843766D03*
X116799D03*
X125499Y837074D03*
X116799D03*
X111941Y847113D03*
Y840420D03*
X125499Y867192D03*
X116799D03*
X125499Y857152D03*
X116799D03*
X111941Y863845D03*
Y853806D03*
X125499Y880577D03*
X116799D03*
X125499Y873885D03*
X116799D03*
X111941Y883924D03*
Y877231D03*
Y870538D03*
X125499Y893963D03*
X116799D03*
X125499Y887270D03*
X116799D03*
X111941Y900656D03*
Y890617D03*
X125499Y917389D03*
X116799D03*
X125499Y910696D03*
X116799D03*
X125499Y904003D03*
X116799D03*
X111941Y914042D03*
Y907349D03*
X125499Y930774D03*
X116799D03*
X125499Y924081D03*
X116799D03*
X111941Y927428D03*
Y920735D03*
X125499Y947507D03*
X116799D03*
X125499Y940814D03*
X116799D03*
X111941Y944160D03*
Y937467D03*
X125499Y964239D03*
X116799D03*
X125499Y954200D03*
X116799D03*
X111941Y960892D03*
Y950853D03*
Y957546D03*
Y954200D03*
X125499Y977625D03*
X116799D03*
X125499Y970932D03*
X116799D03*
X111941Y980971D03*
Y974278D03*
Y967585D03*
X125499Y991011D03*
X116799D03*
X125499Y984318D03*
X116799D03*
X111941Y987664D03*
X125499Y1031168D03*
X116799D03*
X125499Y1024475D03*
X116799D03*
X125499Y1017782D03*
X116799D03*
X111941Y1027822D03*
Y1017782D03*
X125499Y1044554D03*
X116799D03*
X125499Y1037861D03*
X116799D03*
X111941Y1047900D03*
Y1041207D03*
Y1034515D03*
X125499Y1057940D03*
X116799D03*
X125499Y1051247D03*
X116799D03*
X111941Y1061286D03*
Y1054593D03*
X125499Y1061286D03*
Y1078018D03*
X116799D03*
X125499Y1071326D03*
X116799D03*
X125499Y1064633D03*
X116799D03*
X111941Y1074672D03*
Y1067979D03*
X125499Y1094751D03*
X116799D03*
X125499Y1088058D03*
X116799D03*
X111941Y1091404D03*
Y1084711D03*
X125499Y1108137D03*
X116799D03*
X125499Y1101444D03*
X116799D03*
X111941Y1111483D03*
Y1104790D03*
Y1098097D03*
X125499Y1124869D03*
X116799D03*
X125499Y1114829D03*
X116799D03*
X111941Y1128215D03*
Y1121522D03*
X125499Y1144948D03*
X116799D03*
X125499Y1138255D03*
X116799D03*
X125499Y1131562D03*
X116799D03*
X111941Y1141601D03*
Y1134908D03*
X125499Y1161680D03*
X116799D03*
X125499Y1151641D03*
X116799D03*
X111941Y1158333D03*
Y1148294D03*
X125499Y1175066D03*
X116799D03*
X125499Y1168373D03*
X116799D03*
X111941Y1171719D03*
Y1165026D03*
X125499Y1188452D03*
X116799D03*
X125499Y1181759D03*
X116799D03*
X111941Y1185105D03*
Y1178412D03*
X125499Y1205184D03*
X116799D03*
X125499Y1198491D03*
X116799D03*
X111941Y1208530D03*
Y1201837D03*
Y1195144D03*
X125499Y1225263D03*
X116799D03*
X125499Y1218570D03*
X116799D03*
X125499Y1211877D03*
X116799D03*
X111941Y1221916D03*
Y1215223D03*
X125499Y1241995D03*
X116799D03*
X125499Y1235302D03*
X116799D03*
X111941Y1238648D03*
Y1231955D03*
X125412Y1257102D03*
X125499Y1248688D03*
X116799D03*
X111941Y1245341D03*
X116799Y1258727D03*
X111941Y1248688D03*
X114191Y1254604D03*
X119846Y1273364D03*
X122646D03*
X116799Y1265420D03*
Y1262074D03*
X141641Y766798D03*
X132941D03*
X141641Y773491D03*
X132941D03*
X141641Y780184D03*
X132941D03*
X141641Y803609D03*
X132941D03*
X141641Y790223D03*
X132941D03*
X141641Y796916D03*
X132941D03*
X141641Y816995D03*
X132941D03*
X141641Y810302D03*
X132941D03*
X141641Y833727D03*
X132941D03*
X141641Y827034D03*
X132941D03*
X141641Y840420D03*
X132941D03*
X141641Y847113D03*
X132941D03*
Y863845D03*
X141641D03*
Y853806D03*
X132941D03*
Y883924D03*
X141641D03*
X132941Y870538D03*
X141641D03*
X132941Y877231D03*
X141641D03*
X132941Y900656D03*
X141641D03*
X132941Y890617D03*
X141641D03*
X132941Y907349D03*
X141641D03*
X132941Y914042D03*
X141641D03*
X132941Y920735D03*
X141641D03*
X132941Y927428D03*
X141641D03*
X132941Y937467D03*
X141641D03*
X132941Y944160D03*
X141641D03*
X132941Y960892D03*
X141641D03*
X132941Y950853D03*
X141641D03*
Y957546D03*
Y954200D03*
X132941Y980971D03*
X141641D03*
X132941Y974278D03*
X141641D03*
X132941Y967585D03*
X141641D03*
X132941Y987664D03*
X141641D03*
Y994357D03*
X132941Y1027822D03*
X141641D03*
X132941Y1017782D03*
X141641D03*
X132941Y1047900D03*
X141641D03*
X132941Y1041207D03*
X141641D03*
X132941Y1034515D03*
X141641D03*
Y1061286D03*
X132941D03*
X141641Y1054593D03*
X132941D03*
X141641Y1057940D03*
Y1074672D03*
X132941D03*
X141641Y1067979D03*
X132941D03*
X141641Y1091404D03*
X132941D03*
X141641Y1084711D03*
X132941D03*
X141641Y1111483D03*
X132941D03*
X141641Y1104790D03*
X132941D03*
X141641Y1098097D03*
X132941D03*
X141641Y1128215D03*
X132941D03*
X141641Y1121522D03*
X132941D03*
X141641Y1141601D03*
X132941D03*
X141641Y1134908D03*
X132941D03*
X141641Y1158333D03*
X132941D03*
X141641Y1148294D03*
X132941D03*
X141641Y1171719D03*
X132941D03*
X141641Y1165026D03*
X132941D03*
X141641Y1185105D03*
X132941D03*
X141641Y1178412D03*
X132941D03*
X141641Y1208530D03*
X132941D03*
X141641Y1201837D03*
X132941D03*
X141641Y1195144D03*
X132941D03*
Y1221916D03*
X141641D03*
X132941Y1215223D03*
X141641D03*
X132941Y1238648D03*
X141641D03*
X132941Y1231955D03*
X141641D03*
X129933Y1238461D03*
X132941Y1245341D03*
X141641D03*
X132941Y1255381D03*
Y1258727D03*
Y1252034D03*
X141641Y1248688D03*
X143675Y1255567D03*
X135846Y1273364D03*
X138646D03*
X132941Y1265420D03*
Y1262074D03*
X146499Y770144D03*
X155199D03*
X146367Y766775D03*
X146499Y783530D03*
X155199D03*
X146499Y776837D03*
X155199D03*
X146499Y800263D03*
X155199D03*
X146499Y793570D03*
X155199D03*
X146499Y820341D03*
X155199D03*
X146499Y813648D03*
X155199D03*
X146499Y806955D03*
X155199D03*
X146499Y830381D03*
X155199D03*
X146499Y850459D03*
X155199D03*
X146499Y843766D03*
X155199D03*
X146499Y837074D03*
X155199D03*
Y867192D03*
X146499D03*
Y857152D03*
X155199D03*
Y880577D03*
X146499D03*
X155199Y873885D03*
X146499D03*
X155199Y893963D03*
X146499D03*
X155199Y887270D03*
X146499D03*
X155199Y917389D03*
X146499D03*
X155199Y910696D03*
X146499D03*
X155199Y904003D03*
X146499D03*
X155199Y930774D03*
X146499D03*
X155199Y924081D03*
X146499D03*
X155199Y947507D03*
X146499D03*
X155199Y940814D03*
X146499D03*
X155199Y964239D03*
X146499D03*
X155199Y954200D03*
X146499D03*
X155199Y977625D03*
X146499D03*
X155199Y970932D03*
X146499D03*
X155199Y991011D03*
X146499D03*
X155199Y984318D03*
X146499D03*
X155199Y1031168D03*
X146499D03*
X155199Y1024475D03*
X146499D03*
X155199Y1017782D03*
X146499D03*
X155199Y1044554D03*
X146499D03*
X155199Y1037861D03*
X146499D03*
X155199Y1057940D03*
X146499D03*
X155199Y1051247D03*
X146499D03*
X155199Y1078018D03*
X146499D03*
X155199Y1071326D03*
X146499D03*
X155199Y1064633D03*
X146499D03*
X155199Y1094751D03*
X146499D03*
X155199Y1088058D03*
X146499D03*
X155199Y1108137D03*
X146499D03*
X155199Y1101444D03*
X146499D03*
X155199Y1124869D03*
X146499D03*
X155199Y1114829D03*
X146499D03*
X155199Y1144948D03*
X146499D03*
X155199Y1138255D03*
X146499D03*
X155199Y1131562D03*
X146499D03*
X155199Y1161680D03*
X146499D03*
X155199Y1151641D03*
X146499D03*
X155199Y1175066D03*
X146499D03*
X155199Y1168373D03*
X146499D03*
X155199Y1188452D03*
X146499D03*
X155199Y1181759D03*
X146499D03*
X155199Y1205184D03*
X146499D03*
X155199Y1198491D03*
X146499D03*
X155199Y1225263D03*
X146499D03*
X155199Y1218570D03*
X146499D03*
X155199Y1211877D03*
X146499D03*
X155199Y1241995D03*
X146499D03*
X155199Y1235302D03*
X146499D03*
X155135Y1257134D03*
X155199Y1248688D03*
X146499D03*
X160130Y1251847D03*
X146499Y1258727D03*
X149546Y1273364D03*
X152346D03*
X146499Y1265420D03*
Y1262074D03*
X176199Y770144D03*
X162641Y766798D03*
X171341D03*
X176099D03*
X176199Y783530D03*
Y776837D03*
X162641Y780184D03*
X171341D03*
Y773491D03*
X162641D03*
X176199Y800263D03*
X162641Y803609D03*
X171341D03*
X176199Y793570D03*
X162641Y796916D03*
X171341D03*
X162641Y790223D03*
X171341D03*
X176199Y820341D03*
X162641Y816995D03*
X171341D03*
X176199Y813648D03*
Y806955D03*
X162641Y810302D03*
X171341D03*
X162641Y833727D03*
X171341D03*
X176199Y830381D03*
X162641Y827034D03*
X171341D03*
X176199Y850459D03*
Y843766D03*
Y837074D03*
X162641Y847113D03*
X171341D03*
X162641Y840420D03*
X171341D03*
X176199Y867192D03*
X171341Y863845D03*
X162641D03*
X176199Y857152D03*
X162641Y853806D03*
X171341D03*
Y883924D03*
X162641D03*
X176199Y880577D03*
Y873885D03*
X171341Y877231D03*
X162641D03*
X171341Y870538D03*
X162641D03*
X171341Y900656D03*
X162641D03*
X176199Y893963D03*
Y887270D03*
X171341Y890617D03*
X162641D03*
X176199Y917389D03*
Y910696D03*
Y904003D03*
X171341Y914042D03*
X162641D03*
X171341Y907349D03*
X162641D03*
X176199Y930774D03*
Y924081D03*
X171341Y927428D03*
X162641D03*
X171341Y920735D03*
X162641D03*
X176199Y947507D03*
Y940814D03*
X171341Y944160D03*
X162641D03*
X171341Y937467D03*
X162641D03*
X176199Y964239D03*
Y954200D03*
X171341Y960892D03*
X162641D03*
X171341Y950853D03*
X162641D03*
X171341Y957546D03*
Y954200D03*
Y980971D03*
X162641D03*
X176199Y977625D03*
Y970932D03*
X171341Y974278D03*
X162641D03*
X171341Y967585D03*
X162641D03*
X176199Y991011D03*
Y984318D03*
X171341Y987664D03*
X162641D03*
Y994357D03*
X176199Y1031168D03*
Y1024475D03*
Y1017782D03*
X171341Y1027822D03*
X162641D03*
X171341Y1017782D03*
X162641D03*
X171341Y1047900D03*
X162641D03*
X176199Y1044554D03*
Y1037861D03*
X171341Y1041207D03*
X162641D03*
X171341Y1034515D03*
X162641D03*
X176199Y1057940D03*
Y1051247D03*
X171341Y1061286D03*
X162641D03*
X171341Y1054593D03*
X162641D03*
X176199Y1078018D03*
Y1071326D03*
Y1064633D03*
X171341Y1074672D03*
X162641D03*
X171341Y1067979D03*
X162641D03*
X176199Y1094751D03*
Y1088058D03*
X171341Y1091404D03*
X162641D03*
X171341Y1084711D03*
X162641D03*
X171341Y1111483D03*
X162641D03*
X176199Y1108137D03*
Y1101444D03*
X171341Y1104790D03*
X162641D03*
X171341Y1098097D03*
X162641D03*
X171341Y1128215D03*
X162641D03*
X176199Y1124869D03*
Y1114829D03*
X171341Y1121522D03*
X162641D03*
X176199Y1144948D03*
Y1138255D03*
Y1131562D03*
X171341Y1141601D03*
X162641D03*
X171341Y1134908D03*
X162641D03*
X176199Y1161680D03*
Y1151641D03*
X171341Y1158333D03*
X162641D03*
X171341Y1148294D03*
X162641D03*
X176199Y1175066D03*
Y1168373D03*
X171341Y1171719D03*
X162641D03*
X171341Y1165026D03*
X162641D03*
X176199Y1188452D03*
Y1181759D03*
X171341Y1185105D03*
X162641D03*
X171341Y1178412D03*
X162641D03*
X176199Y1205184D03*
Y1198491D03*
X171341Y1208530D03*
X162641D03*
X171341Y1201837D03*
X162641D03*
X171341Y1195144D03*
X162641D03*
X176199Y1225263D03*
Y1218570D03*
Y1211877D03*
X162641Y1221916D03*
X171341D03*
Y1215223D03*
X162641D03*
X176199Y1241995D03*
Y1235302D03*
X171341Y1238648D03*
X162641D03*
X171341Y1231955D03*
X162641D03*
X176199Y1248688D03*
X171341Y1245341D03*
X162641D03*
X176199Y1258727D03*
X162641Y1255381D03*
Y1258727D03*
Y1252034D03*
X171341Y1248688D03*
X171947Y1255837D03*
X165546Y1273364D03*
X168346D03*
X176199Y1265420D03*
X162641D03*
Y1262074D03*
X176199D03*
X192341Y766798D03*
X184899Y770144D03*
X192341Y780184D03*
Y773491D03*
X184899Y783530D03*
Y776837D03*
X192341Y803609D03*
Y796916D03*
Y790223D03*
X184899Y800263D03*
Y793570D03*
X192341Y816995D03*
Y810302D03*
X184899Y820341D03*
Y813648D03*
Y806955D03*
X192341Y833727D03*
X191491Y827034D03*
X184899Y830381D03*
X192341Y847113D03*
Y840420D03*
X184899Y850459D03*
Y843766D03*
Y837074D03*
X191491Y863845D03*
X184899Y867192D03*
X192341Y853806D03*
X184899Y857152D03*
X192341Y883924D03*
Y877231D03*
Y870538D03*
X184899Y880577D03*
Y873885D03*
X192341Y900656D03*
Y890617D03*
X184899Y893963D03*
Y887270D03*
X192341Y914042D03*
Y907349D03*
X184899Y917389D03*
Y910696D03*
Y904003D03*
X191491Y927428D03*
X192341Y920735D03*
X184899Y930774D03*
Y924081D03*
X192341Y937467D03*
Y944160D03*
X184899Y947507D03*
Y940814D03*
X192341Y960892D03*
Y950853D03*
X184899Y964239D03*
Y954200D03*
X192341Y974278D03*
Y980971D03*
Y967585D03*
X184899Y977625D03*
Y970932D03*
X192341Y987664D03*
X184899Y991011D03*
Y984318D03*
X192341Y1027822D03*
Y1017782D03*
X184899Y1031168D03*
Y1024475D03*
Y1017782D03*
X192341Y1047900D03*
Y1041207D03*
Y1034515D03*
X184899Y1044554D03*
Y1037861D03*
X192341Y1054593D03*
Y1061286D03*
X184899Y1057940D03*
Y1051247D03*
Y1061286D03*
X192341Y1074672D03*
Y1067979D03*
X184899Y1078018D03*
Y1071326D03*
Y1064633D03*
X192341Y1091404D03*
X191491Y1084711D03*
X184899Y1094751D03*
Y1088058D03*
X192341Y1111483D03*
Y1104790D03*
Y1098097D03*
X184899Y1108137D03*
Y1101444D03*
X192341Y1128215D03*
Y1121522D03*
X184899Y1124869D03*
Y1114829D03*
X192341Y1141601D03*
Y1134908D03*
X184899Y1144948D03*
Y1138255D03*
Y1131562D03*
X191491Y1158333D03*
X192341Y1148294D03*
X184899Y1161680D03*
Y1151641D03*
X192341Y1171719D03*
Y1165026D03*
X184899Y1175066D03*
Y1168373D03*
X192341Y1185105D03*
Y1178412D03*
X184899Y1188452D03*
Y1181759D03*
X192341Y1208530D03*
Y1201837D03*
Y1195144D03*
X184899Y1205184D03*
Y1198491D03*
X192341Y1221916D03*
Y1215223D03*
X184899Y1225263D03*
Y1218570D03*
Y1211877D03*
X192341Y1238648D03*
X191491Y1231955D03*
X184899Y1241995D03*
Y1235302D03*
X184923Y1258871D03*
X192341Y1245341D03*
X184899Y1248688D03*
X192341Y1255381D03*
Y1258727D03*
Y1252034D03*
X192594Y1271262D03*
X192605Y1268774D03*
X182046Y1273364D03*
X179246D03*
X192341Y1265420D03*
Y1262074D03*
X188119Y1580678D03*
Y1575686D03*
Y1592590D03*
Y1587598D03*
X205899Y770144D03*
X201041Y766798D03*
X205799D03*
X205899Y783530D03*
Y776837D03*
X201041Y780184D03*
Y773491D03*
X205899Y800263D03*
Y793570D03*
X201041Y803609D03*
Y796916D03*
Y790223D03*
X205899Y813648D03*
Y806955D03*
X205049Y820341D03*
X201041Y816995D03*
Y810302D03*
X205049Y830381D03*
X201041Y833727D03*
Y827034D03*
X205899Y850459D03*
Y837074D03*
Y843766D03*
X201041Y847113D03*
Y840420D03*
X205049Y867192D03*
X201041Y863845D03*
X205049Y857152D03*
X201041Y853806D03*
X205899Y873885D03*
Y880577D03*
X201041Y883924D03*
Y877231D03*
Y870538D03*
X205899Y893963D03*
Y887270D03*
X201041Y900656D03*
Y890617D03*
X205899Y917389D03*
Y910696D03*
Y904003D03*
X201041Y914042D03*
Y907349D03*
X205049Y930774D03*
Y924081D03*
X201041Y927428D03*
Y920735D03*
X205899Y940814D03*
Y947507D03*
X201041Y937467D03*
Y944160D03*
X205899Y964239D03*
Y954200D03*
X201041Y960892D03*
Y950853D03*
Y957546D03*
Y954200D03*
X205899Y970932D03*
Y977625D03*
X201041Y974278D03*
Y980971D03*
Y967585D03*
X205899Y991011D03*
Y984318D03*
X201041Y987664D03*
Y994357D03*
X205899Y1031168D03*
Y1017782D03*
Y1024475D03*
X201041Y1027822D03*
Y1017782D03*
X205899Y1044554D03*
Y1037861D03*
X201041Y1047900D03*
Y1041207D03*
Y1034515D03*
X205899Y1057940D03*
Y1051247D03*
X201041Y1054593D03*
Y1061286D03*
X205049Y1078018D03*
X205899Y1071326D03*
Y1064633D03*
X201041Y1074672D03*
Y1067979D03*
X205899Y1094751D03*
X205049Y1088058D03*
X201041Y1091404D03*
Y1084711D03*
X205899Y1101444D03*
Y1108137D03*
X201041Y1111483D03*
Y1104790D03*
Y1098097D03*
X205899Y1114829D03*
Y1124869D03*
X201041Y1128215D03*
Y1121522D03*
X205899Y1144948D03*
Y1138255D03*
Y1131562D03*
X201041Y1141601D03*
Y1134908D03*
X205049Y1161680D03*
Y1151641D03*
X201041Y1158333D03*
Y1148294D03*
X205899Y1168373D03*
Y1175066D03*
X201041Y1171719D03*
Y1165026D03*
X205899Y1188452D03*
Y1181759D03*
X201041Y1185105D03*
Y1178412D03*
X205899Y1205184D03*
Y1198491D03*
X201041Y1208530D03*
Y1201837D03*
Y1195144D03*
X205049Y1225263D03*
X205899Y1211877D03*
Y1218570D03*
X201041Y1221916D03*
Y1215223D03*
X205899Y1241995D03*
X205049Y1235302D03*
X201041Y1238648D03*
Y1231955D03*
X205899Y1248688D03*
X201041Y1245341D03*
X205899Y1258727D03*
X201041Y1248688D03*
X201193Y1257900D03*
X206268Y1271348D03*
X206337Y1268720D03*
X205899Y1265420D03*
Y1262074D03*
X193075Y1580678D03*
Y1575686D03*
X200179D03*
X205135D03*
X200179Y1580678D03*
X205135D03*
X193075Y1592590D03*
Y1587598D03*
X200179Y1592590D03*
X205135D03*
X200179Y1587598D03*
X205135D03*
X198375Y1599884D03*
X193419D03*
X205479D03*
X193419Y1616788D03*
Y1611796D03*
X198375D03*
X193419Y1604876D03*
X198375D03*
Y1616788D03*
X205479Y1611796D03*
Y1604876D03*
Y1616788D03*
X222041Y766798D03*
X214599Y770144D03*
X222041Y780184D03*
Y773491D03*
X214599Y783530D03*
Y776837D03*
X222041Y803609D03*
Y796916D03*
Y790223D03*
X214599Y800263D03*
Y793570D03*
X222041Y810302D03*
X221191Y816995D03*
X214599Y813648D03*
Y806955D03*
X215449Y820341D03*
X222041Y833727D03*
X221191Y827034D03*
X215449Y830381D03*
X222041Y847113D03*
Y840420D03*
X214599Y850459D03*
Y837074D03*
Y843766D03*
X221191Y863845D03*
X215449Y867192D03*
X222041Y853806D03*
X215449Y857152D03*
X222041Y877231D03*
X221191Y870538D03*
X222041Y883924D03*
X214599Y873885D03*
Y880577D03*
X222041Y900656D03*
Y890617D03*
X214599Y893963D03*
Y887270D03*
X222041Y914042D03*
Y907349D03*
X214599Y917389D03*
Y910696D03*
Y904003D03*
X221241Y927428D03*
X222041Y920735D03*
X215449Y930774D03*
Y924081D03*
X222041Y944160D03*
X221191Y937467D03*
X214599Y940814D03*
Y947507D03*
X222041Y960892D03*
Y950853D03*
X214599Y964239D03*
Y954200D03*
X222041Y957546D03*
Y954200D03*
Y980971D03*
Y974278D03*
Y967585D03*
X214599Y970932D03*
Y977625D03*
Y991011D03*
Y984318D03*
X222041Y987664D03*
Y994357D03*
Y1027822D03*
Y1017782D03*
X214599Y1031168D03*
Y1017782D03*
Y1024475D03*
X222041Y1047900D03*
Y1041207D03*
Y1034515D03*
X214599Y1044554D03*
Y1037861D03*
X222041Y1054593D03*
Y1061286D03*
X214599Y1057940D03*
Y1051247D03*
X222041Y1067979D03*
X221191Y1074672D03*
X215449Y1078018D03*
X214599Y1071326D03*
Y1064633D03*
X222041Y1091404D03*
X221191Y1084711D03*
X214599Y1094751D03*
X215449Y1088058D03*
X222041Y1111483D03*
Y1098097D03*
Y1104790D03*
X214599Y1101444D03*
Y1108137D03*
X222041Y1128215D03*
Y1121522D03*
X214599Y1114829D03*
Y1124869D03*
X222041Y1141601D03*
X221191Y1134908D03*
X214599Y1144948D03*
Y1138255D03*
Y1131562D03*
X222041Y1158333D03*
X221191Y1148294D03*
X215449Y1161680D03*
Y1151641D03*
X222041Y1165026D03*
Y1171719D03*
X214599Y1168373D03*
Y1175066D03*
X222041Y1185105D03*
Y1178412D03*
X214599Y1188452D03*
Y1181759D03*
X222041Y1208530D03*
Y1201837D03*
Y1195144D03*
X214599Y1205184D03*
Y1198491D03*
X222041Y1221916D03*
Y1215223D03*
X215449Y1225263D03*
X214599Y1211877D03*
Y1218570D03*
X221191Y1231955D03*
Y1238648D03*
X214599Y1241995D03*
X215449Y1235302D03*
X222041Y1245341D03*
X214824Y1258711D03*
X214599Y1248688D03*
X222041Y1255381D03*
Y1252034D03*
X224987Y1273535D03*
X222041Y1265420D03*
Y1262074D03*
X212239Y1580678D03*
X217195D03*
Y1575686D03*
X212239D03*
X224299D03*
Y1580678D03*
X212239Y1587598D03*
X217195D03*
X212239Y1592590D03*
X217195D03*
X224299Y1587598D03*
Y1592590D03*
X210435Y1599884D03*
X222495D03*
X217539D03*
X210435Y1611796D03*
Y1604876D03*
Y1616788D03*
X222495D03*
X217539D03*
X222495Y1604876D03*
Y1611796D03*
X217539Y1604876D03*
Y1611796D03*
X235599Y770144D03*
X230741Y766798D03*
X235499D03*
X235599Y783530D03*
Y776837D03*
X230741Y780184D03*
Y773491D03*
X235599Y800263D03*
Y793570D03*
X230741Y803609D03*
Y796916D03*
Y790223D03*
X234749Y820341D03*
Y813648D03*
X235599Y806955D03*
X230741Y810302D03*
X231006Y817554D03*
X235599Y830381D03*
X230741Y833727D03*
X231591Y827034D03*
X235599Y850459D03*
Y837074D03*
Y843766D03*
X230741Y847113D03*
Y840420D03*
X234749Y867492D03*
X231591Y863845D03*
X234749Y857152D03*
X230741Y853806D03*
X235599Y874185D03*
Y880577D03*
X230741Y877231D03*
X231059Y871084D03*
X230741Y883924D03*
X235599Y893963D03*
Y887270D03*
X230741Y900656D03*
Y890617D03*
X235599Y917389D03*
Y910696D03*
Y904003D03*
X230741Y914042D03*
Y907349D03*
X235599Y930774D03*
Y924081D03*
X231541Y927428D03*
X230741Y920735D03*
X235599Y947507D03*
X234859Y940814D03*
X230741Y944660D03*
X231591Y937467D03*
X235599Y964239D03*
Y954200D03*
X230741Y960892D03*
Y950853D03*
X235599Y977625D03*
Y970932D03*
X230741Y980971D03*
Y974278D03*
Y967585D03*
X235599Y991011D03*
X230741Y987664D03*
X235599Y984318D03*
X236391Y1002557D03*
X240521Y1000395D03*
X237841Y1000437D03*
X233891Y1002557D03*
X231391D03*
X228891D03*
X235599Y1031168D03*
X230741Y1027822D03*
Y1017782D03*
X235599D03*
Y1024475D03*
Y1044554D03*
Y1037861D03*
X230741Y1047900D03*
Y1041207D03*
Y1034515D03*
X235599Y1051247D03*
Y1057940D03*
X230741Y1054593D03*
Y1061286D03*
X234749Y1078018D03*
X235599Y1071326D03*
Y1064633D03*
X230741Y1067979D03*
X231591Y1074672D03*
X235599Y1094751D03*
X234749Y1088058D03*
X230741Y1091404D03*
Y1084711D03*
X235599Y1108137D03*
Y1101444D03*
X230741Y1111483D03*
Y1098097D03*
Y1104790D03*
X234749Y1124869D03*
X235599Y1114829D03*
X230741Y1128215D03*
Y1121522D03*
X235599Y1144948D03*
Y1138255D03*
X234749Y1131562D03*
X230741Y1141601D03*
X231591Y1134908D03*
X235599Y1151641D03*
Y1161680D03*
X230741Y1158333D03*
X231591Y1148294D03*
X235599Y1175066D03*
Y1168373D03*
X230741Y1165026D03*
Y1171719D03*
X235599Y1188452D03*
Y1181759D03*
X230741Y1185105D03*
Y1178412D03*
X235599Y1205184D03*
Y1198491D03*
X230741Y1208530D03*
Y1201837D03*
Y1195144D03*
X234749Y1225263D03*
X235599Y1218570D03*
Y1211877D03*
X230741Y1221916D03*
Y1215223D03*
X235599Y1241995D03*
X235186Y1234977D03*
X231591Y1231955D03*
Y1238648D03*
X235599Y1248688D03*
X230741Y1245341D03*
X235599Y1258727D03*
X230741Y1248688D03*
X227746Y1273364D03*
X240966Y1273143D03*
X238971Y1274353D03*
X235480Y1265406D03*
X235599Y1262074D03*
X229255Y1575686D03*
Y1580678D03*
X236359D03*
Y1575686D03*
X241315Y1580678D03*
Y1575686D03*
X229255Y1587598D03*
Y1592590D03*
X236359D03*
Y1587598D03*
X241315Y1592590D03*
Y1587598D03*
X229599Y1599884D03*
X234555D03*
X229599Y1604876D03*
Y1611796D03*
X234555Y1604876D03*
Y1611796D03*
X229599Y1616788D03*
X234555D03*
X233268Y1679920D03*
Y1675383D03*
X241142Y1679320D03*
X233268Y1698627D03*
Y1694093D03*
Y1689556D03*
Y1684454D03*
X241142Y1683857D03*
Y1688391D03*
Y1693493D03*
Y1698030D03*
X233268Y1712800D03*
Y1708266D03*
Y1703729D03*
X241142Y1702564D03*
Y1707666D03*
Y1712203D03*
X233268Y1717903D03*
Y1722440D03*
Y1726974D03*
X241142Y1716737D03*
Y1730911D03*
Y1726377D03*
Y1721840D03*
X251741Y766798D03*
X244299Y770144D03*
X251741Y780184D03*
Y773491D03*
X244299Y783530D03*
Y776837D03*
X251741Y803609D03*
Y796916D03*
Y790223D03*
X244299Y800263D03*
Y793570D03*
X250891Y816995D03*
X251741Y810302D03*
X245149Y820341D03*
Y813648D03*
X244299Y806955D03*
X251741Y833727D03*
X250891Y827034D03*
X244299Y830381D03*
X251741Y847113D03*
Y840420D03*
X244299Y850459D03*
Y837074D03*
Y843766D03*
X250891Y863845D03*
Y853806D03*
X245149Y867192D03*
Y857152D03*
X251741Y870538D03*
Y883924D03*
Y877231D03*
X244299Y873885D03*
Y880577D03*
X250891Y900656D03*
X251741Y890617D03*
X244299Y893963D03*
Y887270D03*
X251741Y914042D03*
Y907349D03*
X244299Y917389D03*
Y910696D03*
Y904003D03*
X250891Y927428D03*
X251741Y920735D03*
X245149Y930774D03*
X244299Y924081D03*
X251741Y944160D03*
X250891Y937467D03*
X244299Y947507D03*
X245149Y940814D03*
X251741Y960892D03*
Y950853D03*
X244299Y964239D03*
Y954200D03*
X251741Y957546D03*
Y954200D03*
Y980971D03*
Y974278D03*
Y967585D03*
X244299Y977625D03*
Y970932D03*
X251741Y987664D03*
X244299Y991011D03*
Y984318D03*
X251741Y994357D03*
X254881Y999650D03*
X257561Y999608D03*
X244299Y1031168D03*
X251741Y1027822D03*
Y1017782D03*
X244299D03*
Y1024475D03*
X251741Y1047900D03*
Y1041207D03*
Y1034515D03*
X244299Y1044554D03*
Y1037861D03*
X251741Y1061286D03*
Y1054593D03*
X244299Y1051247D03*
Y1057940D03*
Y1061286D03*
X250891Y1074672D03*
Y1067979D03*
X245149Y1078018D03*
X244299Y1071326D03*
Y1064633D03*
X251741Y1091404D03*
Y1084711D03*
X244299Y1094751D03*
X245149Y1088058D03*
X251741Y1104790D03*
X250891Y1111483D03*
X251741Y1098097D03*
X244299Y1108137D03*
Y1101444D03*
X251741Y1128215D03*
X250891Y1121522D03*
X245149Y1124869D03*
X244299Y1114829D03*
X251741Y1134908D03*
Y1141601D03*
X244299Y1144948D03*
Y1138255D03*
X245149Y1131562D03*
X251741Y1158333D03*
Y1148294D03*
X244299Y1151641D03*
Y1161680D03*
X251741Y1171719D03*
Y1165026D03*
X244299Y1175066D03*
Y1168373D03*
X251741Y1185105D03*
Y1178412D03*
X244299Y1188452D03*
Y1181759D03*
X251741Y1208530D03*
Y1201837D03*
X250891Y1195144D03*
X244299Y1205184D03*
Y1198491D03*
X250891Y1221916D03*
X251741Y1215223D03*
X245149Y1225263D03*
X244299Y1218570D03*
Y1211877D03*
X250891Y1231955D03*
X244299Y1241995D03*
X245149Y1235302D03*
X251741Y1238648D03*
X244299Y1248688D03*
X251741Y1245341D03*
X248047Y1259155D03*
X250467Y1259175D03*
X251707Y1252034D03*
X244789Y1260093D03*
X254897Y1274040D03*
X257197Y1273640D03*
X249603Y1266204D03*
X251699Y1265254D03*
X248419Y1575686D03*
X253375D03*
X248419Y1580678D03*
X253375D03*
X248419Y1587598D03*
X253375D03*
X248419Y1592590D03*
X253375D03*
X246615Y1599884D03*
X241659D03*
X253719D03*
X241659Y1616788D03*
X246615D03*
Y1604876D03*
X241659D03*
X246615Y1611796D03*
X241659D03*
X253719Y1604876D03*
Y1611796D03*
Y1616788D03*
X249016Y1675383D03*
Y1679920D03*
X256890Y1679320D03*
X249016Y1684454D03*
Y1689556D03*
Y1694093D03*
Y1698627D03*
X256890Y1683857D03*
Y1688391D03*
Y1693493D03*
Y1698030D03*
X249016Y1703729D03*
Y1708266D03*
Y1712800D03*
X256890Y1702564D03*
Y1707666D03*
Y1712203D03*
X249016Y1726974D03*
Y1722440D03*
Y1717903D03*
X256890Y1716737D03*
Y1730911D03*
Y1726377D03*
Y1721840D03*
X272529Y111053D03*
X265442D03*
X261899D03*
Y108553D03*
X265442D03*
X268985Y111053D03*
Y108553D03*
X272529D03*
X260441Y766798D03*
Y780184D03*
Y773491D03*
Y803609D03*
Y796916D03*
Y790223D03*
X261291Y816995D03*
X260441Y810302D03*
Y833727D03*
X261291Y827034D03*
X260441Y847113D03*
Y840420D03*
X261291Y863845D03*
Y853806D03*
X260441Y870538D03*
Y883924D03*
Y877231D03*
Y900656D03*
Y890617D03*
Y914042D03*
Y907349D03*
X261291Y927428D03*
X260441Y920735D03*
Y944160D03*
X261291Y937467D03*
X260441Y960892D03*
Y950853D03*
Y980971D03*
Y974278D03*
Y967585D03*
Y987664D03*
Y1027822D03*
Y1017782D03*
Y1047900D03*
Y1041207D03*
Y1034515D03*
Y1061286D03*
Y1054593D03*
Y1057940D03*
X261291Y1074672D03*
Y1067979D03*
X260441Y1091404D03*
Y1084711D03*
Y1104790D03*
X261291Y1111483D03*
X260441Y1098097D03*
Y1128215D03*
X261291Y1121522D03*
X260441Y1134908D03*
Y1141601D03*
Y1158333D03*
Y1148294D03*
Y1171719D03*
Y1165026D03*
Y1185105D03*
Y1178412D03*
Y1208530D03*
Y1201837D03*
Y1195144D03*
X261291Y1221916D03*
X260441Y1215223D03*
X261291Y1231955D03*
X260441Y1238648D03*
Y1245341D03*
Y1248688D03*
X260479Y1580678D03*
X265435D03*
X260479Y1575592D03*
X265435D03*
X272539Y1575686D03*
Y1580678D03*
X260479Y1592590D03*
X265435D03*
X260479Y1587598D03*
X265435D03*
X272539D03*
Y1592590D03*
X258675Y1599884D03*
X270735Y1599790D03*
X265779D03*
X258675Y1604876D03*
Y1611796D03*
Y1616788D03*
X270735D03*
X265779D03*
X270735Y1611796D03*
Y1604876D03*
X265779D03*
Y1611796D03*
X264764Y1675383D03*
Y1679920D03*
X272638Y1679320D03*
X264764Y1684454D03*
Y1689556D03*
Y1694093D03*
Y1698627D03*
X272638Y1683857D03*
Y1688391D03*
Y1693493D03*
Y1698030D03*
X264764Y1703729D03*
Y1708266D03*
Y1712800D03*
X272638Y1702564D03*
Y1707666D03*
Y1712203D03*
X264764Y1726974D03*
Y1722440D03*
Y1717903D03*
X272638Y1716737D03*
Y1730911D03*
Y1726377D03*
Y1721840D03*
X277495Y1575686D03*
Y1580678D03*
X284599D03*
X289555D03*
Y1575686D03*
X284599D03*
X277495Y1587598D03*
Y1592590D03*
X284599D03*
X289555D03*
X284599Y1587598D03*
X289555D03*
X282795Y1599884D03*
X277839D03*
X289899D03*
X282795Y1604876D03*
Y1611796D03*
X277839D03*
Y1604876D03*
X282795Y1616788D03*
X277839D03*
X289899D03*
Y1604876D03*
Y1611796D03*
X280512Y1675383D03*
Y1679920D03*
Y1684454D03*
Y1689556D03*
Y1694093D03*
Y1698627D03*
Y1703729D03*
Y1708266D03*
Y1712800D03*
Y1726974D03*
Y1722440D03*
Y1717903D03*
X296659Y1575686D03*
X301615D03*
X296659Y1580678D03*
X301615D03*
X296659Y1587598D03*
X301615D03*
X296659Y1592590D03*
X301615D03*
X294855Y1599884D03*
X301959D03*
X294855Y1616788D03*
Y1604876D03*
Y1611796D03*
X301959Y1604876D03*
Y1611796D03*
Y1616788D03*
X300197Y1679920D03*
Y1675383D03*
Y1698627D03*
Y1694093D03*
Y1689556D03*
Y1684454D03*
Y1712800D03*
Y1708266D03*
Y1703729D03*
Y1717903D03*
Y1722440D03*
Y1726974D03*
X308719Y1580678D03*
X313675D03*
X308719Y1575686D03*
X313675D03*
X320779D03*
Y1580678D03*
X308719Y1592590D03*
X313675D03*
X308719Y1587598D03*
X313675D03*
X320779D03*
Y1592590D03*
X306915Y1599884D03*
X318975D03*
X314019D03*
X306915Y1604876D03*
Y1611796D03*
Y1616788D03*
X318975D03*
X314019D03*
X318975Y1604876D03*
Y1611796D03*
X314019Y1604876D03*
Y1611796D03*
X308071Y1679320D03*
X315945Y1679920D03*
Y1675383D03*
X308071Y1683857D03*
Y1698030D03*
Y1693493D03*
Y1688391D03*
X315945Y1698627D03*
Y1694093D03*
Y1689556D03*
Y1684454D03*
X308071Y1702564D03*
Y1712203D03*
Y1707666D03*
X315945Y1712800D03*
Y1708266D03*
Y1703729D03*
X308071Y1716737D03*
Y1721840D03*
Y1726377D03*
Y1730911D03*
X315945Y1717903D03*
Y1722440D03*
Y1726974D03*
X338042Y849978D03*
X337778Y854584D03*
X335924Y857789D03*
X334079Y880219D03*
X332228Y877014D03*
X335928D03*
X334078Y893036D03*
X335928Y896240D03*
X332229Y902649D03*
X332228Y915466D03*
X335928D03*
X332229Y921875D03*
Y941100D03*
X332228Y934692D03*
X335928D03*
X334079Y957122D03*
X335928Y953917D03*
X332228D03*
X332229Y973143D03*
X334079Y976347D03*
X331284Y978814D03*
X335349Y985939D03*
X338210Y996480D03*
X332661Y1006093D03*
X338211Y1002888D03*
X332661Y1025318D03*
Y1018910D03*
X338211Y1015705D03*
X332661Y1044544D03*
X334511Y1041340D03*
X333834Y1062790D03*
X329632Y1092168D03*
X336360Y1082995D03*
X338211Y1111834D03*
X335344Y1097289D03*
X338211Y1124651D03*
X336361Y1115039D03*
Y1127856D03*
X338211Y1118243D03*
Y1131060D03*
X325735Y1575686D03*
Y1580678D03*
X332839D03*
X337795D03*
X332839Y1575686D03*
X337795D03*
X325735Y1587598D03*
Y1592590D03*
X332839D03*
X337795D03*
X332839Y1587598D03*
X337795D03*
X326079Y1599884D03*
X331035D03*
X338139D03*
X326079Y1604876D03*
Y1611796D03*
X331035Y1604876D03*
Y1611796D03*
X326079Y1616788D03*
X331035D03*
X338139D03*
Y1604876D03*
Y1611796D03*
X323819Y1679320D03*
X331693Y1679920D03*
Y1675383D03*
X323819Y1683857D03*
Y1698030D03*
Y1693493D03*
Y1688391D03*
X331693Y1698627D03*
Y1694093D03*
Y1689556D03*
Y1684454D03*
X323819Y1702564D03*
Y1712203D03*
Y1707666D03*
X331693Y1712800D03*
Y1708266D03*
Y1703729D03*
X323819Y1716737D03*
Y1721840D03*
Y1726377D03*
Y1730911D03*
X331693Y1717903D03*
Y1722440D03*
Y1726974D03*
X345178Y854584D03*
X347028Y844971D03*
X345178Y848176D03*
X350727Y844971D03*
X347027Y851380D03*
X343327D03*
X354429D03*
X341478Y854584D03*
X339628Y857789D03*
X347029Y864197D03*
Y857789D03*
X348878Y854584D03*
X345179Y860993D03*
X343327Y857789D03*
X352579Y854584D03*
X354429Y864197D03*
X350729D03*
X348879Y867401D03*
X352579D03*
X348879Y860993D03*
X347029Y870606D03*
X354429Y877014D03*
X339629D03*
X345179Y880219D03*
Y873810D03*
X343329Y877014D03*
X352579Y880219D03*
X350729Y877014D03*
X339629Y883423D03*
X347029D03*
X350729D03*
X348879Y873810D03*
X347029Y877014D03*
X348878Y880219D03*
X352578Y899445D03*
X339629Y896240D03*
Y889832D03*
X348879Y886627D03*
X347029Y889832D03*
X345179Y893036D03*
X343328Y896240D03*
X352578Y893036D03*
Y886627D03*
X345179Y899445D03*
X348878Y905853D03*
X352578D03*
X347029Y909057D03*
Y902649D03*
X345179Y912262D03*
X352578D03*
X339629Y915466D03*
X343329D03*
X348878Y925079D03*
X352578D03*
Y918670D03*
X347029Y928283D03*
Y921875D03*
X345179Y918670D03*
Y931488D03*
X352578D03*
Y944304D03*
X347029Y941100D03*
X348878Y944304D03*
X347029Y947509D03*
X352578Y937896D03*
X339629Y934692D03*
X345179Y937896D03*
X343328Y934692D03*
X348878Y963530D03*
X347029Y960326D03*
X339629Y966735D03*
Y953917D03*
X343328D03*
X345179Y957122D03*
X352578D03*
X347029Y966735D03*
X352578Y963530D03*
X345179Y950713D03*
X352578D03*
X354428Y973143D03*
X339629D03*
X345179Y976347D03*
Y969939D03*
X350729Y973143D03*
X347029Y979552D03*
X352579Y976347D03*
X352578Y969939D03*
X348878Y982756D03*
X352578D03*
X339629Y979552D03*
X343329Y973143D03*
X347461Y999684D03*
X345611Y1009297D03*
X343761Y1006093D03*
X345611Y1002888D03*
X351162Y1006093D03*
X354861D03*
X353011Y1009297D03*
Y1002888D03*
X347461Y1012501D03*
X343761Y999684D03*
X353011Y1028523D03*
Y1015705D03*
X341911D03*
X349311D03*
X347461Y1018910D03*
X345611Y1028523D03*
Y1022114D03*
X353011D03*
X347461Y1031727D03*
X353011Y1034931D03*
Y1047749D03*
X349311Y1034931D03*
X347461Y1038136D03*
X345611Y1041340D03*
X343761Y1044544D03*
X353011Y1041340D03*
X345611Y1047749D03*
X349311Y1054157D03*
X353011Y1060565D03*
Y1054157D03*
X347461Y1050952D03*
Y1057361D03*
X345611Y1060565D03*
X343761Y1063770D03*
X353011Y1073383D03*
X340062Y1076587D03*
X347461D03*
Y1070178D03*
X349312Y1073383D03*
X345611Y1066974D03*
X353011D03*
X345611Y1079791D03*
X353011D03*
Y1086200D03*
X349310Y1092609D03*
X347461Y1089404D03*
X345610Y1086200D03*
X343760Y1082995D03*
X343707Y1091513D03*
X353011Y1092608D03*
X347461Y1108630D03*
X354861D03*
X353011Y1099017D03*
X340061Y1108630D03*
Y1102221D03*
X349311Y1099017D03*
X347461Y1102221D03*
X343761D03*
X349311Y1105426D03*
X340061Y1115039D03*
X349311Y1124651D03*
X349312Y1118243D03*
X345611D03*
X343761Y1115039D03*
X341911Y1124651D03*
X354861Y1115039D03*
X351161Y1121447D03*
Y1115039D03*
X351162Y1127856D03*
X353011Y1118243D03*
X354861Y1121447D03*
X345611Y1137469D03*
Y1131060D03*
X349311D03*
X343761Y1134264D03*
X353011Y1137469D03*
Y1131060D03*
X347461Y1134264D03*
X354861D03*
X344899Y1575686D03*
X349855D03*
X344899Y1580678D03*
X349855D03*
X344899Y1587598D03*
X349855D03*
X344899Y1592590D03*
X349855D03*
X343095Y1599884D03*
X355155D03*
X350199D03*
X343095Y1616788D03*
Y1604876D03*
Y1611796D03*
X355155Y1604876D03*
Y1611796D03*
X350199Y1604876D03*
Y1611796D03*
X355155Y1616788D03*
X350199D03*
X339567Y1679320D03*
X347441Y1679920D03*
Y1675383D03*
X355315Y1679320D03*
X339567Y1683857D03*
Y1698030D03*
Y1693493D03*
Y1688391D03*
X347441Y1698627D03*
Y1694093D03*
Y1689556D03*
Y1684454D03*
X355315Y1683857D03*
Y1698030D03*
Y1693493D03*
Y1688391D03*
X339567Y1702564D03*
Y1712203D03*
Y1707666D03*
X347441Y1712800D03*
Y1708266D03*
Y1703729D03*
X355315Y1702564D03*
Y1712203D03*
Y1707666D03*
X339567Y1716737D03*
Y1721840D03*
Y1726377D03*
Y1730911D03*
X347441Y1717903D03*
Y1722440D03*
Y1726974D03*
X355315Y1716737D03*
Y1721840D03*
Y1726377D03*
Y1730911D03*
X359979Y841467D03*
X367379D03*
X365529Y851380D03*
X361829D03*
X358129D03*
X369229D03*
X356278Y848176D03*
X371078D03*
X363678D03*
X365529Y864197D03*
X361829D03*
X359979Y854584D03*
X358129Y864197D03*
X369229D03*
X367379Y854584D03*
X359979Y867401D03*
X367379D03*
X356278Y860993D03*
X371078D03*
X363678D03*
X365529Y877014D03*
X361829D03*
X359979Y880219D03*
X358129Y877014D03*
X369229D03*
X367379Y880219D03*
X371078Y873810D03*
X356278D03*
X363678D03*
X356278Y886627D03*
X365529Y896240D03*
Y889832D03*
X361828Y896240D03*
X361829Y889832D03*
X359979Y893036D03*
X358128Y889832D03*
X369229Y896240D03*
Y889832D03*
X359979Y899445D03*
X371078D03*
X363679Y893036D03*
X367379D03*
X363678Y886627D03*
X371078D03*
X356278Y905853D03*
X365529Y909057D03*
Y902649D03*
X359978Y912262D03*
X358128Y909057D03*
X358129Y902649D03*
X371079Y912262D03*
X365529Y915466D03*
X361828D03*
X369229D03*
X356279Y925079D03*
X365529Y928283D03*
Y921875D03*
X359979Y918670D03*
X358128Y928283D03*
X358129Y921875D03*
X371078Y918670D03*
X359978Y931488D03*
X371079D03*
X358128Y947509D03*
X358129Y941100D03*
X356279Y944304D03*
X365529Y947509D03*
Y941100D03*
Y934691D03*
X361828D03*
X359979Y937896D03*
X369229Y934691D03*
X371078Y937896D03*
X356279Y963530D03*
X358129Y960326D03*
X359979Y957122D03*
X358128Y966735D03*
X361829Y953917D03*
X359978Y950713D03*
X371078Y957122D03*
X371079Y950713D03*
X365529Y953917D03*
X367378Y963530D03*
X363679D03*
X365529Y960326D03*
X365528Y966735D03*
X369229Y953917D03*
X359979Y976347D03*
X358129Y979552D03*
X359978Y969939D03*
X361828Y973143D03*
X356279Y982756D03*
X371078Y976347D03*
X371079Y969939D03*
X369229Y973143D03*
X365529Y979552D03*
Y973143D03*
X365962Y999684D03*
Y1006093D03*
X362261D03*
X360411Y1009297D03*
X360412Y1002888D03*
X358562Y999684D03*
X369662Y1006093D03*
X371512Y1009297D03*
X365961Y1012501D03*
X358561D03*
X356712Y1015705D03*
X365962Y1025318D03*
Y1018910D03*
X364112Y1015705D03*
X360411Y1028523D03*
X362261Y1025318D03*
X360412Y1022114D03*
X358562Y1018910D03*
X369662Y1025318D03*
X367811Y1015705D03*
X371511Y1028523D03*
Y1022114D03*
X365962Y1031727D03*
X358561D03*
X356712Y1034931D03*
X365962Y1044544D03*
Y1038136D03*
X362261Y1044544D03*
X360412Y1041340D03*
X358562Y1038136D03*
X369662Y1044544D03*
X371511Y1041340D03*
X360411Y1047749D03*
X371511D03*
X356712Y1054157D03*
X365962Y1057361D03*
Y1050952D03*
X360412Y1060565D03*
X358562Y1057361D03*
X358561Y1050952D03*
X371511Y1060565D03*
X365962Y1063770D03*
X362261D03*
X369662D03*
X356712Y1073383D03*
X365962Y1070178D03*
Y1076587D03*
X360411Y1066974D03*
X358561Y1070178D03*
X358562Y1076587D03*
X371512Y1066974D03*
X360412Y1079791D03*
X371511D03*
X365962Y1089404D03*
Y1082995D03*
X362261D03*
X360411Y1086200D03*
X358561Y1089404D03*
X356712Y1092608D03*
X369662Y1082995D03*
X371512Y1086200D03*
X365962Y1095813D03*
X358561D03*
X365962Y1102221D03*
X362262D03*
X360411Y1099017D03*
X356711Y1105426D03*
Y1099017D03*
X371512Y1105426D03*
Y1099017D03*
X364112Y1111834D03*
X356712D03*
X371512D03*
X367811Y1105426D03*
X369661Y1102221D03*
X358562D03*
X360412Y1105426D03*
X364111Y1118243D03*
X362261Y1115039D03*
X360411Y1118243D03*
X356711D03*
X367811D03*
X371511D03*
X365962Y1127856D03*
X358561D03*
X369662Y1121447D03*
X362261D03*
X365961Y1140973D03*
X364112Y1131060D03*
X360412D03*
X358561Y1140973D03*
X356712Y1131060D03*
X367811D03*
X371511D03*
X369662Y1134264D03*
X362262D03*
X356959Y1580678D03*
X361915D03*
X356959Y1575592D03*
X361915D03*
X369019Y1575686D03*
Y1580678D03*
X356959Y1592590D03*
X361915D03*
X356959Y1587598D03*
X361915D03*
X367215Y1599790D03*
X362259D03*
X369019Y1587598D03*
Y1592590D03*
X367215Y1616788D03*
X362259D03*
X367215Y1604876D03*
Y1611796D03*
X362259Y1604876D03*
Y1611796D03*
X382179Y841467D03*
X374779D03*
X380329Y851380D03*
X376629D03*
X372929D03*
X384029D03*
X387729D03*
X385878Y848176D03*
X378478D03*
X382179Y854584D03*
X380329Y864197D03*
X376629D03*
X374779Y854584D03*
X372929Y864197D03*
X384029D03*
X387729D03*
X382179Y867401D03*
X374779D03*
X378478Y860993D03*
X385878D03*
X382179Y880219D03*
X380329Y877014D03*
X376629D03*
X374779Y880219D03*
X372929Y877014D03*
X384029D03*
X387729D03*
X378478Y873810D03*
X385878D03*
X380329Y889832D03*
X378479Y893036D03*
X376629Y889832D03*
X372929D03*
X384029D03*
X387729Y896240D03*
Y889832D03*
X378478Y899445D03*
X385879D03*
X378478Y886627D03*
X385878D03*
X382179Y905853D03*
X378478Y912262D03*
Y905853D03*
X374778D03*
X372929Y909057D03*
X372928Y902649D03*
X385878Y912262D03*
X384028Y909057D03*
X384029Y902649D03*
X387728Y915466D03*
X382179Y925079D03*
X378478D03*
Y918670D03*
X374778Y925079D03*
X372929Y928283D03*
X372928Y921875D03*
X385879Y918670D03*
X384028Y928283D03*
X384029Y921875D03*
X378478Y931488D03*
X385878D03*
X384029Y941100D03*
X384028Y947509D03*
X374778Y944304D03*
X372929Y947509D03*
X372928Y941100D03*
X382179Y944304D03*
X378478D03*
Y937896D03*
X385879D03*
X387728Y934691D03*
X387729Y953917D03*
X372928Y960326D03*
X374778Y963530D03*
X372929Y966735D03*
X382179Y963530D03*
X378478D03*
Y957122D03*
X384029Y960326D03*
X385879Y957122D03*
X384028Y966735D03*
X385878Y950713D03*
X378478D03*
X387728Y973143D03*
X376629D03*
X380328D03*
X378479Y976347D03*
X378478Y969939D03*
X385879Y976347D03*
X384029Y979552D03*
X385878Y969939D03*
X374778Y982756D03*
X382179D03*
X378478D03*
X372928Y979552D03*
X375210Y996480D03*
X373361Y999684D03*
X378911Y1009297D03*
Y1002888D03*
X386311Y1009297D03*
X386312Y1002888D03*
X384462Y999684D03*
X373362Y1012501D03*
X384461D03*
X382612Y1015705D03*
X378911Y1028523D03*
Y1022114D03*
Y1015705D03*
X375211D03*
X373361Y1018910D03*
X386311Y1028523D03*
X386312Y1022114D03*
X384462Y1018910D03*
X373362Y1031727D03*
X384461D03*
X382612Y1034931D03*
X378911Y1041340D03*
Y1034931D03*
X375211D03*
X373361Y1038136D03*
X386312Y1041340D03*
X384462Y1038136D03*
X378911Y1047749D03*
X386311D03*
X382612Y1054157D03*
X378911Y1060565D03*
Y1054157D03*
X375211D03*
X373361Y1057361D03*
X373362Y1050952D03*
X386312Y1060565D03*
X384462Y1057361D03*
X384461Y1050952D03*
X382612Y1073383D03*
X378911D03*
Y1066974D03*
X375211Y1073383D03*
X373361Y1076587D03*
X373362Y1070178D03*
X386311Y1066974D03*
X384462Y1076587D03*
X384461Y1070178D03*
X378911Y1079791D03*
X386311D03*
X382611Y1092608D03*
X378911D03*
Y1086200D03*
X375211Y1092608D03*
X373362Y1089404D03*
X386311Y1086200D03*
X384461Y1089404D03*
X373362Y1095813D03*
X384462D03*
X375211Y1099017D03*
X380762Y1095813D03*
Y1108630D03*
X378911Y1099017D03*
X377062Y1102221D03*
X373361Y1108630D03*
Y1102221D03*
X386312Y1099017D03*
X384462Y1102221D03*
X382611Y1099017D03*
Y1118243D03*
X378911D03*
X377061Y1115039D03*
X375211Y1118243D03*
X373361Y1115039D03*
X386311Y1118243D03*
X384461Y1115039D03*
X380761Y1127856D03*
X373361D03*
X384462Y1121447D03*
X377062D03*
X382611Y1131060D03*
X380761Y1140973D03*
X378911Y1131060D03*
X375211D03*
X373361Y1140973D03*
X386311Y1131060D03*
X384462Y1134264D03*
X377062D03*
X380930Y1531402D03*
X384210Y1534152D03*
X373975Y1575686D03*
Y1580678D03*
Y1587598D03*
Y1592590D03*
X379275Y1599884D03*
X374319D03*
X379275Y1604876D03*
Y1611796D03*
X374319Y1604876D03*
Y1611796D03*
X379275Y1616788D03*
X374319D03*
X396979Y841467D03*
X389579D03*
X398829Y851380D03*
X395129D03*
X391429D03*
X402529D03*
X400678Y848176D03*
X393278D03*
X398829Y864197D03*
X396979Y854584D03*
X395129Y864197D03*
X391429D03*
X389579Y854584D03*
X402529Y864197D03*
X396979Y867401D03*
X389579D03*
X400678Y860993D03*
X393278D03*
X398829Y877014D03*
X396979Y880219D03*
X395129Y877014D03*
X391429D03*
X389579Y880219D03*
X402529Y877014D03*
X393278Y873810D03*
X400678D03*
X398829Y889832D03*
X395129Y896240D03*
Y889832D03*
X391428Y896240D03*
X391429Y889832D03*
X389579Y893036D03*
X402529Y889832D03*
X396978Y899445D03*
X402529Y896240D03*
X400678Y899445D03*
X393279Y893036D03*
X396979D03*
X398829Y896240D03*
X400678Y893036D03*
X393278Y886627D03*
X400678D03*
X404378Y899445D03*
X398829Y909057D03*
X398828Y902649D03*
X396979Y912262D03*
X391429Y909057D03*
Y902649D03*
X395129Y915466D03*
X391429D03*
X400678Y905853D03*
X402529Y915466D03*
Y909057D03*
X406229Y915466D03*
X400678Y912262D03*
X402529Y902649D03*
X400678Y931488D03*
X402529Y928283D03*
Y921875D03*
X398829Y928283D03*
X398828Y921875D03*
X396978Y918670D03*
X391429Y928283D03*
Y921875D03*
X400678Y925079D03*
X396979Y931488D03*
X398829Y934691D03*
X402529D03*
X398828Y941100D03*
X396978Y937896D03*
X395129Y934691D03*
X391429Y941100D03*
Y934691D03*
X400678Y937896D03*
X398829Y947509D03*
X391429D03*
X402529Y941100D03*
X400679Y944304D03*
X402529Y947509D03*
X398828Y960326D03*
X396978Y957122D03*
X396979Y950713D03*
X395129Y953917D03*
X391429Y960326D03*
Y953917D03*
X400678Y957122D03*
X398829Y966735D03*
X391429D03*
X400678Y963530D03*
X402529Y966735D03*
Y960326D03*
X398829Y953917D03*
X402529D03*
X400680Y950713D03*
X398828Y979552D03*
X396978Y976347D03*
X396979Y969939D03*
X395129Y973143D03*
X391429Y979552D03*
Y973143D03*
X400678Y982756D03*
Y969939D03*
X397412Y1009297D03*
X397411Y1002888D03*
X395562Y1006093D03*
X391862D03*
Y999684D03*
X388161Y1006093D03*
X401111Y1002888D03*
X399262Y1012501D03*
X391861D03*
X399262Y1006093D03*
X402962D03*
X399262Y999684D03*
X402962D03*
X401111Y1009297D03*
X402962Y1012501D03*
Y1031727D03*
X399261Y1018910D03*
X397411Y1028523D03*
Y1022114D03*
X395562Y1025318D03*
X393711Y1015705D03*
X391862Y1025318D03*
Y1018910D03*
X390012Y1015705D03*
X388161Y1025318D03*
X399262Y1031727D03*
X391862D03*
X401111Y1028523D03*
Y1022114D03*
X402960Y1018910D03*
X402962Y1025318D03*
X399262D03*
X401111Y1015705D03*
X399261Y1038136D03*
X397411Y1041340D03*
X395562Y1044544D03*
X391862D03*
Y1038136D03*
X388161Y1044544D03*
X397411Y1047749D03*
X401111D03*
X399262Y1044544D03*
X402962D03*
X401111Y1041340D03*
X402962Y1038136D03*
X406662Y1057361D03*
X399261D03*
X399262Y1050952D03*
X397411Y1060565D03*
X391862Y1057361D03*
Y1050952D03*
X395562Y1063770D03*
X391862D03*
X388161D03*
X402962Y1057361D03*
Y1063770D03*
X401113Y1060565D03*
X399262Y1063770D03*
X401111Y1054157D03*
X402962Y1050952D03*
Y1076587D03*
Y1070178D03*
X399261Y1076587D03*
X399262Y1070178D03*
X397412Y1066974D03*
X391862Y1076587D03*
Y1070178D03*
X401111Y1073383D03*
X397411Y1079791D03*
X401111D03*
X401112Y1066974D03*
X399262Y1089404D03*
X397412Y1086200D03*
X395562Y1082995D03*
X391862Y1089404D03*
Y1082995D03*
X388161D03*
X401112Y1092608D03*
X401111Y1086200D03*
X399261Y1095813D03*
X391862D03*
X402962D03*
X399262Y1082995D03*
Y1102221D03*
X397412Y1099017D03*
X395562Y1102221D03*
X390011Y1105426D03*
X388162Y1108630D03*
Y1102221D03*
X401111Y1105426D03*
X397411Y1111834D03*
X390011D03*
X391862Y1102221D03*
X393711Y1105426D03*
X397411Y1118243D03*
X395561Y1115039D03*
X393711Y1118243D03*
X390011D03*
X388161Y1115039D03*
X401111Y1118243D03*
X395561Y1127856D03*
X388161D03*
X402961D03*
X391862Y1121447D03*
X399262D03*
X397411Y1131060D03*
X395561Y1140973D03*
X393711Y1131060D03*
X390011D03*
X388161Y1140973D03*
X402961D03*
X401111Y1131060D03*
X391862Y1134264D03*
X399262D03*
X419179Y841467D03*
X404379D03*
X411779D03*
X413629Y851380D03*
X409929D03*
X406229D03*
X417329D03*
X408078Y848176D03*
X415478D03*
X404379Y854584D03*
X413629Y864197D03*
X411779Y854584D03*
X409929Y864197D03*
X406229D03*
X419179Y854584D03*
X417329Y864197D03*
X404379Y867401D03*
X411779D03*
X419179D03*
X415478Y860993D03*
X408078D03*
X404379Y880219D03*
X413629Y877014D03*
X411779Y880219D03*
X409929Y877014D03*
Y870606D03*
X406229Y877014D03*
X419179Y880219D03*
X417329Y877014D03*
X415478Y873810D03*
X408078D03*
X413629Y889832D03*
X411779Y893036D03*
X409929Y889832D03*
X408079Y893036D03*
X406229Y889832D03*
X419179Y893036D03*
X417329Y889832D03*
X404378Y893036D03*
X415478Y886627D03*
X408078D03*
X406229Y896240D03*
X408078Y899445D03*
X415478D03*
X409929Y896240D03*
X415478Y893036D03*
X417329Y896240D03*
X422878Y893036D03*
X411778Y899445D03*
X413629Y896240D03*
X419178Y899445D03*
X422878Y912262D03*
X413629Y902649D03*
X409929Y909057D03*
Y902649D03*
X404378Y912262D03*
Y905853D03*
X419178Y912262D03*
X419179Y905853D03*
X417329Y902649D03*
X409929Y915466D03*
X417329Y909057D03*
X406229D03*
X413629D03*
Y915466D03*
X411778Y905853D03*
X408078D03*
Y912262D03*
X406229Y902649D03*
X415478Y905853D03*
X411778Y912262D03*
X415478D03*
X417329Y915466D03*
X411779Y918670D03*
X406229Y921875D03*
X409929D03*
X404378Y918670D03*
X418229Y926896D03*
X419178Y918670D03*
X405048Y930812D03*
X408078Y918670D03*
X408569Y929108D03*
X406308Y928626D03*
X417329Y921875D03*
X411872Y925264D03*
X415479Y918670D03*
X405145Y946239D03*
Y948539D03*
X414093Y942098D03*
X405048Y938046D03*
Y935746D03*
X416393Y942098D03*
X418693D03*
X407589Y942164D03*
X405289D03*
X409889D03*
X405122Y965896D03*
Y963596D03*
X415185Y956620D03*
X411685D03*
X409385D03*
X417685D03*
X414365Y971140D03*
X416755D03*
X404861Y981269D03*
Y978969D03*
X404785Y971100D03*
X407085D03*
X409385D03*
X411685D03*
X420205D03*
X404861Y986421D03*
X405101Y992971D03*
Y995271D03*
X404861Y988721D03*
X415185Y985580D03*
X417575D03*
X412365Y985610D03*
X410065D03*
X420145Y985550D03*
X415185Y1014540D03*
X417575D03*
X405227Y1007156D03*
X405231Y1004848D03*
X417575Y1000060D03*
X415185D03*
X409385Y1014540D03*
X407085D03*
X411685D03*
X412385Y1000080D03*
X410085D03*
X420215Y1000040D03*
X420405Y1014470D03*
X404986Y1022427D03*
X404998Y1026821D03*
X414461Y1028855D03*
X411961D03*
X416961D03*
X419461D03*
X408325Y1031971D03*
Y1034271D03*
X408511Y1041340D03*
X417762Y1044544D03*
X412211Y1047749D03*
X404811D03*
X415911D03*
X419611D03*
X406662Y1044544D03*
X410362D03*
X408511Y1047749D03*
X414062Y1044544D03*
X404811Y1041340D03*
X412211D03*
X415911D03*
X419611D03*
X406662Y1050952D03*
X415911Y1060565D03*
Y1054157D03*
X412211Y1060565D03*
X410361Y1050952D03*
X408511Y1054157D03*
X404811Y1060565D03*
X417761Y1050952D03*
X414060D03*
X417762Y1057361D03*
X421462Y1050952D03*
X419611Y1054157D03*
X406662Y1063770D03*
X408511Y1060565D03*
X410362Y1063770D03*
X412211Y1054157D03*
X404811D03*
X414062Y1057361D03*
X410362D03*
X417762Y1063770D03*
X414062D03*
X419611Y1060565D03*
Y1079791D03*
X408511Y1073383D03*
X406662Y1070178D03*
X404811Y1073383D03*
X415911Y1066974D03*
X410362Y1076587D03*
Y1070178D03*
X406661Y1076587D03*
X404811Y1066974D03*
X419611Y1073383D03*
X412211Y1079791D03*
X404811D03*
X417762Y1076587D03*
X408511Y1066974D03*
X415911Y1079791D03*
X412211Y1073383D03*
X415911D03*
X414062Y1070178D03*
X417762D03*
X412211Y1066974D03*
X419611D03*
X415911Y1092608D03*
X415912Y1086200D03*
X412211Y1092608D03*
X408511Y1086200D03*
X417761Y1089404D03*
Y1082995D03*
X410362Y1095813D03*
X406662D03*
X419612Y1099017D03*
X404811Y1092608D03*
X417762Y1095813D03*
X414061D03*
X415912Y1099017D03*
X414062Y1108630D03*
X412211Y1099017D03*
X410362Y1102221D03*
X406661Y1108630D03*
Y1102221D03*
X404812Y1105426D03*
X417762Y1102221D03*
X404812Y1111834D03*
X415911Y1118243D03*
X414061Y1121447D03*
X412211Y1124651D03*
Y1118243D03*
X410361Y1115039D03*
X408511Y1118243D03*
X406661Y1115039D03*
X404811Y1118243D03*
X417761Y1115039D03*
X410361Y1127856D03*
X415912Y1124651D03*
X419612D03*
Y1118243D03*
X417761Y1121447D03*
Y1127856D03*
X406661Y1121447D03*
X414062Y1127856D03*
Y1134264D03*
X412212Y1131060D03*
X410361Y1140973D03*
X408511Y1131060D03*
X404811D03*
X406662Y1134264D03*
X415912Y1137469D03*
Y1131060D03*
X414061Y1140973D03*
X419612Y1137469D03*
Y1131060D03*
X417761Y1134264D03*
Y1140973D03*
X412212Y1137469D03*
X432128Y844671D03*
X426579Y841467D03*
X432129Y851380D03*
X428429D03*
X424729D03*
X421029D03*
X435829D03*
X422878Y848176D03*
X432129Y864197D03*
X428429D03*
X426579Y854584D03*
X424729Y864197D03*
X421029D03*
X433979Y854584D03*
X435829Y864197D03*
X426579Y867401D03*
X433979D03*
X430278Y860993D03*
X422878D03*
X432129Y877014D03*
X428429D03*
X426579Y880219D03*
X424729Y877014D03*
X421029D03*
X433979Y880219D03*
X435829Y877014D03*
X422878Y873810D03*
X430278D03*
X432129Y889832D03*
X428429D03*
X426579Y893036D03*
X424729Y889832D03*
X421029D03*
X433979Y893036D03*
X435829Y889832D03*
X422878Y886627D03*
X430278D03*
Y899445D03*
X422878D03*
X424729Y896240D03*
X430278Y893036D03*
X432129Y896240D03*
X437678Y893036D03*
X421029Y896240D03*
X426578Y899445D03*
X428429Y896240D03*
X433978Y899445D03*
X435829Y896240D03*
X424729Y915466D03*
X426578Y912262D03*
X424729Y902649D03*
X432129D03*
X428429Y909057D03*
Y902649D03*
X421029D03*
X435829D03*
X428429Y915466D03*
X430278Y912262D03*
X432129Y915466D03*
X421029Y909057D03*
X435829D03*
Y915466D03*
X432128Y909057D03*
X433978Y905853D03*
X424728Y909057D03*
X422878Y905853D03*
X430278D03*
X426578D03*
X421029Y915466D03*
X433979Y912262D03*
X430278Y918670D03*
X433980Y925079D03*
Y931487D03*
X428429Y921875D03*
X432129D03*
X433979Y918670D03*
X435829Y921875D03*
X424927Y927255D03*
X423176Y929465D03*
X422427Y927255D03*
X425676Y929465D03*
X424729Y921875D03*
X422878Y918670D03*
X421029Y921875D03*
X426578Y918670D03*
X430279Y925079D03*
X432130Y928283D03*
X430279Y931487D03*
X432130Y934692D03*
X435830Y928283D03*
X430279Y937897D03*
X433979D03*
X426875Y947199D03*
Y949499D03*
X427875Y936470D03*
X433980Y944305D03*
X427875Y941930D03*
Y944230D03*
X430280Y944305D03*
X432130Y941101D03*
X435830D03*
X432129Y947510D03*
X435830D03*
Y934692D03*
X426905Y965935D03*
Y963635D03*
X433980Y957123D03*
Y950714D03*
Y963531D03*
X427875Y956373D03*
Y954073D03*
X422685Y956620D03*
X425185D03*
X430280Y957123D03*
X432129Y960327D03*
Y953918D03*
X430280Y950714D03*
X435830Y960327D03*
Y953918D03*
X432129Y966736D03*
X430280Y963531D03*
X435830Y966736D03*
X426905Y980336D03*
Y978036D03*
X433980Y976348D03*
Y969940D03*
Y982757D03*
X430268Y976348D03*
X432129Y973144D03*
X430280Y969940D03*
X427875Y971267D03*
X422685Y971100D03*
X427875Y968967D03*
X435830Y973144D03*
X430280Y982757D03*
X432129Y979553D03*
X427875Y983111D03*
X435830Y979553D03*
X426905Y994722D03*
Y992422D03*
X422685Y985580D03*
X427875Y985411D03*
Y997521D03*
X426905Y1006875D03*
Y1009175D03*
X434411Y1009298D03*
X434412Y1002889D03*
X430712Y1009298D03*
X427875Y1012152D03*
X430712Y1002889D03*
X427875Y999821D03*
X422685Y1000060D03*
X436263Y1006094D03*
Y999685D03*
X432562Y1006094D03*
Y999685D03*
X427875Y1014452D03*
X423015Y1014470D03*
X436263Y1012502D03*
X432562D03*
X426905Y1021963D03*
Y1019663D03*
X434411Y1028524D03*
Y1022115D03*
X434412Y1015706D03*
X421961Y1028855D03*
X430712Y1022115D03*
Y1015706D03*
X427875Y1026704D03*
X430712Y1028524D03*
X436263Y1018911D03*
X432562D03*
Y1025319D03*
X436263D03*
X427875Y1029004D03*
Y1031304D03*
X436263Y1031728D03*
X432562D03*
X428862Y1044544D03*
X434412Y1034932D03*
X430712Y1047749D03*
X423311D03*
X427011D03*
X427012Y1041340D03*
X423312D03*
X425162Y1044544D03*
X423285Y1036884D03*
X430711Y1041340D03*
X430712Y1034932D03*
X427875Y1033604D03*
X423285Y1032284D03*
Y1034584D03*
X436262Y1038137D03*
X436261Y1044544D03*
X432562Y1038137D03*
X434412Y1041340D03*
X432561Y1044544D03*
X434412Y1047749D03*
X421462Y1044544D03*
X427011Y1054157D03*
X430711D03*
X425162Y1057361D03*
X432561Y1050952D03*
X434411Y1060565D03*
Y1054157D03*
X421462Y1063770D03*
X428861Y1057361D03*
X432561D03*
X421462D03*
X425162Y1050952D03*
X423311Y1054157D03*
X428862Y1050952D03*
X436262Y1057361D03*
Y1050952D03*
Y1063770D03*
X425162D03*
X423311Y1060565D03*
X427011D03*
X428861Y1063770D03*
X430711Y1060565D03*
X423311Y1073383D03*
X432560Y1070178D03*
X421462Y1076587D03*
X430711Y1073383D03*
X427011D03*
Y1066974D03*
X425162Y1076587D03*
X423311Y1066974D03*
X432561Y1076587D03*
X434411Y1073383D03*
Y1066974D03*
X427012Y1079791D03*
X434411D03*
X423311D03*
X436262Y1070178D03*
Y1076587D03*
X421462Y1070178D03*
X425162D03*
X428862D03*
X430711Y1066974D03*
X428861Y1082995D03*
X425162Y1089404D03*
X421462Y1082995D03*
X432561Y1089404D03*
Y1082995D03*
X434411Y1092608D03*
Y1086200D03*
X428861Y1095813D03*
X421462D03*
X432561D03*
X436262Y1082995D03*
Y1089404D03*
X436261Y1095813D03*
X427011Y1099017D03*
X425161Y1102221D03*
X423311Y1105426D03*
X421462Y1108630D03*
X434411Y1105426D03*
X423311Y1111834D03*
X434411D03*
X421462Y1102221D03*
X423311Y1099017D03*
X428861Y1108630D03*
X427012Y1105426D03*
X425162Y1108630D03*
X430711Y1105426D03*
Y1099017D03*
X428861Y1102221D03*
X436262Y1108630D03*
Y1102221D03*
X432561Y1108630D03*
Y1102221D03*
X434412Y1099017D03*
X430711Y1111834D03*
X427012D03*
X423311Y1124651D03*
Y1118243D03*
X421462Y1115039D03*
X434411Y1124651D03*
Y1118243D03*
X430711Y1124651D03*
X428861Y1121447D03*
X427012Y1124651D03*
X425162Y1121447D03*
X421461D03*
X430711Y1118243D03*
X428861Y1115039D03*
X427012Y1118243D03*
X425162Y1115039D03*
X436262Y1121447D03*
Y1115039D03*
X432561Y1121447D03*
Y1115039D03*
X428861Y1127856D03*
X425162D03*
X421461D03*
X436262D03*
X432561D03*
X423312Y1137469D03*
X423311Y1131060D03*
X434412Y1137769D03*
X434411Y1131060D03*
X430711Y1137769D03*
X427012Y1137569D03*
X430711Y1131060D03*
X428861Y1134264D03*
X427012Y1131060D03*
X425162Y1134264D03*
X421461D03*
X428861Y1140973D03*
X425161D03*
X421461D03*
X436261Y1134264D03*
X432561D03*
X452478Y848176D03*
X445078D03*
X441378D03*
X439529Y844671D03*
X446929Y851380D03*
X443228D03*
X439529D03*
X450629D03*
X448779Y854584D03*
X446929Y864197D03*
X443229D03*
X441379Y854584D03*
X439529Y864197D03*
X439528Y857789D03*
X437680Y860992D03*
X450629Y864197D03*
X448779Y867401D03*
X441379D03*
X445078Y860993D03*
X452479D03*
X448779Y880219D03*
X446929Y877014D03*
X443229D03*
X441379Y880219D03*
X439529Y877014D03*
X450629D03*
X437679Y873810D03*
X452479D03*
X445078D03*
X448779Y893036D03*
X446929Y889832D03*
X443229D03*
X441379Y893036D03*
X439529Y896240D03*
Y889832D03*
X437678Y886627D03*
X450629Y889832D03*
X437679Y899445D03*
X452478Y886627D03*
X445078D03*
X452478Y899445D03*
X441378D03*
X445078Y893036D03*
X446929Y896240D03*
X452479Y893036D03*
X445078Y899445D03*
X443229Y896240D03*
X448778Y899445D03*
X450630Y896240D03*
X446929Y909057D03*
Y902649D03*
X443229D03*
X439528D03*
X437678Y912262D03*
X437679Y905853D03*
X450629Y902649D03*
X446929Y915466D03*
X443229Y909057D03*
X439529Y915466D03*
X445079Y905853D03*
X441379D03*
X450630Y909057D03*
X452479Y905853D03*
X448779D03*
X448780Y912262D03*
X441380D03*
X439529Y909057D03*
X445080Y912262D03*
X443229Y915466D03*
X450629D03*
X452478Y912262D03*
X448779Y918670D03*
X454329Y915466D03*
X439529Y921875D03*
X446930Y928283D03*
X441379Y925079D03*
Y931487D03*
X446929Y921875D03*
X437678Y918670D03*
X441378D03*
X450629Y921875D03*
X445078Y918670D03*
X443229Y921875D03*
X452478Y918670D03*
X446930Y934692D03*
X443230Y928283D03*
X448780Y931487D03*
X437679D03*
X450630Y928283D03*
X448780Y925079D03*
X445079Y931487D03*
X439530Y934692D03*
X445079Y925079D03*
X439530Y928283D03*
X437679Y925079D03*
X441379Y937897D03*
X445079D03*
X437679D03*
X448779D03*
X446929Y941101D03*
X446930Y947510D03*
X437680Y944305D03*
X441380D03*
X443230Y941101D03*
X445079Y944305D03*
X439530Y941101D03*
X450630D03*
X448780Y944305D03*
X443229Y947510D03*
X439529D03*
X450630D03*
X443230Y934692D03*
X446930Y960327D03*
Y953918D03*
Y966736D03*
X445079Y957123D03*
X437680D03*
X441380D03*
X439529Y960327D03*
X443229D03*
Y953918D03*
X439529D03*
X437680Y950714D03*
X441380D03*
X445079D03*
X448780Y957123D03*
X450630Y953918D03*
Y960327D03*
X448780Y950714D03*
X445079Y963531D03*
X437680D03*
X441380D03*
X439529Y966736D03*
X443229D03*
X448780Y963531D03*
X450630Y966736D03*
X446930Y979553D03*
Y973144D03*
X445079Y976348D03*
Y969940D03*
X439529Y973144D03*
X443229D03*
X437680Y976348D03*
X441380D03*
X437680Y969940D03*
X441380D03*
X450630Y973144D03*
X448780Y976348D03*
Y969940D03*
X445079Y982757D03*
X437680D03*
X441380D03*
X439529Y979553D03*
X443229D03*
X448780Y982757D03*
X450630Y979553D03*
X447362Y1006094D03*
Y999685D03*
Y1012502D03*
X439962Y1006094D03*
X443662D03*
X445511Y1009298D03*
X438113D03*
X441813D03*
X445512Y1002889D03*
X438113D03*
X441813D03*
X439962Y999685D03*
X443662D03*
X451062Y1006094D03*
X449213Y1009298D03*
Y1002889D03*
X451062Y999685D03*
X439962Y1012502D03*
X443662D03*
X451062D03*
X447362Y1025319D03*
Y1018911D03*
Y1031728D03*
X445511Y1022115D03*
X438113D03*
X441813D03*
X445512Y1015706D03*
X438113D03*
X439962Y1018911D03*
X441813Y1015706D03*
X443662Y1018911D03*
Y1025319D03*
X439962D03*
X445511Y1028524D03*
X441813D03*
X438113D03*
X449213Y1022115D03*
X451062Y1018911D03*
X449213Y1015706D03*
X451062Y1025319D03*
X449213Y1028524D03*
X439962Y1031728D03*
X443662D03*
X451062D03*
X447360Y1038136D03*
X452911Y1041340D03*
X451061Y1044544D03*
X449211Y1047749D03*
X452911D03*
X439962Y1038137D03*
X443662D03*
X438112Y1041340D03*
X439961Y1044544D03*
X441812Y1041340D03*
X443661Y1044544D03*
X447361D03*
X445511Y1041340D03*
X445512Y1034932D03*
X438113D03*
X441813D03*
X451062Y1038137D03*
X449211Y1041340D03*
X449213Y1034932D03*
X445510Y1047749D03*
X441812D03*
X438112D03*
X447361Y1057361D03*
Y1050952D03*
X452911Y1060565D03*
X447361Y1063770D03*
X449211Y1054157D03*
X449213Y1060565D03*
X438112D03*
Y1054157D03*
X439961Y1057361D03*
X441812Y1054157D03*
Y1060565D03*
X443661Y1057361D03*
X445511Y1060565D03*
Y1054157D03*
X439961Y1050952D03*
X443661D03*
X439961Y1063770D03*
X443661D03*
X451061D03*
X452911Y1054157D03*
X451062Y1050952D03*
X454762D03*
Y1057361D03*
X451062D03*
X451061Y1076587D03*
X452911Y1073383D03*
X447361Y1076587D03*
Y1070178D03*
X449211Y1073383D03*
X452911Y1079791D03*
X449211D03*
X439961Y1076587D03*
Y1070178D03*
X441812Y1073383D03*
X438112D03*
X443661Y1070178D03*
Y1076587D03*
X445511Y1073383D03*
X441812Y1066974D03*
X438112D03*
X445511D03*
X441812Y1079791D03*
X438112D03*
X445511D03*
X452911Y1066974D03*
X449211D03*
X451062Y1070178D03*
X447361Y1082995D03*
X452911Y1092608D03*
X451062Y1089404D03*
X449212Y1086200D03*
X451062Y1095813D03*
X452911Y1086200D03*
X443661Y1082995D03*
X439961D03*
X441812Y1086200D03*
X445511D03*
X439961Y1089404D03*
X441812Y1092608D03*
X438112D03*
X443661Y1089404D03*
X445511Y1092608D03*
X447361Y1089404D03*
X438112Y1086200D03*
X449211Y1092608D03*
X439961Y1095813D03*
X443661D03*
X447361D03*
X451060Y1082995D03*
X447361Y1108630D03*
Y1102221D03*
X452911Y1099017D03*
X441812Y1105426D03*
X438112D03*
X439961Y1108630D03*
X443661D03*
X445511Y1105426D03*
X439961Y1102221D03*
X441812Y1099017D03*
X438112D03*
X443661Y1102221D03*
X445511Y1099017D03*
X452912Y1105426D03*
X451061Y1108630D03*
X449212Y1105426D03*
X451061Y1102221D03*
X449212Y1099017D03*
X441812Y1111834D03*
X438112D03*
X445511D03*
X452912D03*
X449212D03*
X447361Y1121447D03*
Y1115039D03*
Y1127856D03*
X438112Y1124651D03*
X439961Y1121447D03*
X441812Y1124651D03*
X445511D03*
X443661Y1121447D03*
X438112Y1118243D03*
X441812D03*
X439961Y1115039D03*
X445511Y1118243D03*
X443661Y1115039D03*
X452912Y1124651D03*
Y1118243D03*
X451061Y1121447D03*
X449212Y1124651D03*
Y1118243D03*
X451061Y1115039D03*
X439961Y1127856D03*
X443661D03*
X451061D03*
X447361Y1134264D03*
X441812Y1137769D03*
X438112D03*
X445511D03*
X443661Y1134264D03*
X441812Y1131060D03*
X439961Y1134264D03*
X438112Y1131060D03*
X445511D03*
X452912Y1137769D03*
Y1131060D03*
X449212Y1137769D03*
Y1131060D03*
X451061Y1134264D03*
X461729Y851380D03*
X458029D03*
X454328D03*
X456179Y841467D03*
X463579D03*
X469129Y851380D03*
X465429D03*
X459878Y848176D03*
X467278D03*
X456179Y854584D03*
X463579D03*
X461729Y864197D03*
X458029D03*
X454329D03*
X469129D03*
X465429D03*
X456179Y867401D03*
X463579D03*
X459878Y860993D03*
X467278D03*
X461729Y877014D03*
X458029D03*
X456179Y880219D03*
X454329Y877014D03*
X463579Y880219D03*
X469129Y877014D03*
X465429D03*
X467278Y873810D03*
X459878D03*
X461729Y889832D03*
X458029D03*
X456179Y893036D03*
X454329Y889832D03*
X463579Y893036D03*
X469129Y896240D03*
Y889832D03*
X465429D03*
X459878Y886627D03*
X467278D03*
X459878Y899445D03*
X467278D03*
X454329Y896240D03*
X459878Y893036D03*
X461729Y896240D03*
X467278Y893036D03*
X456178Y899445D03*
X458029Y896240D03*
X463578Y899445D03*
X465429Y896240D03*
X470978Y899445D03*
X463578Y905853D03*
X470980Y912262D03*
X461729Y902649D03*
X458029D03*
X456178Y912262D03*
Y905853D03*
X454329Y902649D03*
X465429D03*
Y909057D03*
Y915466D03*
X469129Y902649D03*
X454329Y909057D03*
X470978Y918670D03*
X467278Y912262D03*
X469129Y915466D03*
X458029Y909057D03*
X459878Y905853D03*
X461729Y915466D03*
X467278Y905853D03*
X461729Y909057D03*
X458029Y915466D03*
X459878Y918670D03*
X463578Y912262D03*
X459878D03*
X469129Y909057D03*
X454103Y931359D03*
Y933659D03*
X461729Y921875D03*
X456178Y918670D03*
X467278D03*
X454329Y921875D03*
X468236Y928349D03*
X465936D03*
X463636D03*
X461336D03*
X459036D03*
X469129Y921875D03*
X463578Y918670D03*
X465429Y921875D03*
X458029D03*
X462261Y942152D03*
X464561D03*
X466861D03*
X454423Y949139D03*
X469251Y942246D03*
X453585Y942238D03*
Y939938D03*
Y944538D03*
X454393Y963829D03*
Y966129D03*
X463874Y956540D03*
X466272D03*
X454423Y951439D03*
X453403Y956999D03*
X461424Y956620D03*
X458404D03*
X453403Y959299D03*
X468904Y956620D03*
X466272Y971100D03*
X463874Y971140D03*
X454263Y981209D03*
Y978909D03*
X468904Y971100D03*
X458404D03*
X461424Y971140D03*
X453403Y973099D03*
Y970799D03*
X454463Y995299D03*
Y992999D03*
X466272Y985580D03*
X463874D03*
X453403Y986899D03*
X461424Y985580D03*
X458404D03*
X453403Y984599D03*
X468904Y985580D03*
X453403Y998399D03*
X466272Y1014540D03*
X463874D03*
X454443Y1009409D03*
Y1007109D03*
X466272Y1000060D03*
X463874D03*
X468895Y1014550D03*
X453403Y1012199D03*
X458404Y1000080D03*
X461424D03*
X453403Y1000699D03*
X468904Y1000080D03*
X458404Y1014540D03*
X461295Y1014510D03*
X453403Y1014499D03*
X454434Y1022186D03*
Y1019886D03*
X465680Y1028855D03*
X463180D03*
X460680D03*
X458180D03*
X457942Y1031909D03*
X467711Y1047750D03*
X460311D03*
Y1041340D03*
X467372Y1036874D03*
X465861Y1044544D03*
X456611Y1047749D03*
X464011D03*
X471411Y1041340D03*
X467711D03*
X454762Y1044544D03*
Y1038136D03*
X460971Y1037069D03*
X463271D03*
X458671D03*
X457942Y1034409D03*
X456611Y1041340D03*
X464011D03*
X462162Y1044544D03*
X458462D03*
X464011Y1054157D03*
X465860Y1050952D03*
X456611Y1060565D03*
X462161Y1057361D03*
X456611Y1054157D03*
X462162Y1050952D03*
X465862Y1057361D03*
X458462Y1063770D03*
X465862D03*
X462161D03*
X460312Y1054157D03*
X458462Y1057361D03*
X467712Y1054157D03*
Y1060565D03*
X454761Y1063770D03*
X464012Y1060565D03*
X458460Y1050952D03*
X460311Y1060565D03*
X454761Y1076587D03*
X456611Y1073383D03*
X454762Y1070178D03*
X462162D03*
X467711Y1073383D03*
Y1066974D03*
X456612Y1079791D03*
X467711D03*
X460311Y1073383D03*
X458460Y1070178D03*
X460311Y1066974D03*
X464011D03*
X465860Y1070178D03*
X469560D03*
X464012Y1079791D03*
X460312D03*
X462162Y1076587D03*
X456611Y1066974D03*
X465862Y1076587D03*
X464011Y1073383D03*
X458462Y1076587D03*
X458461Y1082995D03*
X456611Y1086200D03*
X460311Y1092608D03*
X464011Y1086200D03*
X467712D03*
Y1092608D03*
X465862Y1082995D03*
X462162D03*
X462161Y1095812D03*
X458461D03*
X465861Y1089403D03*
X456612Y1092607D03*
X454761Y1089403D03*
X460311Y1086200D03*
X454760Y1082995D03*
X465861Y1095812D03*
X464012Y1092607D03*
X454761Y1095812D03*
X458461Y1089403D03*
X462161D03*
X460312Y1105426D03*
X458462Y1102221D03*
X456611Y1099017D03*
X464012Y1105426D03*
Y1099017D03*
X462162Y1108630D03*
X465861D03*
Y1102221D03*
X464012Y1111834D03*
X467711Y1105426D03*
Y1111834D03*
Y1099017D03*
X462162Y1102221D03*
X458461Y1108630D03*
X456612Y1105426D03*
X454761Y1108630D03*
Y1102221D03*
X460312Y1111834D03*
X456611D03*
X460312Y1099016D03*
X458462Y1121447D03*
Y1115039D03*
X467712Y1124651D03*
X467711Y1118243D03*
X465862Y1121447D03*
Y1115039D03*
X458462Y1127856D03*
X464012Y1124651D03*
X462161Y1121447D03*
X460312Y1124651D03*
X456611D03*
X454761Y1121447D03*
X464011Y1118243D03*
X462161Y1115039D03*
X460312Y1118243D03*
X456611D03*
X454761Y1115039D03*
X462161Y1127856D03*
X454761D03*
X465861D03*
X458462Y1134264D03*
X464012Y1137469D03*
X460312D03*
X456612D03*
X464012Y1131060D03*
X462161Y1134264D03*
X460312Y1131060D03*
X456611D03*
X454761Y1134264D03*
X462161Y1140973D03*
X458461D03*
X454761D03*
X467712Y1137469D03*
X465861Y1134264D03*
X467712Y1131060D03*
X465861Y1140973D03*
X478379Y841467D03*
X470979D03*
X476529Y851380D03*
X480229D03*
X472829D03*
X483929D03*
X474678Y848176D03*
X482078D03*
X480229Y864197D03*
X478379Y854584D03*
X476529Y864197D03*
X470979Y854584D03*
X472829Y864197D03*
X483929D03*
X478379Y867401D03*
X470979D03*
X474678Y860993D03*
X482078D03*
X480229Y877014D03*
X478379Y880219D03*
X476529Y877014D03*
X472829D03*
X472828Y870606D03*
X470979Y880219D03*
Y873810D03*
X483929Y877014D03*
X474678Y873810D03*
X482078D03*
X480228Y896240D03*
X480229Y889832D03*
X478379Y893036D03*
X470979D03*
X476529Y889832D03*
X472829D03*
X483929D03*
X474678Y899445D03*
X482078D03*
X474678Y893036D03*
X472829Y896240D03*
X478378Y899445D03*
X474678Y886627D03*
X482078D03*
X476529Y896240D03*
Y915466D03*
X478380Y912262D03*
X478379Y918670D03*
X480229Y902649D03*
X474678Y912262D03*
Y905853D03*
X483929Y909057D03*
X482079Y912262D03*
X483928Y902649D03*
X480229Y915466D03*
X472828D03*
X472829Y902649D03*
X480228Y909057D03*
X482078Y905853D03*
X476529Y902649D03*
X470978Y905853D03*
X478378D03*
X472829Y909057D03*
X476529D03*
X480229Y928283D03*
X478378Y931488D03*
Y925079D03*
X482078D03*
X476285Y930126D03*
X480229Y921875D03*
X476528D03*
X474678Y918670D03*
X483929Y928283D03*
X482078Y918670D03*
X483928Y921875D03*
X482079Y931488D03*
X472829Y921875D03*
X470536Y928349D03*
X478378Y937896D03*
X480229Y941100D03*
X476285Y934726D03*
X476180Y945355D03*
Y947655D03*
X478378Y944304D03*
X480229Y934691D03*
X483928Y941100D03*
X482079Y944304D03*
X482078Y937896D03*
X483928Y947509D03*
X480229D03*
X471550Y942152D03*
X473851Y942246D03*
X476285Y962326D03*
Y960026D03*
Y964626D03*
X483928Y960326D03*
X482078Y957122D03*
X482079Y950713D03*
X483929Y966735D03*
X478378Y963530D03*
X480228Y960326D03*
X478378Y950713D03*
X480229Y953917D03*
X478378Y957122D03*
X471404Y956620D03*
X480229Y966735D03*
X482078Y963529D03*
X476285Y966926D03*
X476192Y977670D03*
X476335Y980737D03*
X482079Y969939D03*
X483928Y979552D03*
X482078Y976347D03*
Y982756D03*
X478379Y969939D03*
X476285Y973826D03*
Y971526D03*
X471404Y971100D03*
X473904D03*
X480229Y979552D03*
X478378Y982756D03*
X480229Y973143D03*
X478378Y976347D03*
X476285Y996826D03*
Y994526D03*
Y989926D03*
Y987626D03*
X471404Y985580D03*
X476295Y1010500D03*
X476285Y1012926D03*
Y1006026D03*
Y1003726D03*
X471204Y1014540D03*
X484361Y999684D03*
X482512Y1009297D03*
X482511Y1002888D03*
X484362Y1012501D03*
X480662Y999684D03*
X478811Y1002888D03*
Y1009297D03*
X480662Y1012501D03*
X471404Y1000080D03*
X476275Y1022636D03*
X476285Y1017526D03*
X482511Y1028523D03*
Y1022114D03*
X484361Y1018910D03*
Y1031727D03*
X480662D03*
X482511Y1015705D03*
X480661Y1018910D03*
X478811Y1022114D03*
Y1028523D03*
Y1015705D03*
X476325Y1031795D03*
Y1027195D03*
Y1029495D03*
X470724Y1028827D03*
X480662Y1025318D03*
X471282Y1036526D03*
X473507Y1035928D03*
X475111Y1041340D03*
X482511D03*
X482512Y1034931D03*
X484361Y1038136D03*
X471411Y1047749D03*
X482511D03*
X475111D03*
X469562Y1044544D03*
X478811Y1034931D03*
X480662Y1038136D03*
X478811Y1041340D03*
X480662Y1044544D03*
X473262D03*
X476962D03*
X478811Y1047749D03*
X480662Y1050952D03*
X475111Y1060565D03*
X471411Y1054157D03*
X484361Y1057361D03*
X482511Y1060565D03*
X484362Y1050952D03*
X473261Y1057361D03*
X471412Y1060565D03*
X475112Y1054157D03*
X469562Y1063770D03*
X469561Y1057361D03*
X473262Y1063770D03*
X469561Y1050952D03*
X473262D03*
X482511Y1054157D03*
X480662Y1063770D03*
X480661Y1057361D03*
X478812Y1060565D03*
X476962Y1063770D03*
Y1057361D03*
X478812Y1054157D03*
X476961Y1050952D03*
X478811Y1066974D03*
X475111D03*
X473262Y1070178D03*
X478811Y1073383D03*
X484361Y1076587D03*
X484362Y1070178D03*
X482512Y1066974D03*
X478812Y1079791D03*
X475111D03*
X482511D03*
X471411Y1066974D03*
X476962Y1076587D03*
X480662D03*
Y1070178D03*
X476962D03*
X473262Y1076587D03*
X469562D03*
X471411Y1073383D03*
Y1079791D03*
X475111Y1073383D03*
X482511D03*
X480662Y1082995D03*
X476962Y1089404D03*
X473262Y1082995D03*
X469561Y1089404D03*
X482512Y1086200D03*
X484362Y1089404D03*
X480661Y1095813D03*
X469562D03*
X484362D03*
X473262D03*
X469562Y1082995D03*
X480662Y1089404D03*
X478812Y1092607D03*
X475112D03*
X473261Y1089403D03*
X471412Y1086199D03*
X476961Y1082994D03*
X482512Y1092607D03*
X476961Y1095812D03*
X471412Y1092607D03*
X475112Y1086199D03*
X478812D03*
X480662Y1108630D03*
X478811Y1099017D03*
X473262Y1108630D03*
X476962Y1102221D03*
X475112Y1099017D03*
X471411D03*
X469562Y1102221D03*
X482511Y1105426D03*
Y1111834D03*
X484362Y1108630D03*
X475111Y1111834D03*
X471411D03*
X478811Y1105426D03*
X469562Y1108630D03*
X473262Y1102221D03*
X482511Y1099017D03*
X478811Y1111834D03*
X476962Y1108630D03*
X471411Y1105426D03*
X475111D03*
X484362Y1102221D03*
X480662D03*
X480661Y1115039D03*
X478811Y1118243D03*
X476961Y1115039D03*
X475111Y1118243D03*
X471411D03*
X469561Y1115039D03*
X482511Y1118243D03*
X476961Y1127856D03*
X469562D03*
X484361D03*
X484362Y1115039D03*
X473262D03*
Y1121447D03*
X480662D03*
X478811Y1131060D03*
X476961Y1140973D03*
X475111Y1131060D03*
X471412Y1137469D03*
Y1131060D03*
X469561Y1140973D03*
X473261Y1134264D03*
X482511Y1131060D03*
X484361Y1140973D03*
X480662Y1134264D03*
X469561D03*
X484333Y1575686D03*
Y1580678D03*
X477229D03*
X472273D03*
Y1575686D03*
X477229D03*
X482529Y1599884D03*
X477573D03*
X484333Y1587598D03*
Y1592590D03*
X472273D03*
X477229D03*
Y1587598D03*
X472273D03*
X482529Y1616788D03*
X477573D03*
Y1611796D03*
X482529D03*
X477573Y1604876D03*
X482529D03*
X493179Y841467D03*
X485779D03*
X500579D03*
X495029Y851380D03*
X491329D03*
X487629D03*
X498729D03*
X489478Y848176D03*
X496878D03*
X495029Y864197D03*
X493179Y854584D03*
X491329Y864197D03*
X487629D03*
X485779Y854584D03*
X498729Y864197D03*
X500579Y854584D03*
X493179Y867401D03*
X485779D03*
X500579D03*
X489478Y860993D03*
X496878D03*
X495029Y877014D03*
X493179Y880219D03*
X491329Y877014D03*
X487629D03*
X485779Y880219D03*
X500579D03*
X498729Y877014D03*
X496878Y873810D03*
X489478D03*
X489479Y893036D03*
X495029Y889832D03*
X491329D03*
X487629D03*
X498729D03*
X500579Y893036D03*
X498729Y896240D03*
X496879Y899445D03*
X489478D03*
Y886627D03*
X496878D03*
Y912262D03*
X495029Y909057D03*
X489478Y912262D03*
Y905853D03*
X495029Y902649D03*
X493179Y905853D03*
X485778D03*
X498728Y915466D03*
X495028Y928283D03*
X493179Y925079D03*
X489478D03*
Y918670D03*
X485778Y925079D03*
X496879Y918670D03*
X495029Y921875D03*
X496878Y931488D03*
X489478D03*
X496879Y937896D03*
X495029Y941100D03*
X493179Y944304D03*
X489478D03*
Y937896D03*
X485778Y944304D03*
X498729Y934691D03*
X495028Y947509D03*
X496879Y957122D03*
X495029Y960326D03*
X489478Y957122D03*
Y950713D03*
X496878D03*
X498729Y953917D03*
X495028Y966735D03*
X493179Y963530D03*
X485778D03*
X489478D03*
X500579D03*
X496879Y976347D03*
X496878Y969939D03*
X489478Y976347D03*
Y969939D03*
X495029Y979552D03*
X498728Y973143D03*
X493179Y982756D03*
X489478D03*
X485778D03*
X497311Y1009297D03*
X497312Y1002888D03*
X495462Y999684D03*
X489911Y1009297D03*
X489912Y1002888D03*
X491761Y1006093D03*
X488062D03*
X499161D03*
X495461Y1012501D03*
X497311Y1028523D03*
X489911D03*
Y1022114D03*
Y1015705D03*
X497311Y1022114D03*
X495462Y1018910D03*
X493612Y1015705D03*
X486211D03*
X501012D03*
X499161Y1025318D03*
X495461Y1031727D03*
X497312Y1041340D03*
X489911D03*
Y1034931D03*
X495462Y1038136D03*
X493612Y1034931D03*
X486211D03*
X499161Y1044544D03*
X489911Y1047749D03*
X497311D03*
Y1060565D03*
X495462Y1057361D03*
X489911Y1060565D03*
Y1054157D03*
X495461Y1050952D03*
X493611Y1054157D03*
X486211D03*
X499162Y1063770D03*
X495462Y1076587D03*
X493612Y1073383D03*
X489911Y1066974D03*
X486211Y1073383D03*
X497311Y1066974D03*
X495461Y1070178D03*
X489911Y1073383D03*
X497312Y1079791D03*
X489911D03*
X497311Y1086200D03*
X493612Y1092608D03*
X489911D03*
Y1086200D03*
X486211Y1092608D03*
X495461Y1089404D03*
X499161Y1082995D03*
X495462Y1095813D03*
X499162D03*
X491762D03*
X488062D03*
X497312Y1105426D03*
X493611D03*
X491762Y1102221D03*
X488061D03*
X486211Y1105426D03*
X486212Y1099017D03*
X499161Y1108630D03*
Y1102221D03*
X497312Y1111834D03*
X489911D03*
Y1099017D03*
X495462Y1102221D03*
X501011Y1099017D03*
X493611D03*
X497311D03*
X495462Y1108630D03*
X489911Y1105426D03*
X486211Y1111834D03*
X493611D03*
X491762Y1108630D03*
X488062D03*
X501012Y1105426D03*
Y1111833D03*
X497311Y1118243D03*
X495462Y1121447D03*
X493612Y1118243D03*
X489911D03*
X486211D03*
X501011D03*
X499161Y1115039D03*
X491761Y1127856D03*
X499161D03*
X491762Y1115039D03*
X495462D03*
X488062D03*
Y1121447D03*
X497311Y1131060D03*
X493611D03*
X489911D03*
X486211D03*
X491761Y1140973D03*
X501011Y1131060D03*
X499161Y1140973D03*
X495462Y1134264D03*
X488062D03*
X501349Y1580678D03*
X496393D03*
Y1575686D03*
X501349D03*
X489289D03*
Y1580678D03*
X501693Y1599884D03*
X494589D03*
X489633D03*
X501349Y1592590D03*
X496393D03*
X501349Y1587598D03*
X496393D03*
X489289D03*
Y1592590D03*
X501693Y1611796D03*
Y1604876D03*
Y1616788D03*
X489633Y1611796D03*
X494589Y1604876D03*
X489633D03*
X494589Y1611796D03*
X489633Y1616788D03*
X494589D03*
X497441Y1675383D03*
Y1679920D03*
Y1684454D03*
Y1689556D03*
Y1694093D03*
Y1698627D03*
Y1703729D03*
Y1708266D03*
Y1712800D03*
Y1726974D03*
Y1722440D03*
Y1717903D03*
X507979Y841467D03*
X515379D03*
X506129Y851380D03*
X502429D03*
X513529D03*
X509829D03*
X517229D03*
X511678Y848176D03*
X504278D03*
X513529Y864197D03*
X509829D03*
X506129D03*
X502429D03*
X507979Y854584D03*
X515379D03*
X517229Y864197D03*
X507979Y867401D03*
X515379D03*
X511678Y860993D03*
X504278D03*
X509829Y877014D03*
X507979Y880219D03*
X502429Y877014D03*
X513529D03*
X506129D03*
X515379Y880219D03*
X517229Y877014D03*
X511678Y873810D03*
X504278D03*
X506129Y889832D03*
X502428Y896240D03*
X502429Y889832D03*
X513529D03*
X509829D03*
X506128Y896240D03*
X504279Y893036D03*
X515379D03*
X517229Y889832D03*
X507978Y899445D03*
X515378D03*
X511678Y886627D03*
X504278D03*
X511678Y905853D03*
X509829Y909057D03*
X507979Y912262D03*
X502429Y909057D03*
Y902649D03*
X509828D03*
X515378Y912262D03*
Y905853D03*
X502429Y915466D03*
X506129D03*
X511678Y925079D03*
X509829Y928283D03*
X502429D03*
Y921875D03*
X509828D03*
X507978Y918670D03*
X515378Y925079D03*
Y918670D03*
X507979Y931488D03*
X515378D03*
X511678Y944304D03*
X509828Y941100D03*
X507978Y937896D03*
X506129Y934691D03*
X502429Y941100D03*
Y934691D03*
X515378Y944304D03*
Y937896D03*
X509829Y947509D03*
X502429D03*
X509828Y960326D03*
X507978Y957122D03*
X506129Y953917D03*
X502429Y960326D03*
Y953917D03*
X507979Y950713D03*
X515378Y957122D03*
Y950713D03*
X509829Y966735D03*
X502428D03*
X511678Y963530D03*
X504278D03*
X515378D03*
X507978Y976347D03*
X507979Y969939D03*
X502429Y979552D03*
Y973143D03*
X513529D03*
X509828Y979552D03*
X506129Y973143D03*
X515379Y976347D03*
X515378Y969939D03*
X517228Y973143D03*
X511678Y982756D03*
X515378D03*
X510261Y999684D03*
X508411Y1002888D03*
X506562Y1006093D03*
X502862Y999684D03*
X502861Y1012501D03*
X508412Y1009297D03*
X510262Y1012501D03*
X515811Y1009297D03*
Y1002888D03*
X508411Y1028523D03*
X502862Y1025318D03*
Y1018910D03*
X510261D03*
X508411Y1022114D03*
X506562Y1025318D03*
X504711Y1015705D03*
X515811Y1028523D03*
Y1022114D03*
X510262Y1031727D03*
X502862D03*
X515811Y1015705D03*
X512111D03*
X502862Y1044544D03*
Y1038136D03*
X512111Y1034931D03*
X510261Y1038136D03*
X508411Y1041340D03*
X506562Y1044544D03*
X515811Y1034931D03*
Y1041340D03*
X508411Y1047749D03*
X515811D03*
X510262Y1057361D03*
X508411Y1060565D03*
X502862Y1057361D03*
Y1050952D03*
X512111Y1054157D03*
X510262Y1050952D03*
X515811Y1054157D03*
Y1060565D03*
X502862Y1063770D03*
X506562D03*
X510262Y1076587D03*
Y1070178D03*
X502862Y1076587D03*
Y1070178D03*
X512111Y1073383D03*
X508411Y1066974D03*
X515811Y1073383D03*
Y1066974D03*
X508411Y1079791D03*
X515811D03*
X512112Y1092608D03*
X510262Y1089404D03*
X508412Y1086200D03*
X506562Y1082995D03*
X502862Y1089404D03*
Y1082995D03*
X515812Y1092608D03*
X515811Y1086200D03*
X513961Y1095813D03*
X502862D03*
X517662D03*
X513962Y1108630D03*
Y1102221D03*
X512112Y1099017D03*
X508411D03*
X506562Y1108630D03*
X504711Y1099017D03*
X502862Y1102221D03*
X515811Y1105426D03*
Y1111834D03*
X517662Y1108630D03*
X510262Y1102221D03*
X502861Y1108629D03*
X512112Y1105426D03*
X508412Y1111833D03*
X506561Y1102220D03*
X504712Y1111833D03*
Y1105426D03*
X510261Y1108630D03*
X512112Y1111833D03*
X508412Y1105426D03*
X513961Y1115039D03*
X512111Y1118243D03*
X508411D03*
X504711D03*
X510261Y1115039D03*
X515811Y1118243D03*
X513961Y1127856D03*
X506561D03*
X517662Y1115039D03*
X502862D03*
X510262Y1121447D03*
X502862D03*
X517662D03*
X506561Y1115038D03*
X513961Y1140973D03*
X512111Y1131060D03*
X508411D03*
X504711D03*
X506561Y1140973D03*
X515811Y1131060D03*
X510262Y1134264D03*
X502862D03*
X517662D03*
X508453Y1575686D03*
X513409D03*
X508453Y1580678D03*
X513409D03*
X513753Y1599884D03*
X506649D03*
X508453Y1587598D03*
X513409D03*
X508453Y1592590D03*
X513409D03*
X513753Y1616788D03*
Y1604876D03*
Y1611796D03*
X506649D03*
Y1604876D03*
Y1616788D03*
X513189Y1675383D03*
Y1679920D03*
X505315Y1679320D03*
X513189Y1684454D03*
Y1689556D03*
Y1694093D03*
Y1698627D03*
X505315Y1688391D03*
Y1693493D03*
Y1698030D03*
Y1683857D03*
X513189Y1703729D03*
Y1708266D03*
Y1712800D03*
X505315Y1707666D03*
Y1712203D03*
Y1702564D03*
X513189Y1726974D03*
Y1722440D03*
Y1717903D03*
X505315Y1730911D03*
Y1726377D03*
Y1721840D03*
Y1716737D03*
X528329Y844671D03*
X522779Y841467D03*
X528329Y851380D03*
X524629D03*
X520929D03*
X532029D03*
X519078Y848176D03*
X528329Y864197D03*
X524629D03*
X520929D03*
X530179Y860993D03*
Y854584D03*
X522779D03*
X532028Y857789D03*
X533879Y860993D03*
X530178Y867401D03*
X522779D03*
X533879D03*
X526479Y860993D03*
X519078D03*
X528329Y877014D03*
X522779Y880219D03*
X520929Y877014D03*
X530179Y880219D03*
X524629Y877014D03*
X532029D03*
X533879Y880219D03*
Y873810D03*
X532028Y883423D03*
X526479Y873810D03*
X519078D03*
X528329Y896240D03*
Y889832D03*
X524629D03*
X526479Y893036D03*
X524629Y896240D03*
X520929Y889832D03*
X532029D03*
Y896240D03*
X533879Y893036D03*
X522779Y899445D03*
X533879D03*
X530178Y893036D03*
X526479Y886627D03*
X519078D03*
X533879D03*
X528329Y902649D03*
X522778Y912262D03*
X520928Y909057D03*
X519079Y905853D03*
X520929Y902649D03*
X528329Y915466D03*
X524628D03*
X532029D03*
X528329Y909057D03*
X533879Y912262D03*
X528329Y921875D03*
X520928Y928283D03*
X519079Y925079D03*
X522779Y918670D03*
X520929Y921875D03*
X522778Y931488D03*
X528329Y928283D03*
X533879Y918670D03*
X533878Y931488D03*
X528329Y941100D03*
Y934691D03*
X524628D03*
X522779Y937896D03*
X520929Y941100D03*
X519079Y944304D03*
X520928Y947509D03*
X532029Y934691D03*
X533879Y937896D03*
X528329Y947509D03*
Y960326D03*
Y953917D03*
X524629D03*
X522779Y957122D03*
X520929Y960326D03*
X522778Y950713D03*
X520928Y966735D03*
X526479Y963530D03*
X519079D03*
X533879Y957122D03*
X532029Y953917D03*
X533879Y950713D03*
X530178Y963530D03*
X528329Y966735D03*
Y979552D03*
Y973143D03*
X522779Y976347D03*
X522778Y969939D03*
X524628Y973143D03*
X520929Y979552D03*
X533879Y976347D03*
X519079Y982756D03*
X533901Y980606D03*
X533879Y969939D03*
X532029Y973143D03*
X521361Y1012501D03*
Y999684D03*
X528762Y1006093D03*
Y999684D03*
X525061Y1006093D03*
X523211Y1009297D03*
X523212Y1002888D03*
X534311Y1009297D03*
Y1002888D03*
X532461Y1006093D03*
X528761Y1012501D03*
X528762Y1025318D03*
X523211Y1028523D03*
X525061Y1025318D03*
X528762Y1031727D03*
X521361D03*
X519512Y1015705D03*
X521362Y1018910D03*
X523211Y1022114D03*
X526912Y1015705D03*
X528762Y1018910D03*
X530611Y1015705D03*
X534311Y1028523D03*
X534310Y1022114D03*
X532461Y1025318D03*
X528762Y1044544D03*
X525061D03*
X523212Y1041340D03*
X521362Y1038136D03*
X519512Y1034931D03*
X532462Y1044544D03*
X523211Y1047749D03*
X528762Y1038136D03*
X534311Y1041340D03*
Y1047749D03*
X528762Y1057361D03*
Y1050952D03*
X523212Y1060565D03*
X521362Y1057361D03*
X521361Y1050952D03*
X519512Y1054157D03*
X528762Y1063770D03*
X525061D03*
X534311Y1060565D03*
X532462Y1063770D03*
X528762Y1076587D03*
Y1070178D03*
X521362Y1076587D03*
X521361Y1070178D03*
X519512Y1073383D03*
X523211Y1066974D03*
X523212Y1079791D03*
X534311Y1066974D03*
Y1079791D03*
X523211Y1086200D03*
X521361Y1089404D03*
X519511Y1092608D03*
X528762Y1089404D03*
Y1082995D03*
X525061D03*
X532462Y1082996D03*
X534311Y1086200D03*
X528761Y1095813D03*
X526911Y1105426D03*
X521361Y1102221D03*
X519511Y1105426D03*
X519512Y1099017D03*
X532461Y1108630D03*
X530612Y1111834D03*
X523211D03*
X526911Y1099017D03*
X534311D03*
X532460Y1102221D03*
X521362Y1108630D03*
X525062D03*
X534311Y1111834D03*
X523211Y1105426D03*
X534311D03*
X528762Y1108630D03*
X519511Y1111834D03*
X526911D03*
X528762Y1102221D03*
X525062D03*
X523212Y1099017D03*
X530611Y1105426D03*
Y1124651D03*
Y1118243D03*
X528762Y1121447D03*
X523211Y1118243D03*
X521361Y1115039D03*
X519511Y1118243D03*
X532461Y1115039D03*
X528761Y1127856D03*
X521361D03*
X525062Y1115039D03*
X528762D03*
X526911Y1118243D03*
X525062Y1121447D03*
X534311Y1118243D03*
X532461Y1121446D03*
X534311Y1124650D03*
X532461Y1127855D03*
X530612Y1137469D03*
Y1131060D03*
X526912D03*
X523211D03*
X519511D03*
X528761Y1134264D03*
X521361Y1140973D03*
X534311Y1131060D03*
X525062Y1134264D03*
X528761Y1140973D03*
X532461D03*
X532573Y1575686D03*
Y1580678D03*
X520513D03*
X525469D03*
X520513Y1575686D03*
X525469D03*
X525813Y1599884D03*
X530769D03*
X518709D03*
X532573Y1587598D03*
Y1592590D03*
X525469D03*
X520513D03*
Y1587598D03*
X525469D03*
X525813Y1611796D03*
X530769D03*
X525813Y1604876D03*
X530769D03*
Y1616788D03*
X525813D03*
X518709D03*
Y1604876D03*
Y1611796D03*
X528937Y1675383D03*
Y1679920D03*
X521063Y1679320D03*
X528937Y1684454D03*
Y1689556D03*
Y1694093D03*
Y1698627D03*
X521063Y1688391D03*
Y1693493D03*
Y1698030D03*
Y1683857D03*
X528937Y1703729D03*
Y1708266D03*
Y1712800D03*
X521063Y1707666D03*
Y1712203D03*
Y1702564D03*
X528937Y1726974D03*
Y1722440D03*
Y1717903D03*
X521063Y1730911D03*
Y1726377D03*
Y1721840D03*
Y1716737D03*
X537580Y848176D03*
X535729Y844671D03*
Y851380D03*
X544979Y860993D03*
Y854584D03*
X539428Y864197D03*
X537579Y854584D03*
Y860993D03*
X544979Y867401D03*
X541279D03*
X537579D03*
X546829Y870606D03*
X541279Y873810D03*
X535729Y870606D03*
Y883423D03*
X541279Y880219D03*
X546829Y883423D03*
X541279Y886627D03*
X544979D03*
X537579D03*
X535729Y889832D03*
X550529D03*
X548679Y912262D03*
X537579Y905853D03*
X535729Y909057D03*
Y902649D03*
X548679Y905853D03*
X537578Y925079D03*
X535729Y928283D03*
Y921875D03*
X548678Y925079D03*
Y931488D03*
X537578Y944304D03*
X535729Y941100D03*
X548678Y944304D03*
X535729Y947509D03*
X549278Y949619D03*
X549719Y962436D03*
X535729Y960326D03*
Y966735D03*
X537579Y963530D03*
X548146Y965640D03*
X537579Y982756D03*
X541279Y969939D03*
X539429Y973143D03*
X543729Y984866D03*
X536161Y999684D03*
X549254Y1000648D03*
X536161Y1012501D03*
X541712Y1015705D03*
X545412D03*
X538012D03*
X536161Y1018910D03*
X549112Y1015705D03*
X536161Y1031727D03*
X545412Y1034931D03*
X541711D03*
X538011D03*
X536161Y1038136D03*
X549112Y1034931D03*
X541711Y1054157D03*
X538011D03*
X536161Y1057361D03*
X545411Y1054157D03*
X536161Y1050952D03*
X549422Y1064850D03*
X545411Y1066974D03*
X536161Y1076587D03*
X536162Y1070178D03*
X538011Y1073383D03*
X547262Y1070178D03*
X538011Y1092608D03*
X536161Y1089404D03*
X545411Y1092608D03*
X547262Y1082996D03*
X543561Y1095813D03*
X536161D03*
X547261D03*
X545412Y1105426D03*
X541711D03*
X539861Y1108630D03*
Y1102221D03*
X536161D03*
X541711Y1111834D03*
X545411D03*
X538011Y1105426D03*
X536161Y1108630D03*
X538011Y1111834D03*
X543561Y1108630D03*
X545411Y1124651D03*
Y1118243D03*
X543562Y1115039D03*
X539862D03*
X538011Y1124651D03*
X536161Y1115039D03*
X541711Y1118243D03*
X538010Y1118242D03*
X543561Y1121446D03*
X539861Y1127855D03*
X536161D03*
Y1121446D03*
X539861D03*
X541711Y1124650D03*
X543561Y1127855D03*
X541711Y1131060D03*
X536162Y1134264D03*
X538012Y1131059D03*
X549589Y1580678D03*
X544633D03*
X549589Y1575592D03*
X544633D03*
X537529Y1575686D03*
Y1580678D03*
X549933Y1599790D03*
X537873Y1599884D03*
X542829D03*
X549589Y1592590D03*
X544633D03*
X549589Y1587598D03*
X544633D03*
X537529D03*
Y1592590D03*
X549933Y1611796D03*
Y1604876D03*
Y1616788D03*
X542829D03*
X537873D03*
Y1604876D03*
X542829D03*
X537873Y1611796D03*
X542829D03*
X544685Y1675383D03*
Y1679920D03*
X536811Y1679320D03*
X544685Y1684454D03*
Y1689556D03*
Y1694093D03*
Y1698627D03*
X536811Y1688391D03*
Y1693493D03*
Y1698030D03*
Y1683857D03*
X544685Y1703729D03*
Y1708266D03*
Y1712800D03*
X536811Y1707666D03*
Y1712203D03*
Y1702564D03*
X544685Y1726974D03*
Y1722440D03*
Y1717903D03*
X536811Y1730911D03*
Y1726377D03*
Y1721840D03*
Y1716737D03*
X551429Y979057D03*
X550701Y972608D03*
X550961Y1031727D03*
X556693Y1575686D03*
X561649D03*
X556693Y1580678D03*
X561649D03*
X561993Y1599884D03*
X554889Y1599790D03*
X556693Y1587598D03*
X561649D03*
Y1592590D03*
X556693D03*
X561993Y1616788D03*
Y1604876D03*
Y1611796D03*
X554889D03*
Y1604876D03*
Y1616788D03*
X552559Y1679320D03*
X564370Y1675383D03*
Y1679920D03*
X552559Y1688391D03*
Y1693493D03*
Y1698030D03*
Y1683857D03*
X564370Y1684454D03*
Y1689556D03*
Y1694093D03*
Y1698627D03*
X552559Y1707666D03*
Y1712203D03*
Y1702564D03*
X564370Y1703729D03*
Y1708266D03*
Y1712800D03*
X552559Y1730911D03*
Y1726377D03*
Y1721840D03*
Y1716737D03*
X564370Y1726974D03*
Y1722440D03*
Y1717903D03*
X580813Y1575686D03*
Y1580678D03*
X573709D03*
X568753D03*
Y1575686D03*
X573709D03*
X579009Y1599884D03*
X574053D03*
X566949D03*
X580813Y1587598D03*
Y1592590D03*
X573709D03*
X568753D03*
X573709Y1587598D03*
X568753D03*
X574053Y1616788D03*
X579009D03*
Y1611796D03*
X574053D03*
X579009Y1604876D03*
X574053D03*
X566949Y1616788D03*
Y1604876D03*
Y1611796D03*
X580118Y1675383D03*
Y1679920D03*
X572244Y1679320D03*
X580118Y1684454D03*
Y1689556D03*
Y1694093D03*
Y1698627D03*
X572244Y1688391D03*
Y1693493D03*
Y1698030D03*
Y1683857D03*
X580118Y1703729D03*
Y1708266D03*
Y1712800D03*
X572244Y1707666D03*
Y1712203D03*
Y1702564D03*
X580118Y1726974D03*
Y1722440D03*
Y1717903D03*
X572244Y1730911D03*
Y1726377D03*
Y1721840D03*
Y1716737D03*
X597829Y1580678D03*
X592873D03*
X597829Y1575686D03*
X592873D03*
X585769D03*
Y1580678D03*
X598173Y1599884D03*
X586113D03*
X591069D03*
X597829Y1592590D03*
X592873D03*
X597829Y1587598D03*
X592873D03*
X585769D03*
Y1592590D03*
X598173Y1616788D03*
Y1611796D03*
Y1604876D03*
X586113D03*
X591069D03*
X586113Y1611796D03*
X591069D03*
Y1616788D03*
X586113D03*
X595866Y1675383D03*
Y1679920D03*
X587992Y1679320D03*
X595866Y1684454D03*
Y1689556D03*
Y1694093D03*
Y1698627D03*
X587992Y1688391D03*
Y1693493D03*
Y1698030D03*
Y1683857D03*
X595866Y1703729D03*
Y1708266D03*
Y1712800D03*
X587992Y1707666D03*
Y1712203D03*
Y1702564D03*
X595866Y1726974D03*
Y1722440D03*
Y1717903D03*
X587992Y1730911D03*
Y1726377D03*
Y1721840D03*
Y1716737D03*
X609889Y1575686D03*
X604933D03*
X609889Y1580678D03*
X604933D03*
X615189Y1599884D03*
X610233D03*
X603129D03*
X609889Y1587598D03*
X604933D03*
X609889Y1592590D03*
X604933D03*
X615189Y1604876D03*
X610233D03*
X615189Y1611796D03*
X610233D03*
X615189Y1616788D03*
X610233D03*
X603129D03*
Y1611796D03*
Y1604876D03*
X611614Y1675383D03*
Y1679920D03*
X603740Y1679320D03*
X611614Y1684454D03*
Y1689556D03*
Y1694093D03*
Y1698627D03*
X603740Y1688391D03*
Y1693493D03*
Y1698030D03*
Y1683857D03*
X611614Y1703729D03*
Y1708266D03*
Y1712800D03*
X603740Y1707666D03*
Y1712203D03*
Y1702564D03*
X611614Y1726974D03*
Y1722440D03*
Y1717903D03*
X603740Y1730911D03*
Y1726377D03*
Y1721840D03*
Y1716737D03*
X629599Y770144D03*
X620899D03*
X629658Y766478D03*
X629599Y783530D03*
X620899D03*
X629599Y776837D03*
X620899D03*
X620846Y800263D03*
X629599D03*
Y793570D03*
X620899D03*
Y820341D03*
X629599D03*
X620076Y813648D03*
X630593D03*
X619632Y806955D03*
X630792D03*
X620899Y830381D03*
X629599D03*
X620005Y850459D03*
X630754D03*
X620899Y843766D03*
X629599D03*
Y837074D03*
X620899D03*
Y867192D03*
X629599D03*
X620058Y857152D03*
X630481D03*
X620899Y880577D03*
X629599D03*
X620899Y873885D03*
X629599D03*
X630756Y893963D03*
X620899D03*
X629599Y887270D03*
X620899D03*
Y910696D03*
X629599D03*
Y917389D03*
X620899D03*
X629599Y904003D03*
X620899D03*
X630399Y930697D03*
X619905Y930774D03*
X620899Y924081D03*
X629599D03*
Y947507D03*
X620899D03*
X619964Y940814D03*
X630777D03*
X629599Y964239D03*
X620899D03*
X629599Y954200D03*
X620899D03*
Y977625D03*
X629599D03*
Y970932D03*
X620899D03*
Y991011D03*
X629599D03*
Y984318D03*
X620899D03*
X623347Y999665D03*
X625780Y1000198D03*
X620899Y1031168D03*
X629599D03*
X620899Y1017782D03*
X629599D03*
X620899Y1024475D03*
X629599D03*
X620899Y1044554D03*
X629599D03*
X620899Y1037861D03*
X629599D03*
X620899Y1057940D03*
X629599D03*
Y1051247D03*
X620899D03*
Y1061286D03*
Y1078018D03*
X629599D03*
X630399Y1071326D03*
X619999D03*
X620899Y1064633D03*
X629599D03*
X620899Y1088058D03*
X629599D03*
Y1094751D03*
X620899D03*
Y1108137D03*
X629599D03*
Y1101444D03*
X620899D03*
X630363Y1124674D03*
X620369Y1124969D03*
X630399Y1114829D03*
X620099D03*
X620899Y1131562D03*
X629599D03*
Y1144948D03*
X620899D03*
X629599Y1138255D03*
X620899D03*
X620511Y1161680D03*
X629833Y1161581D03*
X629599Y1151641D03*
X620899D03*
X629599Y1175066D03*
X620899D03*
X629599Y1168373D03*
X620899D03*
X630623Y1188452D03*
X620899D03*
X629599Y1181759D03*
X620899D03*
X629599Y1205184D03*
X620899D03*
Y1198491D03*
X629599D03*
X620899Y1225263D03*
X629599D03*
Y1218570D03*
X620899D03*
X629599Y1211877D03*
X620899D03*
X629599Y1241995D03*
X620899D03*
X630922Y1235302D03*
X620036D03*
X620899Y1248688D03*
X629599D03*
X629931Y1258727D03*
X629699Y1255381D03*
X625246Y1273164D03*
X627646D03*
X631270Y1264942D03*
X629053Y1575686D03*
Y1580678D03*
X621949D03*
X616993D03*
X621949Y1575686D03*
X616993D03*
X622293Y1599884D03*
X627249D03*
X629053Y1587598D03*
Y1592590D03*
X621949D03*
X616993D03*
X621949Y1587598D03*
X616993D03*
X627249Y1616788D03*
X622293D03*
Y1611796D03*
X627249D03*
X622293Y1604876D03*
X627249D03*
X619488Y1679320D03*
Y1688391D03*
Y1693493D03*
Y1698030D03*
Y1683857D03*
Y1707666D03*
Y1712203D03*
Y1702564D03*
Y1730911D03*
Y1726377D03*
Y1721840D03*
Y1716737D03*
X637041Y766798D03*
X645741D03*
X650599D03*
X645741Y773491D03*
X637041D03*
X645741Y780184D03*
X637041D03*
Y803609D03*
X645741D03*
X637041Y796916D03*
X645741D03*
Y790223D03*
X637041D03*
X636221Y810302D03*
X646844D03*
X646774Y816995D03*
X637041D03*
X645741Y833727D03*
X637041D03*
Y827034D03*
X645741D03*
X637041Y847113D03*
X645801D03*
X637041Y840420D03*
X645741D03*
X646819Y853806D03*
X636332Y853955D03*
X645918Y863845D03*
X636266D03*
X637041Y877231D03*
X645741D03*
X637041Y870538D03*
X645741D03*
Y883924D03*
X637041D03*
Y900656D03*
X645741D03*
X637041Y890617D03*
X645741D03*
X637041Y914042D03*
X645741D03*
Y907349D03*
X637041D03*
X646393Y927526D03*
X636026Y927428D03*
X645741Y920735D03*
X637041D03*
X645741Y944160D03*
X637041D03*
X636170Y937467D03*
X646703D03*
X645741Y960892D03*
X637041D03*
Y950853D03*
X645741D03*
X636941Y957546D03*
Y954200D03*
X637041Y980971D03*
X645741D03*
X637041Y974278D03*
X645741D03*
X637041Y967585D03*
X645741D03*
X637041Y987664D03*
X645741D03*
X644347Y1003135D03*
X640327D03*
X640467Y1000735D03*
X647447Y1002865D03*
X647397Y1000135D03*
X644257Y1000325D03*
X637041Y1027822D03*
X645741D03*
Y1017782D03*
X637041D03*
X645741Y1047900D03*
X637041D03*
Y1041207D03*
X645741D03*
X637041Y1034515D03*
X645741D03*
X637041Y1061286D03*
X645741D03*
Y1054593D03*
X637041D03*
X636141Y1074672D03*
X646541D03*
X645741Y1067979D03*
X636841D03*
X637041Y1091404D03*
X645741D03*
Y1084711D03*
X636241D03*
X645741Y1111483D03*
X637041D03*
X645741Y1098097D03*
X637041D03*
X645741Y1104790D03*
X637041D03*
Y1121522D03*
X645741D03*
X637041Y1128915D03*
X645741Y1128215D03*
X646584Y1135108D03*
X635744Y1134908D03*
X645741Y1141601D03*
X637041D03*
X645741Y1148294D03*
X637041D03*
X645741Y1158333D03*
X637041D03*
Y1171719D03*
X645741D03*
Y1165026D03*
X637041D03*
Y1185105D03*
X645741D03*
Y1178412D03*
X637041D03*
X645741Y1208530D03*
X637041D03*
X645741Y1201837D03*
X637041D03*
Y1195144D03*
X645741D03*
X636005Y1221916D03*
X646570D03*
X645741Y1215223D03*
X637041D03*
X645741Y1238648D03*
X637041D03*
X635995Y1231862D03*
X646539Y1231955D03*
X645741Y1245341D03*
X637041D03*
X634213Y1258679D03*
X636946Y1258414D03*
X637041Y1252034D03*
X645897Y1248785D03*
X647877Y1254076D03*
X642746Y1273364D03*
X639946D03*
X636877Y1261235D03*
X646069Y1580678D03*
X641113D03*
X646069Y1575592D03*
X641113D03*
X634009Y1575686D03*
Y1580678D03*
X646413Y1599790D03*
X639309Y1599884D03*
X634353D03*
X646069Y1592590D03*
X641113D03*
X646069Y1587598D03*
X641113D03*
X634009D03*
Y1592590D03*
X646413Y1616788D03*
Y1611796D03*
Y1604876D03*
X639309D03*
X634353D03*
X639309Y1611796D03*
X634353D03*
Y1616788D03*
X639309D03*
X667677Y441636D03*
X650599Y770144D03*
X659299D03*
X650599Y783530D03*
X659299D03*
X650599Y776837D03*
X659299D03*
Y800263D03*
X650599D03*
Y793570D03*
X659299D03*
Y806955D03*
X650599D03*
X660432Y813648D03*
X650599D03*
X660199Y820341D03*
X650599D03*
X659299Y830381D03*
X650599D03*
X659299Y850459D03*
X650599D03*
X659299Y843766D03*
X650599D03*
Y837074D03*
X659299D03*
Y857152D03*
X650599D03*
X649563Y867192D03*
X660299D03*
X659299Y873885D03*
X650599D03*
Y880577D03*
X659299D03*
X650599Y893963D03*
X659299D03*
X650599Y887270D03*
X659299D03*
Y917389D03*
X650599D03*
X659299Y910696D03*
X650599D03*
Y904003D03*
X659299D03*
X660504Y924081D03*
X650599D03*
X660174Y930774D03*
X649661D03*
X659299Y947507D03*
X650599D03*
X659299Y940814D03*
X650599D03*
X659299Y964239D03*
X650599D03*
Y954200D03*
X659299D03*
Y977625D03*
X650599D03*
X659299Y970932D03*
X650599D03*
X659299Y991011D03*
X650599D03*
X659299Y984318D03*
X650599D03*
X650107Y1002825D03*
X659299Y1031168D03*
X650599D03*
X659299Y1017782D03*
X650599D03*
X659299Y1024475D03*
X650599D03*
X659299Y1044554D03*
X650599D03*
X659299Y1037861D03*
X650599D03*
X659299Y1051247D03*
X650599D03*
Y1057940D03*
X659299D03*
X660099Y1078018D03*
X649799D03*
X659299Y1071326D03*
X650599D03*
X659299Y1064633D03*
X650599D03*
X659299Y1094751D03*
X650599D03*
X660099Y1088058D03*
X649799D03*
X650599Y1108137D03*
X659299D03*
X650599Y1101444D03*
X659299D03*
X660199Y1124869D03*
X649932Y1124640D03*
X659299Y1114829D03*
X650599D03*
X659299Y1130762D03*
X650599D03*
X659299Y1138255D03*
X650599D03*
X659299Y1144948D03*
X650599D03*
X659299Y1151641D03*
X650599D03*
Y1161680D03*
X659299D03*
X650599Y1175066D03*
X659299D03*
X650599Y1168373D03*
X659299D03*
X650599Y1188452D03*
X659299D03*
X650599Y1181759D03*
X659299D03*
X650599Y1205184D03*
X659299D03*
X650599Y1198491D03*
X659299D03*
X660070Y1225263D03*
X649913D03*
X659299Y1218570D03*
X650599D03*
X659299Y1211877D03*
X650599D03*
X659299Y1241995D03*
X650599D03*
X660234Y1235302D03*
X649701D03*
X650599Y1248688D03*
X659299D03*
X659546Y1257664D03*
X650599Y1258727D03*
X666741Y1255381D03*
X656446Y1273364D03*
X653646D03*
X649587Y1266766D03*
X654606Y1431203D03*
X653173Y1575686D03*
X658129D03*
X653173Y1580678D03*
X658129D03*
X663429Y1599884D03*
X658473D03*
X651369Y1599790D03*
X653173Y1587598D03*
X658129D03*
X653173Y1592590D03*
X658129D03*
X663429Y1604876D03*
X658473D03*
X663429Y1611796D03*
X658473D03*
Y1616788D03*
X663429D03*
X651369D03*
Y1611796D03*
Y1604876D03*
X668329Y411714D03*
X674628Y424313D03*
X671479Y421163D03*
X667660Y429037D03*
X674628Y427462D03*
Y414864D03*
X677778D03*
Y424313D03*
X671479Y414864D03*
X674628Y421163D03*
Y418013D03*
X677778D03*
Y421163D03*
X668329D03*
X677778Y427462D03*
Y430612D03*
X674628Y436911D03*
Y443210D03*
X671479Y430612D03*
Y436911D03*
X677778Y433761D03*
X668329Y436911D03*
X677778Y440061D03*
X674628D03*
X677778Y436911D03*
Y443210D03*
X680928Y440061D03*
X674628Y430612D03*
X671479Y443211D03*
Y462108D03*
X677778Y449510D03*
X668329Y452659D03*
X674628D03*
X671479D03*
X677778D03*
X668329Y455809D03*
X671479Y458959D03*
X674628D03*
X668329D03*
X677778D03*
Y455809D03*
X674628D03*
X668067Y462090D03*
X677778Y462108D03*
X671479Y455809D03*
X680928Y458959D03*
X674628Y449510D03*
Y462108D03*
X677778Y477856D03*
Y471557D03*
Y474707D03*
X671479Y465258D03*
X674628D03*
X668329D03*
X677778D03*
Y468407D03*
X671479Y481006D03*
X667350Y470680D03*
X671479Y474707D03*
X674628Y484006D03*
X668329Y481006D03*
X680299Y770144D03*
X675441Y766798D03*
X666741D03*
X680299D03*
Y783530D03*
Y776837D03*
X666741Y773491D03*
X675441D03*
X666741Y780184D03*
X675441D03*
Y803609D03*
X666741D03*
X680299Y800263D03*
Y793570D03*
X666741Y796916D03*
X675441D03*
X666741Y790223D03*
X675441D03*
X676403Y816995D03*
X665803D03*
X675441Y810302D03*
X666741D03*
X680299Y820341D03*
Y813648D03*
Y806955D03*
X675441Y833727D03*
X666741D03*
X676625Y827034D03*
X665876D03*
X680299Y830381D03*
X675441Y847113D03*
X666741D03*
X680299Y850459D03*
Y843766D03*
Y837074D03*
X666741Y840420D03*
X675441D03*
X676417Y853806D03*
X665890D03*
X680299Y867192D03*
Y857152D03*
X665916Y863845D03*
X676600D03*
X675441Y877231D03*
X666741D03*
X675441Y870538D03*
X666741D03*
Y883924D03*
X675441D03*
X680299Y880577D03*
Y873885D03*
X666741Y900656D03*
X675441D03*
X680299Y893963D03*
Y887270D03*
X666741Y890617D03*
X675441D03*
Y914042D03*
X666741D03*
X680299Y917389D03*
Y910696D03*
Y904003D03*
X666741Y907349D03*
X675441D03*
X676488Y927428D03*
X665896D03*
X675441Y920735D03*
X666741D03*
X680299Y930774D03*
Y924081D03*
X675441Y944160D03*
X666741D03*
X676359Y937467D03*
X665923D03*
X680299Y947507D03*
Y940814D03*
Y964239D03*
X675441Y960892D03*
X666741D03*
X680299Y954200D03*
X666741Y950853D03*
X675441D03*
X666641Y957546D03*
Y954200D03*
X675441Y980971D03*
X666741D03*
X680299Y970932D03*
X675441Y974278D03*
X666741D03*
X675441Y967585D03*
X666741D03*
X680299Y977625D03*
X675441Y987664D03*
X666741D03*
X680299Y991011D03*
Y984318D03*
X672063Y998632D03*
X680299Y1031168D03*
Y1024475D03*
X675441Y1027822D03*
X666741D03*
X675441Y1017782D03*
X666741D03*
X680299D03*
X675441Y1047900D03*
X666741D03*
X680299Y1037861D03*
X675441Y1041207D03*
X666741D03*
X675441Y1034515D03*
X666741D03*
X680299Y1044554D03*
Y1057940D03*
Y1051247D03*
X675441Y1054593D03*
X666741D03*
Y1061286D03*
X675441D03*
X680299D03*
X676341Y1074672D03*
X665841D03*
X675441Y1067979D03*
X666741D03*
X680299Y1078018D03*
Y1071326D03*
Y1064633D03*
X675441Y1091404D03*
X666741D03*
X676241Y1084711D03*
X665941D03*
X680299Y1094751D03*
Y1088058D03*
X666741Y1111483D03*
X675441D03*
X680299Y1108137D03*
Y1101444D03*
X666741Y1104790D03*
X675441D03*
X666741Y1098097D03*
X675441D03*
X666741Y1128215D03*
X675441D03*
X680299Y1124869D03*
Y1114829D03*
X666741Y1121522D03*
X675441D03*
X680299Y1144948D03*
Y1138255D03*
Y1131562D03*
X666741Y1141601D03*
X675441D03*
X666741Y1134908D03*
X675441D03*
X676652Y1148294D03*
X665602D03*
X676241Y1158333D03*
X665941D03*
X680299Y1161680D03*
Y1151641D03*
X675441Y1165026D03*
X666741D03*
X680299Y1175066D03*
Y1168373D03*
X666741Y1171719D03*
X675441D03*
X680299Y1188452D03*
Y1181759D03*
X666741Y1185105D03*
X675441D03*
X666741Y1178412D03*
X675441D03*
X680299Y1205184D03*
Y1198491D03*
X666741Y1208530D03*
X675441D03*
X666741Y1201837D03*
X675441D03*
X666741Y1195144D03*
X675441D03*
X680299Y1218570D03*
Y1225263D03*
X676448Y1221916D03*
X665651D03*
X675441Y1215223D03*
X666741D03*
X680299Y1211877D03*
X675441Y1238648D03*
X666741D03*
X676462Y1231955D03*
X665912D03*
X680299Y1241995D03*
Y1235302D03*
X675441Y1245341D03*
X666741D03*
X676046Y1257964D03*
X680299Y1248688D03*
Y1258727D03*
X666741Y1252034D03*
X675537Y1248885D03*
X672446Y1273364D03*
X669646D03*
X666741Y1262074D03*
X666646Y1264464D03*
X680046Y1264964D03*
X695055Y112678D03*
Y115178D03*
X684077Y414864D03*
X680928Y424313D03*
X687227Y414864D03*
X690376Y421163D03*
Y418013D03*
Y414864D03*
X693526Y427462D03*
X687227Y424313D03*
X690376Y427462D03*
X680928Y414864D03*
Y418013D03*
X684077Y421163D03*
X680928Y427462D03*
X684077Y418013D03*
Y427462D03*
X680928Y421163D03*
X684077Y424313D03*
X687227Y427462D03*
X696676D03*
X693526Y421163D03*
Y424313D03*
X690376D03*
X696676Y421163D03*
Y424313D03*
Y418013D03*
Y436911D03*
X693526Y443210D03*
Y440061D03*
Y436911D03*
X690376Y440061D03*
Y433761D03*
X680928Y436911D03*
Y433761D03*
X693526Y430612D03*
X696676Y440061D03*
Y443210D03*
X684077Y430612D03*
Y440061D03*
X687227Y436911D03*
Y443210D03*
X684077D03*
Y436911D03*
X680928Y443210D03*
X690376Y436911D03*
Y443210D03*
X687227Y440061D03*
X693526Y433761D03*
X696676D03*
X684077D03*
X687227Y430612D03*
X690376D03*
X696676D03*
X687227Y433761D03*
X680928Y430612D03*
X687227Y462108D03*
X693526Y452659D03*
Y449510D03*
X696676Y455809D03*
X693526D03*
X690376Y452659D03*
Y458959D03*
X680928Y455809D03*
X693526Y462108D03*
X680928Y449510D03*
X687227D03*
X690376Y462108D03*
X684077Y449510D03*
X680928Y452659D03*
X684077D03*
X687227Y455809D03*
X684077D03*
X680928Y462108D03*
X696676Y449510D03*
Y452659D03*
X690376Y449510D03*
Y455809D03*
X687227Y452659D03*
X693526Y458959D03*
X696676D03*
Y462108D03*
X687227Y458959D03*
X684077D03*
Y468407D03*
X687227Y471557D03*
Y474707D03*
Y477856D03*
X684077Y471557D03*
X690376Y465258D03*
X684077D03*
X680928Y471557D03*
Y474707D03*
Y477856D03*
X696676D03*
X684077D03*
X680928Y468407D03*
X693526Y465258D03*
Y471557D03*
X690376Y468407D03*
Y477856D03*
Y471557D03*
X687227Y465258D03*
X690376Y474707D03*
X687227Y468407D03*
X693526D03*
X684077Y474707D03*
X696676Y465258D03*
Y474707D03*
Y468407D03*
X693526Y474707D03*
X696676Y471557D03*
X693526Y477856D03*
X696441Y766798D03*
X688999Y770144D03*
X696441Y773491D03*
Y780184D03*
X688999Y783530D03*
Y776837D03*
X696441Y803609D03*
Y796916D03*
Y790223D03*
X688999Y800263D03*
Y793570D03*
X696441Y816995D03*
Y810302D03*
X689888Y820341D03*
X688999Y813648D03*
Y806955D03*
X696441Y833727D03*
Y827034D03*
X688999Y830381D03*
X696441Y847113D03*
X688999Y850459D03*
X696441Y840420D03*
X688999Y843766D03*
Y837074D03*
X696441Y863845D03*
Y853806D03*
X688999Y867192D03*
X689896Y857152D03*
X696441Y883924D03*
Y877231D03*
Y870538D03*
X688999Y880577D03*
Y873885D03*
X696441Y900656D03*
Y890617D03*
X688999Y893963D03*
Y887270D03*
X696441Y914042D03*
Y907349D03*
X688999Y917389D03*
Y910696D03*
Y904003D03*
X696441Y927428D03*
Y920735D03*
X690104Y930774D03*
X688999Y924081D03*
X696441Y944160D03*
Y937467D03*
X688999Y947507D03*
Y940814D03*
X696441Y960892D03*
Y950853D03*
X688999Y964239D03*
Y954200D03*
X696441Y957546D03*
Y954200D03*
Y980971D03*
Y974278D03*
Y967585D03*
X688999Y970932D03*
Y977625D03*
X696441Y987664D03*
X688999Y991011D03*
Y984318D03*
X696441Y994357D03*
Y1027822D03*
Y1017782D03*
X688999Y1031168D03*
Y1024475D03*
Y1017782D03*
X696441Y1047900D03*
Y1041207D03*
Y1034515D03*
X688999Y1037861D03*
Y1044554D03*
X696441Y1054593D03*
Y1061286D03*
X688999Y1057940D03*
Y1051247D03*
X696441Y1074672D03*
Y1067979D03*
X688999Y1077118D03*
Y1071326D03*
Y1064633D03*
X696441Y1091404D03*
Y1084711D03*
X688999Y1094751D03*
Y1088058D03*
X696441Y1111483D03*
Y1104790D03*
Y1098097D03*
X688999Y1108137D03*
Y1101444D03*
X696441Y1128215D03*
Y1121522D03*
X688999Y1124869D03*
Y1114829D03*
X696441Y1141601D03*
Y1134908D03*
X688999Y1144948D03*
Y1138255D03*
Y1131562D03*
X696441Y1158333D03*
Y1148294D03*
X688999Y1161680D03*
X689999Y1151641D03*
X696441Y1171719D03*
Y1165026D03*
X688999Y1175066D03*
Y1168373D03*
X696441Y1185105D03*
Y1178412D03*
X688999Y1188452D03*
Y1181759D03*
X696441Y1208530D03*
Y1201837D03*
Y1195144D03*
X688999Y1205184D03*
Y1198491D03*
X696441Y1221916D03*
Y1215223D03*
X688999Y1218570D03*
X689799Y1225263D03*
X688999Y1211877D03*
X696441Y1238648D03*
Y1231955D03*
X688999Y1241995D03*
Y1235302D03*
X688916Y1256964D03*
X696441Y1245341D03*
X688999Y1248688D03*
X696441Y1255381D03*
Y1248688D03*
X686146Y1273364D03*
X683346D03*
X696046Y1263764D03*
X698598Y115178D03*
X705685D03*
X702141D03*
X698598Y112678D03*
X705685D03*
X702141D03*
X706125Y421163D03*
X702975Y414864D03*
X706125Y418013D03*
X712424Y424313D03*
X699825Y427462D03*
X699826Y414864D03*
X699825Y424313D03*
X709274Y436911D03*
X706125Y440061D03*
Y436911D03*
X699825Y440061D03*
Y436911D03*
X712424Y443210D03*
Y440061D03*
Y436911D03*
Y430612D03*
X709274Y440061D03*
Y443210D03*
X706125D03*
X699825D03*
X709274Y433761D03*
X712424D03*
X699825D03*
X706125D03*
X699825Y430612D03*
X706125Y462108D03*
X709274D03*
X712424D03*
Y455809D03*
X709274D03*
X706125D03*
Y452659D03*
X699825Y455809D03*
Y452659D03*
X712424D03*
Y449510D03*
X709274D03*
X699825D03*
X706125D03*
X709274Y452659D03*
X699825Y458959D03*
X706125D03*
X709274D03*
X712424D03*
X699825Y462108D03*
X709274Y474707D03*
Y471557D03*
Y465258D03*
Y468407D03*
X712424Y474707D03*
Y468407D03*
Y465258D03*
X709274Y477856D03*
X699825Y468407D03*
X706125Y471557D03*
Y468407D03*
X699825Y471557D03*
Y474707D03*
X706125Y477856D03*
X699825Y465258D03*
X712424Y471557D03*
X706125Y481006D03*
X709999Y770144D03*
X705141Y766798D03*
X709899D03*
X709999Y783530D03*
Y776837D03*
X705141Y773491D03*
Y780184D03*
X709999Y800263D03*
Y793570D03*
X705141Y803609D03*
Y796916D03*
Y790223D03*
X709999Y820341D03*
Y813648D03*
Y806955D03*
X705141Y816995D03*
Y810302D03*
X709999Y830381D03*
X705141Y833727D03*
Y827034D03*
Y847113D03*
X709999Y850459D03*
Y843766D03*
Y837074D03*
X705141Y840420D03*
Y863845D03*
Y853806D03*
X709999Y867192D03*
Y857152D03*
X705141Y883924D03*
Y877231D03*
Y870538D03*
X709999Y880577D03*
Y873885D03*
X705141Y900656D03*
Y890617D03*
X709999Y893963D03*
Y887270D03*
X705141Y914042D03*
Y907349D03*
X709999Y917389D03*
Y910696D03*
Y904003D03*
X705141Y927428D03*
Y920735D03*
X709999Y930774D03*
Y924081D03*
X705141Y944160D03*
Y937467D03*
X709999Y947507D03*
Y940814D03*
X705141Y960892D03*
Y950853D03*
X709999Y964239D03*
Y954200D03*
X705141Y980971D03*
Y974278D03*
Y967585D03*
X709999Y977625D03*
Y970932D03*
X705141Y987664D03*
X709999Y991011D03*
Y984318D03*
X705141Y1027822D03*
Y1017782D03*
X709999Y1031168D03*
Y1024475D03*
Y1017782D03*
X705141Y1047900D03*
Y1041207D03*
Y1034515D03*
X709999Y1044554D03*
Y1037861D03*
X705141Y1054593D03*
Y1061286D03*
X709999Y1057940D03*
Y1051247D03*
X705141Y1074672D03*
Y1067979D03*
X709999Y1078018D03*
Y1071326D03*
Y1064633D03*
X705141Y1091404D03*
Y1084711D03*
X709999Y1094751D03*
Y1088058D03*
X705141Y1111483D03*
Y1104790D03*
Y1098097D03*
X709999Y1108137D03*
Y1101444D03*
X705141Y1128215D03*
Y1121522D03*
X709999Y1124869D03*
Y1114829D03*
X705141Y1141601D03*
Y1134908D03*
X709999Y1144948D03*
Y1138255D03*
Y1131562D03*
X705141Y1158333D03*
Y1148294D03*
X709999Y1161680D03*
Y1151641D03*
X705141Y1171719D03*
Y1165026D03*
X709999Y1175066D03*
Y1168373D03*
X705141Y1185105D03*
Y1178412D03*
X709999Y1188452D03*
Y1181759D03*
X705141Y1208530D03*
Y1201837D03*
Y1195144D03*
X709999Y1205184D03*
Y1198491D03*
X705141Y1221916D03*
Y1215223D03*
X709999Y1225263D03*
Y1218570D03*
Y1211877D03*
X705141Y1238648D03*
Y1231955D03*
X709999Y1241995D03*
Y1235302D03*
X705141Y1245341D03*
X709999Y1248688D03*
Y1258727D03*
X705037Y1252034D03*
X706493Y1256563D03*
X713046Y1273364D03*
X702146D03*
X699346D03*
X705167Y1262074D03*
X709977Y1264985D03*
X721873Y427462D03*
X725022D03*
X728172Y418013D03*
X725022Y414864D03*
X718723Y418013D03*
X715574Y427462D03*
X728172Y421163D03*
X718723Y414864D03*
X725022Y424313D03*
X721873D03*
X725022Y421163D03*
X728172Y427462D03*
X731322Y421163D03*
X725022Y418013D03*
X718723Y427462D03*
Y424313D03*
Y421163D03*
X715574Y424313D03*
Y421163D03*
Y418013D03*
X728172Y424313D03*
X718723Y436911D03*
X721873Y433761D03*
Y436911D03*
Y440061D03*
Y430612D03*
X718723Y433761D03*
Y440061D03*
X725022Y436911D03*
Y433761D03*
X728172D03*
X715574D03*
X718723Y430612D03*
X715574D03*
X725022D03*
X728172Y436911D03*
X715574D03*
Y440061D03*
Y443210D03*
X728172D03*
Y430612D03*
X725022Y440061D03*
X718723Y443210D03*
X721873D03*
X725022D03*
X728172Y440061D03*
X731322D03*
X728172Y455809D03*
Y458959D03*
X718723Y455809D03*
X721873Y458959D03*
X715574D03*
X728172Y449510D03*
X721873Y452659D03*
X725022D03*
X728172D03*
X715574Y462108D03*
X725022Y458959D03*
X721873Y455809D03*
X725022Y462108D03*
X718723Y452659D03*
X715574Y449510D03*
Y452659D03*
Y455809D03*
X728172Y462108D03*
X718723Y449510D03*
X721873D03*
X725022D03*
X718723Y458959D03*
X721873Y462108D03*
X718723D03*
X725022Y468407D03*
X721873Y465258D03*
Y477856D03*
X725022D03*
X718723Y468407D03*
X715574Y474707D03*
Y471557D03*
Y468407D03*
Y465258D03*
X718723Y474707D03*
Y471557D03*
X728172Y477856D03*
X721873Y471557D03*
X725022D03*
X718723Y465258D03*
X728172D03*
X725022Y474707D03*
X728172Y468407D03*
X721873Y474707D03*
Y468407D03*
X728172Y474707D03*
Y471557D03*
X725022Y465258D03*
X718723Y477856D03*
X725132Y481116D03*
X728272Y481006D03*
X726141Y766798D03*
X718699Y770144D03*
X726141Y773491D03*
Y780184D03*
X718699Y783530D03*
Y776837D03*
X726141Y803609D03*
Y796916D03*
Y790223D03*
X718699Y800263D03*
Y793570D03*
X726141Y816995D03*
Y810302D03*
X718699Y820341D03*
Y813648D03*
Y806955D03*
X726141Y833727D03*
Y827034D03*
X718699Y830381D03*
X726141Y847113D03*
Y840420D03*
X718699Y850459D03*
Y843766D03*
Y837074D03*
X726141Y863845D03*
Y853806D03*
X718699Y867192D03*
Y857152D03*
X726141Y883924D03*
Y877231D03*
Y870538D03*
X718699Y880577D03*
Y873885D03*
X726141Y900656D03*
Y890617D03*
X718699Y893963D03*
Y887270D03*
X726141Y914042D03*
Y907349D03*
X718699Y917389D03*
Y910696D03*
Y904003D03*
X726141Y927428D03*
Y920735D03*
X718699Y930774D03*
Y924081D03*
X726141Y944160D03*
Y937467D03*
X718699Y947507D03*
Y940814D03*
X726141Y960892D03*
Y950853D03*
X718699Y964239D03*
Y954200D03*
X726041Y957546D03*
Y954200D03*
X726141Y980971D03*
Y974278D03*
Y967585D03*
X718699Y977625D03*
Y970932D03*
X726141Y987664D03*
X718699Y991011D03*
Y984318D03*
X726041Y994357D03*
X726141Y1027822D03*
Y1017782D03*
X718699Y1031168D03*
Y1024475D03*
Y1017782D03*
X726141Y1047900D03*
Y1041207D03*
Y1034515D03*
X718699Y1044554D03*
Y1037861D03*
X726141Y1061286D03*
Y1054593D03*
X718699Y1057940D03*
Y1051247D03*
X726141Y1057940D03*
Y1074672D03*
Y1067979D03*
X718699Y1078018D03*
Y1071326D03*
Y1064633D03*
X726141Y1091404D03*
Y1084711D03*
X718699Y1094751D03*
Y1088058D03*
X726141Y1111483D03*
Y1104790D03*
Y1098097D03*
X718699Y1108137D03*
Y1101444D03*
X726141Y1128215D03*
Y1121522D03*
X718699Y1124869D03*
Y1114829D03*
X726141Y1141601D03*
Y1134908D03*
X718699Y1144948D03*
Y1138255D03*
Y1131562D03*
X726141Y1158333D03*
Y1148294D03*
X718699Y1161680D03*
Y1151641D03*
X726141Y1171719D03*
Y1165026D03*
X718699Y1175066D03*
Y1168373D03*
X726141Y1185105D03*
Y1178412D03*
X718699Y1188452D03*
Y1181759D03*
X726141Y1208530D03*
Y1201837D03*
Y1195144D03*
X718699Y1205184D03*
Y1198491D03*
X726141Y1221916D03*
Y1215223D03*
X718699Y1225263D03*
Y1218570D03*
Y1211877D03*
X726141Y1238648D03*
Y1231955D03*
X718699Y1241995D03*
Y1235302D03*
X726141Y1245341D03*
X719046Y1257064D03*
X718699Y1248688D03*
X726141Y1255381D03*
Y1248688D03*
X729046Y1273364D03*
X715846D03*
X726141Y1262074D03*
X726107Y1265420D03*
X737621Y411714D03*
X734471Y418013D03*
X731322Y427462D03*
Y418013D03*
X734471Y421163D03*
X731322Y424313D03*
X734471D03*
X737621D03*
X731322Y414864D03*
Y433761D03*
Y430612D03*
X734471Y436911D03*
X731322D03*
X734471Y443210D03*
X737621D03*
X731322D03*
Y455809D03*
X737621Y458959D03*
X731322D03*
Y462108D03*
X734471Y452659D03*
X731322D03*
Y449510D03*
X734471Y458959D03*
X731322Y465258D03*
Y477856D03*
X737621Y471557D03*
X734471Y468407D03*
X731322D03*
X731321Y474707D03*
X731322Y471557D03*
X737621Y481006D03*
X734471D03*
X739699Y770144D03*
X734841Y766798D03*
X739699D03*
Y783530D03*
Y776837D03*
X734841Y773491D03*
Y780184D03*
X739699Y800263D03*
Y793570D03*
X734841Y803609D03*
Y796916D03*
Y790223D03*
X739699Y820341D03*
Y813648D03*
Y806955D03*
X734841Y816995D03*
Y810302D03*
X739699Y830381D03*
X734841Y833727D03*
Y827034D03*
X739699Y850459D03*
Y843766D03*
Y837074D03*
X734841Y847113D03*
Y840420D03*
X739699Y867192D03*
Y857152D03*
X734841Y863845D03*
Y853806D03*
X739699Y880577D03*
Y873885D03*
X734841Y883924D03*
Y877231D03*
Y870538D03*
X739699Y893963D03*
Y887270D03*
X734841Y900656D03*
Y890617D03*
X739699Y917389D03*
Y910696D03*
Y904003D03*
X734841Y914042D03*
Y907349D03*
X739699Y930774D03*
Y924081D03*
X734841Y927428D03*
Y920735D03*
X739699Y947507D03*
Y940814D03*
X734841Y944160D03*
Y937467D03*
X739699Y964239D03*
Y954200D03*
X734841Y960892D03*
Y950853D03*
X739699Y977625D03*
Y970932D03*
X734841Y980971D03*
Y974278D03*
Y967585D03*
X739699Y991011D03*
Y984318D03*
X734841Y987664D03*
X739699Y1031168D03*
Y1024475D03*
Y1017782D03*
X734841Y1027822D03*
Y1017782D03*
X739699Y1044554D03*
Y1037861D03*
X734841Y1047900D03*
Y1041207D03*
Y1034515D03*
X739699Y1057940D03*
Y1051247D03*
X734841Y1061286D03*
Y1054593D03*
X739699Y1061286D03*
Y1078018D03*
Y1071326D03*
Y1064633D03*
X734841Y1074672D03*
Y1067979D03*
X739699Y1094751D03*
Y1088058D03*
X734841Y1091404D03*
Y1084711D03*
X739699Y1108137D03*
Y1101444D03*
X734841Y1111483D03*
Y1104790D03*
Y1098097D03*
X739699Y1124869D03*
Y1114829D03*
X734841Y1128215D03*
Y1121522D03*
X739699Y1144948D03*
Y1138255D03*
Y1131562D03*
X734841Y1141601D03*
Y1134908D03*
X739699Y1161680D03*
Y1151641D03*
X734841Y1158333D03*
Y1148294D03*
X739699Y1175066D03*
Y1168373D03*
X734841Y1171719D03*
Y1165026D03*
X739699Y1188452D03*
Y1181759D03*
X734841Y1185105D03*
Y1178412D03*
X739699Y1205184D03*
Y1198491D03*
X734841Y1208530D03*
Y1201837D03*
Y1195144D03*
X739699Y1225263D03*
Y1218570D03*
Y1211877D03*
X734841Y1221916D03*
Y1215223D03*
X739699Y1241995D03*
Y1235302D03*
X734841Y1238648D03*
Y1231955D03*
X739699Y1248688D03*
X734841Y1245341D03*
X739699Y1258727D03*
X734967Y1252034D03*
X745546Y1273364D03*
X742746D03*
X731372Y1273464D03*
X739697Y1265420D03*
X755841Y766798D03*
X748399Y770144D03*
X755841Y780184D03*
Y773491D03*
X748399Y783530D03*
Y776837D03*
X755841Y803609D03*
Y796916D03*
Y790223D03*
X748399Y800263D03*
Y793570D03*
X755841Y816995D03*
Y810302D03*
X748399Y820341D03*
Y813648D03*
Y806955D03*
X755841Y833727D03*
Y827034D03*
X748399Y830381D03*
X755841Y847113D03*
Y840420D03*
X748399Y850459D03*
Y843766D03*
Y837074D03*
X755841Y863845D03*
Y853806D03*
X748399Y867192D03*
Y857152D03*
X755841Y883924D03*
Y877231D03*
Y870538D03*
X748399Y880577D03*
Y873885D03*
X755841Y900656D03*
Y890617D03*
X748399Y893963D03*
Y887270D03*
X755841Y914042D03*
Y907349D03*
X748399Y917389D03*
Y910696D03*
Y904003D03*
X755841Y927428D03*
Y920735D03*
X748399Y930774D03*
Y924081D03*
X755841Y944160D03*
Y937467D03*
X748399Y947507D03*
Y940814D03*
X755841Y960892D03*
Y950853D03*
X748399Y964239D03*
Y954200D03*
X755841Y957546D03*
Y954200D03*
Y980971D03*
Y974278D03*
Y967585D03*
X748399Y977625D03*
Y970932D03*
X755841Y987664D03*
X748399Y991011D03*
Y984318D03*
X755841Y994357D03*
Y1027822D03*
Y1017782D03*
X748399Y1031168D03*
Y1024475D03*
Y1017782D03*
X755841Y1047900D03*
Y1041207D03*
Y1034515D03*
X748399Y1044554D03*
Y1037861D03*
X755841Y1054593D03*
Y1061286D03*
X748399Y1057940D03*
Y1051247D03*
X755541Y1057940D03*
X755841Y1067979D03*
Y1074672D03*
X748399Y1078018D03*
Y1071326D03*
Y1064633D03*
X755841Y1084711D03*
Y1091404D03*
X748399Y1094751D03*
Y1088058D03*
X755841Y1111483D03*
Y1104790D03*
Y1098097D03*
X748399Y1108137D03*
Y1101444D03*
X755841Y1128215D03*
Y1121522D03*
X748399Y1124869D03*
Y1114829D03*
X755841Y1141601D03*
Y1134908D03*
X748399Y1144948D03*
Y1138255D03*
Y1131562D03*
X755841Y1158333D03*
Y1148294D03*
X748399Y1161680D03*
Y1151641D03*
X755841Y1171719D03*
Y1165026D03*
X748399Y1175066D03*
Y1168373D03*
X755841Y1185105D03*
Y1178412D03*
X748399Y1188452D03*
Y1181759D03*
X755841Y1208530D03*
Y1201837D03*
Y1195144D03*
X748399Y1205184D03*
Y1198491D03*
X755841Y1221916D03*
Y1215223D03*
X748399Y1225263D03*
Y1218570D03*
Y1211877D03*
X755841Y1238648D03*
Y1231955D03*
X748399Y1241995D03*
Y1235302D03*
X755841Y1245341D03*
X748283Y1256964D03*
X748399Y1248688D03*
X750890Y1248500D03*
X755890Y1255381D03*
X755841Y1252034D03*
Y1248688D03*
X750040Y1254179D03*
X758746Y1273364D03*
X761546D03*
X755841Y1262074D03*
X755797Y1265420D03*
X769399Y770144D03*
X778099D03*
X764541Y766798D03*
X769399D03*
Y783530D03*
X778099D03*
X769399Y776837D03*
X778099D03*
X764541Y780184D03*
Y773491D03*
X769399Y800263D03*
X778099D03*
X769399Y793570D03*
X778099D03*
X764541Y803609D03*
Y796916D03*
Y790223D03*
X769399Y820341D03*
X778099D03*
X769399Y813648D03*
X778099D03*
X769399Y806955D03*
X778099D03*
X764541Y816995D03*
Y810302D03*
X769399Y830381D03*
X778099D03*
X764541Y833727D03*
Y827034D03*
X769399Y850459D03*
X778099D03*
Y843766D03*
X769399D03*
Y837074D03*
X778099D03*
X764541Y847113D03*
Y840420D03*
X778099Y867192D03*
X769399D03*
Y857152D03*
X778099D03*
X764541Y863845D03*
Y853806D03*
X769399Y880577D03*
X778099D03*
X769399Y873885D03*
X778099D03*
X764541Y883924D03*
Y877231D03*
Y870538D03*
X778099Y893963D03*
X769399D03*
Y887270D03*
X778099D03*
X764541Y900656D03*
Y890617D03*
X769399Y917389D03*
X778099D03*
X769399Y910696D03*
X778099D03*
X769399Y904003D03*
X778099D03*
X764541Y914042D03*
Y907349D03*
X769399Y930774D03*
X778099D03*
X769399Y924081D03*
X778099D03*
X764541Y927428D03*
Y920735D03*
X769399Y947507D03*
X778099D03*
X769399Y940814D03*
X778099D03*
X764541Y944160D03*
Y937467D03*
X769399Y964239D03*
X778099D03*
X769399Y954200D03*
X778099D03*
X764541Y960892D03*
Y950853D03*
X769399Y977625D03*
X778099D03*
X769399Y970932D03*
X778099D03*
X764541Y980971D03*
Y974278D03*
Y967585D03*
X769399Y991011D03*
X778099D03*
X769399Y984318D03*
X778099D03*
X764541Y987664D03*
X769399Y1031168D03*
X778099D03*
X769399Y1024475D03*
X778099D03*
X769399Y1017782D03*
X778099D03*
X764541Y1027822D03*
Y1017782D03*
X778099Y1044554D03*
X769399D03*
Y1037861D03*
X778099D03*
X764541Y1047900D03*
Y1041207D03*
Y1034515D03*
X769399Y1057940D03*
X778099D03*
X769399Y1051247D03*
X778099D03*
X764541Y1054593D03*
Y1061286D03*
X778099Y1078018D03*
X769399D03*
X778099Y1071326D03*
X769399D03*
Y1064633D03*
X778099D03*
X764541Y1067979D03*
Y1074672D03*
X778099Y1094751D03*
X769399D03*
X778099Y1088058D03*
X769399D03*
X764541Y1084711D03*
Y1091404D03*
X778099Y1108137D03*
X769399D03*
X778099Y1101444D03*
X769399D03*
X764541Y1111483D03*
Y1104790D03*
Y1098097D03*
X778099Y1124869D03*
X769399D03*
X778099Y1114829D03*
X769399D03*
X764541Y1128215D03*
Y1121522D03*
X778099Y1144948D03*
X769399D03*
X778099Y1138255D03*
X769399D03*
X778099Y1131562D03*
X769399D03*
X764541Y1141601D03*
Y1134908D03*
X778099Y1161680D03*
X769399D03*
X778099Y1151641D03*
X769399D03*
X764541Y1158333D03*
Y1148294D03*
X778099Y1175066D03*
X769399D03*
X778099Y1168373D03*
X769399D03*
X764541Y1171719D03*
Y1165026D03*
X778099Y1188452D03*
X769399D03*
X778099Y1181759D03*
X769399D03*
X764541Y1185105D03*
Y1178412D03*
X769399Y1205184D03*
X778099D03*
Y1198491D03*
X769399D03*
X764541Y1208530D03*
Y1201837D03*
Y1195144D03*
X778099Y1225263D03*
X769399D03*
X778099Y1218570D03*
X769399D03*
Y1211877D03*
X778099D03*
X764541Y1221916D03*
Y1215223D03*
X778099Y1241995D03*
X769399D03*
X778099Y1235302D03*
X769399D03*
X764541Y1238648D03*
Y1231955D03*
X778346Y1257264D03*
X778099Y1248688D03*
X769399D03*
X764541Y1245341D03*
X769399Y1258727D03*
X766148Y1255882D03*
X772446Y1273364D03*
X775246D03*
X769399Y1265420D03*
X785541Y766798D03*
X794241D03*
X785541Y773491D03*
X794241D03*
X785541Y780184D03*
X794241D03*
X785541Y803609D03*
X794241D03*
X785541Y790223D03*
X794241D03*
X785541Y796916D03*
X794241D03*
X785541Y816995D03*
X794241D03*
X785541Y810302D03*
X794241D03*
X785541Y833727D03*
X794241D03*
X785541Y827034D03*
X794241D03*
X785541Y840420D03*
X794241D03*
X785541Y847113D03*
X794241D03*
X785541Y853806D03*
X794241D03*
X785541Y863845D03*
X794241D03*
X785541Y883924D03*
X794241D03*
X785541Y870538D03*
X794241D03*
X785541Y877231D03*
X794241D03*
X785541Y900656D03*
X794241D03*
X785541Y890617D03*
X794241D03*
X785541Y907349D03*
X794241D03*
X785541Y914042D03*
X794241D03*
X785541Y920735D03*
X794241D03*
X785541Y927428D03*
X794241D03*
X785541Y937467D03*
X794241D03*
X785541Y944160D03*
X794241D03*
X785541Y960892D03*
X794241D03*
X785541Y950853D03*
X794241D03*
X785541Y957546D03*
Y954200D03*
Y980971D03*
X794241D03*
X785541Y974278D03*
X794241D03*
X785541Y967585D03*
X794241D03*
X785541Y987664D03*
X794241D03*
X785541Y994357D03*
Y1027822D03*
X794241D03*
X785541Y1017782D03*
X794241D03*
X785541Y1047900D03*
X794241D03*
X785541Y1041207D03*
X794241D03*
X785541Y1034515D03*
X794241D03*
X785541Y1054593D03*
X794241D03*
X785541Y1061286D03*
X794241D03*
X785541Y1074672D03*
X794241D03*
X785541Y1067979D03*
X794241D03*
X785541Y1091404D03*
X794241D03*
X785541Y1084711D03*
X794241D03*
X785541Y1111483D03*
X794241D03*
X785541Y1104790D03*
X794241D03*
X785541Y1098097D03*
X794241D03*
X785541Y1128215D03*
X794241D03*
X785541Y1121522D03*
X794241D03*
X785541Y1141601D03*
X794241D03*
X785541Y1134908D03*
X794241D03*
X785541Y1158333D03*
X794241D03*
X785541Y1148294D03*
X794241D03*
X785541Y1171719D03*
X794241D03*
X785541Y1165026D03*
X794241D03*
X785541Y1178412D03*
X794241D03*
X785541Y1185105D03*
X794241D03*
X785541Y1208530D03*
X794241D03*
X785541Y1195144D03*
X794241D03*
X785541Y1201837D03*
X794241D03*
X785541Y1221916D03*
X794241D03*
X785541Y1215223D03*
X794241D03*
X785541Y1238648D03*
X794241D03*
X785541Y1231955D03*
X794241D03*
X785541Y1245341D03*
X794241D03*
X785541Y1255381D03*
X794157Y1252034D03*
X785541Y1248688D03*
X788446Y1273364D03*
X791246D03*
X785541Y1265420D03*
Y1262074D03*
X799099Y770144D03*
X807799D03*
X797417Y767345D03*
X799099Y783530D03*
X807799D03*
X799099Y776837D03*
X807799D03*
X799099Y800263D03*
X807799D03*
X799099Y793570D03*
X807799D03*
X799099Y820341D03*
X807799D03*
X799099Y806955D03*
X807799D03*
X799099Y813648D03*
X807799D03*
X799099Y830381D03*
X807799D03*
X799099Y850459D03*
X807799D03*
X799099Y837074D03*
X807799D03*
X799099Y843766D03*
X807799D03*
X799099Y867192D03*
X807799D03*
X799099Y857152D03*
X807799D03*
X799099Y873885D03*
X807799D03*
X799099Y880577D03*
X807799D03*
X799099Y887270D03*
X807799D03*
X799099Y893963D03*
X807799D03*
X799099Y917389D03*
X807799D03*
X799099Y904003D03*
X807799D03*
X799099Y910696D03*
X807799D03*
X799099Y930774D03*
X807799D03*
X799099Y924081D03*
X807799D03*
X799099Y947507D03*
X807799D03*
X799099Y940814D03*
X807799D03*
X799099Y964239D03*
X807799D03*
X799099Y954200D03*
X807799D03*
X799099Y970932D03*
X807799D03*
X799099Y977625D03*
X807799D03*
X799099Y991011D03*
X807799D03*
X799099Y984318D03*
X807799D03*
X799099Y1031168D03*
X807799D03*
X799099Y1024475D03*
X807799D03*
X799099Y1017782D03*
X807799D03*
X799099Y1037861D03*
X807799D03*
X799099Y1044554D03*
X807799D03*
X799099Y1057940D03*
X807799D03*
X799099Y1051247D03*
X807799D03*
X799099Y1061286D03*
Y1078018D03*
X807799D03*
X799099Y1071326D03*
X807799D03*
X799099Y1064633D03*
X807799D03*
X799099Y1094751D03*
X807799D03*
X799099Y1088058D03*
X807799D03*
X799099Y1108137D03*
X807799D03*
X799099Y1101444D03*
X807799D03*
X799099Y1124869D03*
X807799D03*
X799099Y1114829D03*
X807799D03*
X799099Y1144948D03*
X807799D03*
X799099Y1138255D03*
X807799D03*
X799099Y1131562D03*
X807799D03*
X799099Y1161680D03*
X807799D03*
X799099Y1151641D03*
X807799D03*
X799099Y1175066D03*
X807799D03*
X799099Y1168373D03*
X807799D03*
X799099Y1188452D03*
X807799D03*
X799099Y1181759D03*
X807799D03*
X799099Y1205184D03*
X807799D03*
X799099Y1198491D03*
X807799D03*
X799099Y1225263D03*
X807799D03*
X799099Y1211877D03*
X807799D03*
X799099Y1218570D03*
X807799D03*
X799099Y1241995D03*
X807799D03*
X799099Y1235302D03*
X807799D03*
X799099Y1248688D03*
X807799D03*
X808046Y1257664D03*
X799099Y1258727D03*
X804946Y1273364D03*
X802146D03*
X799099Y1265420D03*
X815241Y766798D03*
X823941D03*
X815241Y773491D03*
X823941D03*
X815241Y780184D03*
X823941D03*
X815241Y803609D03*
X823941D03*
X815241Y790223D03*
X823941D03*
X815241Y796916D03*
X823941D03*
X815241Y816995D03*
X823941D03*
X815241Y810302D03*
X823941D03*
X815241Y833727D03*
X823941D03*
X815241Y827034D03*
X823941D03*
X815241Y840420D03*
X823941D03*
X815241Y847113D03*
X823941D03*
X815241Y853806D03*
X823941D03*
X815241Y863845D03*
X823941D03*
X815241Y883924D03*
X823941D03*
X815241Y870538D03*
X823941D03*
X815241Y877231D03*
X823941D03*
X815241Y900656D03*
X823941D03*
X815241Y890617D03*
X823941D03*
X815241Y907349D03*
X823941D03*
X815241Y914042D03*
X823941D03*
X815241Y920735D03*
X823941D03*
X815241Y927428D03*
X823941D03*
X815241Y937467D03*
X823941D03*
X815241Y944160D03*
X823941D03*
X815241Y960892D03*
X823941D03*
X815241Y950853D03*
X823941D03*
X815241Y957546D03*
Y954200D03*
Y980971D03*
X823941D03*
X815241Y974278D03*
X823941D03*
X815241Y967585D03*
X823941D03*
X815241Y987664D03*
X823941D03*
X815241Y994357D03*
Y1027822D03*
X823941D03*
X815241Y1017782D03*
X823941D03*
X815241Y1047900D03*
X823941D03*
X815241Y1041207D03*
X823941D03*
X815241Y1034515D03*
X823941D03*
X815241Y1054593D03*
X823941D03*
X815241Y1061286D03*
X823941D03*
X815241Y1074672D03*
X823941D03*
X815241Y1067979D03*
X823941D03*
X815241Y1091404D03*
X823941D03*
X815241Y1084711D03*
X823941D03*
X815241Y1111483D03*
X823941D03*
X815241Y1104790D03*
X823941D03*
X815241Y1098097D03*
X823941D03*
X815241Y1128215D03*
X823941D03*
X815241Y1121522D03*
X823941D03*
X815241Y1141601D03*
X823941D03*
X815241Y1134908D03*
X823941D03*
X815241Y1158333D03*
X823941D03*
X815241Y1148294D03*
X823941D03*
X815241Y1171719D03*
X823941D03*
X815241Y1165026D03*
X823941D03*
X815241Y1178412D03*
X823941D03*
X815241Y1185105D03*
X823941D03*
X815241Y1208530D03*
X823941D03*
X815241Y1195144D03*
X823941D03*
X815241Y1201837D03*
X823941D03*
X815241Y1221916D03*
X823941D03*
X815241Y1215223D03*
X823941D03*
X815241Y1238648D03*
X823941D03*
X815241Y1231955D03*
X823941D03*
X815241Y1245341D03*
X823941D03*
X815241Y1255381D03*
X823877Y1252034D03*
X815241Y1248688D03*
X826501Y1254553D03*
X820946Y1273364D03*
X818146D03*
X815241Y1265420D03*
Y1262074D03*
X828799Y770144D03*
X837499D03*
X828699Y766798D03*
X828799Y783530D03*
X837499D03*
X828799Y776837D03*
X837499D03*
Y800263D03*
X828799D03*
X837499Y793570D03*
X828799D03*
Y820341D03*
X837499D03*
X828799Y813648D03*
X837499D03*
X828799Y806955D03*
X837499D03*
X828799Y830381D03*
X837499D03*
X828799Y850459D03*
X837499D03*
X828799Y843766D03*
X837499D03*
X828799Y837074D03*
X837499D03*
X828799Y867192D03*
X837499D03*
X828799Y857152D03*
X837499D03*
X828799Y880577D03*
X837499D03*
X828799Y873885D03*
X837499D03*
X828799Y893963D03*
X837499D03*
X828799Y887270D03*
X837499D03*
X828799Y917389D03*
X837499D03*
Y904003D03*
X828799D03*
X837499Y910696D03*
X828799D03*
Y930774D03*
X837499D03*
X828799Y924081D03*
X837499D03*
X828799Y947507D03*
X837499D03*
X828799Y940814D03*
X837499D03*
X828799Y964239D03*
X837499D03*
X828799Y954200D03*
X837499D03*
X828799Y977625D03*
X837499D03*
X828799Y970932D03*
X837499D03*
X828799Y991011D03*
X837499D03*
X828799Y984318D03*
X837499D03*
X828799Y1031168D03*
X837499D03*
X828799Y1024475D03*
X837499D03*
X828799Y1017782D03*
X837499D03*
X828799Y1044554D03*
X837499D03*
X828799Y1037861D03*
X837499D03*
X828799Y1057940D03*
X837499D03*
X828799Y1051247D03*
X837499D03*
X828799Y1078018D03*
X837499D03*
X828799Y1071326D03*
X837499D03*
X828799Y1064633D03*
X837499D03*
X828799Y1094751D03*
X837499D03*
Y1088058D03*
X828799D03*
X837499Y1108137D03*
X828799D03*
Y1101444D03*
X837499D03*
Y1124869D03*
X828799D03*
X837499Y1114829D03*
X828799D03*
X837499Y1144948D03*
X828799D03*
X837499Y1138255D03*
X828799D03*
X837499Y1131562D03*
X828799D03*
X837499Y1161680D03*
X828799D03*
X837499Y1151641D03*
X828799D03*
X837499Y1175066D03*
X828799D03*
X837499Y1168373D03*
X828799D03*
Y1188452D03*
X837499D03*
Y1181759D03*
X828799D03*
X837499Y1205184D03*
X828799D03*
X837499Y1198491D03*
X828799D03*
X837499Y1225263D03*
X828799D03*
X837499Y1218570D03*
X828799D03*
X837499Y1211877D03*
X828799D03*
X837499Y1241995D03*
X828799D03*
X837499Y1235302D03*
X828799D03*
X837499Y1248688D03*
X828799D03*
X837846Y1256964D03*
X828799Y1258727D03*
X839246Y1273064D03*
X842046D03*
X831846Y1273364D03*
X834646D03*
X828799Y1265420D03*
X844941Y766798D03*
X853641D03*
X844941Y780184D03*
X853641D03*
X844941Y773491D03*
X853641D03*
X844941Y803609D03*
X853641D03*
X844941Y796916D03*
X853641D03*
X844941Y790223D03*
X853641D03*
X844941Y816995D03*
X853641D03*
X844941Y810302D03*
X853641D03*
X844941Y833727D03*
X853641D03*
X844941Y827034D03*
X853641D03*
X844941Y847113D03*
X853641D03*
X844941Y840420D03*
X853641D03*
X844941Y863845D03*
X853641D03*
X844941Y853806D03*
X853641D03*
X844941Y883924D03*
X853641D03*
X844941Y877231D03*
X853641D03*
X844941Y870538D03*
X853641D03*
X844941Y900656D03*
X853641D03*
X844941Y890617D03*
X853641D03*
X844941Y914042D03*
X853641D03*
X844941Y907349D03*
X853641D03*
X844941Y927428D03*
X853641D03*
X844941Y920735D03*
X853641D03*
X844941Y944160D03*
X853641D03*
X844941Y937467D03*
X853641D03*
X844941Y960892D03*
X853641D03*
X844941Y950853D03*
X853641D03*
X844841Y957546D03*
Y954200D03*
X844941Y980971D03*
X853641D03*
X844941Y974278D03*
X853641D03*
X844941Y967585D03*
X853641D03*
X844941Y987664D03*
X853641D03*
X844841Y994357D03*
X844941Y1027822D03*
X853641D03*
X844941Y1017782D03*
X853641D03*
X844941Y1047900D03*
X853641D03*
X844941Y1041207D03*
X853641D03*
X844941Y1034515D03*
X853641D03*
X844941Y1061286D03*
X853641D03*
X844941Y1054593D03*
X853641D03*
X844941Y1074672D03*
X853641D03*
X844941Y1067979D03*
X853641D03*
X844941Y1091404D03*
X853641D03*
X844941Y1084711D03*
X853641D03*
X844941Y1111483D03*
X853641D03*
X844941Y1104790D03*
X853641D03*
X844941Y1098097D03*
X853641D03*
X844941Y1128215D03*
X853641D03*
X844941Y1121522D03*
X853641D03*
X844941Y1141601D03*
X853641D03*
X844941Y1134908D03*
X853641D03*
X844941Y1158333D03*
X853641D03*
X844941Y1148294D03*
X853641D03*
X844941Y1171719D03*
X853641D03*
X844941Y1165026D03*
X853641D03*
X844941Y1185105D03*
X853641D03*
X844941Y1178412D03*
X853641D03*
X844941Y1208530D03*
X853641D03*
X844941Y1201837D03*
X853641D03*
X844941Y1195144D03*
X853641D03*
X844941Y1221916D03*
X853641D03*
X844941Y1215223D03*
X853641D03*
X844941Y1238648D03*
X853641D03*
X844941Y1231955D03*
X853641D03*
X844941Y1245341D03*
X853641D03*
X844941Y1258727D03*
Y1252034D03*
X844997Y1248155D03*
X844941Y1265420D03*
Y1262074D03*
X918264Y506011D03*
X998205Y195735D03*
Y192191D03*
X1000705Y195735D03*
Y192191D03*
X998205Y199278D03*
X1000705D03*
X998205Y202821D03*
X1000705D03*
X1003841Y770144D03*
Y783530D03*
Y776837D03*
Y800263D03*
Y793570D03*
Y820341D03*
Y813648D03*
Y806955D03*
Y830381D03*
Y850459D03*
Y843766D03*
Y837074D03*
Y867192D03*
Y857152D03*
Y880577D03*
Y873885D03*
Y893963D03*
Y887270D03*
Y917389D03*
Y910696D03*
Y904003D03*
Y930774D03*
Y924081D03*
Y947507D03*
Y940814D03*
Y964239D03*
Y954200D03*
Y977625D03*
Y970932D03*
Y991011D03*
Y984318D03*
Y1031168D03*
Y1024475D03*
Y1017782D03*
Y1044554D03*
Y1037861D03*
Y1057940D03*
Y1051247D03*
Y1078018D03*
Y1071326D03*
Y1064633D03*
Y1094751D03*
Y1088058D03*
Y1108137D03*
Y1101444D03*
Y1124869D03*
Y1114829D03*
Y1144948D03*
Y1138255D03*
Y1131562D03*
Y1161680D03*
Y1151641D03*
Y1175066D03*
Y1168373D03*
Y1188452D03*
Y1181759D03*
Y1205184D03*
Y1198491D03*
Y1225263D03*
Y1218570D03*
Y1211877D03*
Y1241995D03*
Y1235302D03*
Y1248688D03*
X1003831Y1259077D03*
X1003841Y1265420D03*
Y1262074D03*
X1019983Y766798D03*
X1012541Y770144D03*
X1012769Y766798D03*
X1019983Y780184D03*
Y773491D03*
X1012541Y783530D03*
Y776837D03*
X1019983Y803609D03*
Y796916D03*
Y790223D03*
X1012541Y800263D03*
Y793570D03*
X1019983Y816995D03*
Y810302D03*
X1012541Y820341D03*
Y813648D03*
Y806955D03*
X1019983Y833727D03*
Y827034D03*
X1012541Y830381D03*
X1019983Y847113D03*
Y840420D03*
X1012541Y850459D03*
Y843766D03*
Y837074D03*
X1019983Y863845D03*
Y853806D03*
X1012541Y867192D03*
Y857152D03*
X1019983Y883924D03*
Y877231D03*
Y870538D03*
X1012541Y880577D03*
Y873885D03*
X1019983Y900656D03*
Y890617D03*
X1012541Y893963D03*
Y887270D03*
X1019983Y914042D03*
Y907349D03*
X1012541Y917389D03*
Y910696D03*
Y904003D03*
X1019983Y927428D03*
Y920735D03*
X1012541Y930774D03*
Y924081D03*
X1019983Y944160D03*
Y937467D03*
X1012541Y947507D03*
Y940814D03*
X1019983Y960892D03*
Y950853D03*
X1012541Y964239D03*
Y954200D03*
X1019983Y980971D03*
Y974278D03*
Y967585D03*
X1012541Y977625D03*
Y970932D03*
X1019983Y987664D03*
X1012541Y991011D03*
Y984318D03*
X1019983Y994357D03*
Y1027822D03*
Y1017782D03*
X1012541Y1031168D03*
Y1024475D03*
Y1017782D03*
X1019983Y1047900D03*
Y1041207D03*
Y1034515D03*
X1012541Y1044554D03*
Y1037861D03*
X1019983Y1061286D03*
Y1054593D03*
X1012541Y1057940D03*
Y1051247D03*
X1019983Y1067979D03*
Y1074672D03*
X1012541Y1078018D03*
Y1071326D03*
Y1064633D03*
X1019983Y1091404D03*
Y1084711D03*
X1012541Y1094751D03*
Y1088058D03*
X1019983Y1111483D03*
Y1104790D03*
Y1098097D03*
X1012541Y1108137D03*
Y1101444D03*
X1019983Y1128215D03*
Y1121522D03*
X1012541Y1124869D03*
Y1114829D03*
X1019983Y1141601D03*
Y1134908D03*
X1012541Y1144948D03*
Y1138255D03*
Y1131562D03*
X1019983Y1158333D03*
Y1148294D03*
X1012541Y1161680D03*
Y1151641D03*
X1019983Y1171719D03*
Y1165026D03*
X1012541Y1175066D03*
Y1168373D03*
X1019983Y1185105D03*
Y1178412D03*
X1012541Y1188452D03*
Y1181759D03*
X1019983Y1208530D03*
Y1201837D03*
Y1195144D03*
X1012541Y1205184D03*
Y1198491D03*
X1019983Y1221916D03*
Y1215223D03*
X1012541Y1225263D03*
Y1218570D03*
Y1211877D03*
X1019983Y1238648D03*
Y1231955D03*
X1012541Y1241995D03*
Y1235302D03*
X1012543Y1257198D03*
X1019983Y1245341D03*
X1012541Y1248688D03*
X1017900Y1247632D03*
X1019983Y1255381D03*
Y1252034D03*
Y1248688D03*
X1017111Y1273299D03*
X1014111D03*
X1019983Y1262074D03*
Y1265420D03*
X1033541Y770144D03*
X1028683Y766798D03*
X1033441D03*
X1033541Y783530D03*
Y776837D03*
X1028683Y780184D03*
Y773491D03*
X1033541Y800263D03*
Y793570D03*
X1028683Y803609D03*
Y796916D03*
Y790223D03*
X1033541Y820341D03*
Y813648D03*
Y806955D03*
X1028683Y816995D03*
Y810302D03*
X1033541Y830381D03*
X1028683Y833727D03*
Y827034D03*
X1033541Y850459D03*
Y843766D03*
Y837074D03*
X1028683Y847113D03*
Y840420D03*
X1033541Y867192D03*
Y857152D03*
X1028683Y863845D03*
Y853806D03*
X1033541Y880577D03*
Y873885D03*
X1028683Y883924D03*
Y877231D03*
Y870538D03*
X1033541Y893963D03*
Y887270D03*
X1028683Y900656D03*
Y890617D03*
X1033541Y917389D03*
Y910696D03*
Y904003D03*
X1028683Y914042D03*
Y907349D03*
X1033541Y930774D03*
Y924081D03*
X1028683Y927428D03*
Y920735D03*
X1033541Y947507D03*
Y940814D03*
X1028683Y944160D03*
Y937467D03*
X1033541Y964239D03*
Y954200D03*
X1028683Y960892D03*
Y950853D03*
Y957546D03*
Y954200D03*
X1033541Y977625D03*
Y970932D03*
X1028683Y980971D03*
Y974278D03*
Y967585D03*
X1033541Y991011D03*
Y984318D03*
X1028683Y987664D03*
X1033541Y1031168D03*
Y1017782D03*
Y1024475D03*
X1028683Y1027822D03*
Y1017782D03*
X1033541Y1044554D03*
Y1037861D03*
X1028683Y1047900D03*
Y1041207D03*
Y1034515D03*
X1033541Y1057940D03*
Y1051247D03*
X1028683Y1061286D03*
Y1054593D03*
X1033541Y1078018D03*
Y1071326D03*
Y1064633D03*
X1028683Y1067979D03*
Y1074672D03*
X1033541Y1094751D03*
Y1088058D03*
X1028683Y1091404D03*
Y1084711D03*
X1033541Y1108137D03*
Y1101444D03*
X1028683Y1111483D03*
Y1104790D03*
Y1098097D03*
X1033541Y1114829D03*
Y1124869D03*
X1028683Y1128215D03*
Y1121522D03*
X1033541Y1144948D03*
Y1138255D03*
Y1131562D03*
X1028683Y1141601D03*
Y1134908D03*
X1033541Y1161680D03*
Y1151641D03*
X1028683Y1158333D03*
Y1148294D03*
X1033541Y1175066D03*
Y1168373D03*
X1028683Y1171719D03*
Y1165026D03*
X1033541Y1188452D03*
Y1181759D03*
X1028683Y1185105D03*
Y1178412D03*
X1033541Y1205184D03*
Y1198491D03*
X1028683Y1208530D03*
Y1201837D03*
Y1195144D03*
X1033541Y1225263D03*
Y1218570D03*
Y1211877D03*
X1028683Y1221916D03*
Y1215223D03*
X1033541Y1241995D03*
Y1235302D03*
X1028683Y1238648D03*
Y1231955D03*
X1033541Y1248688D03*
X1028683Y1245341D03*
X1033541Y1258727D03*
X1036588Y1273344D03*
X1022888D03*
X1025688D03*
X1033541Y1265420D03*
X1030780Y1266532D03*
X1049683Y766798D03*
X1042241Y770144D03*
X1049683Y780184D03*
Y773491D03*
X1042241Y783530D03*
Y776837D03*
X1049683Y803609D03*
Y796916D03*
Y790223D03*
X1042241Y800263D03*
Y793570D03*
X1049683Y816995D03*
Y810302D03*
X1042241Y820341D03*
Y813648D03*
Y806955D03*
X1049683Y833727D03*
Y827034D03*
X1042241Y830381D03*
X1049683Y847113D03*
Y840420D03*
X1042241Y850459D03*
Y843766D03*
Y837074D03*
X1049683Y863845D03*
Y853806D03*
X1042241Y867192D03*
Y857152D03*
X1049683Y883924D03*
Y877231D03*
Y870538D03*
X1042241Y880577D03*
Y873885D03*
X1049683Y900656D03*
Y890617D03*
X1042241Y893963D03*
Y887270D03*
X1049683Y914042D03*
Y907349D03*
X1042241Y917389D03*
Y910696D03*
Y904003D03*
X1049683Y927428D03*
Y920735D03*
X1042241Y930774D03*
Y924081D03*
X1049683Y944160D03*
Y937467D03*
X1042241Y947507D03*
Y940814D03*
X1049683Y960892D03*
Y950853D03*
X1042241Y964239D03*
Y954200D03*
X1049683Y980971D03*
Y974278D03*
Y967585D03*
X1042241Y977625D03*
Y970932D03*
X1049683Y987664D03*
X1042241Y991011D03*
Y984318D03*
X1049683Y1027822D03*
Y1017782D03*
X1042241Y1031168D03*
Y1017782D03*
Y1024475D03*
X1049683Y1047900D03*
Y1041207D03*
Y1034515D03*
X1042241Y1044554D03*
Y1037861D03*
X1049683Y1061286D03*
Y1054593D03*
X1042241Y1057940D03*
Y1051247D03*
Y1061286D03*
X1049683Y1074672D03*
Y1067979D03*
X1042241Y1078018D03*
Y1071326D03*
Y1064633D03*
X1049683Y1091404D03*
Y1084711D03*
X1042241Y1094751D03*
Y1088058D03*
X1049683Y1111483D03*
Y1104790D03*
Y1098097D03*
X1042241Y1108137D03*
Y1101444D03*
Y1114829D03*
X1049683Y1128215D03*
Y1121522D03*
X1042241Y1124869D03*
X1049683Y1141601D03*
Y1134908D03*
X1042241Y1144948D03*
Y1138255D03*
Y1131562D03*
Y1161680D03*
X1049683Y1158333D03*
Y1148294D03*
X1042241Y1151641D03*
X1049683Y1171719D03*
Y1165026D03*
X1042241Y1175066D03*
Y1168373D03*
X1049683Y1185105D03*
Y1178412D03*
X1042241Y1188452D03*
Y1181759D03*
X1049683Y1208530D03*
Y1201837D03*
Y1195144D03*
X1042241Y1205184D03*
Y1198491D03*
X1049683Y1215223D03*
Y1221916D03*
X1042241Y1225263D03*
Y1218570D03*
Y1211877D03*
X1049683Y1238648D03*
Y1231955D03*
X1042241Y1241995D03*
Y1235302D03*
X1042331Y1257488D03*
X1049683Y1245341D03*
X1042241Y1248688D03*
X1049683Y1258727D03*
X1052588Y1273344D03*
X1039388D03*
X1049683Y1265420D03*
Y1262074D03*
X1063241Y770144D03*
X1058383Y766798D03*
X1063141D03*
X1063241Y783530D03*
Y776837D03*
X1058383Y780184D03*
Y773491D03*
X1063241Y800263D03*
Y793570D03*
X1058383Y803609D03*
Y796916D03*
Y790223D03*
X1063241Y820341D03*
Y813648D03*
Y806955D03*
X1058383Y816995D03*
Y810302D03*
X1063241Y830381D03*
X1058383Y833727D03*
Y827034D03*
X1063241Y850459D03*
Y843766D03*
Y837074D03*
X1058383Y847113D03*
Y840420D03*
X1063241Y867192D03*
Y857152D03*
X1058383Y863845D03*
Y853806D03*
X1063241Y880577D03*
Y873885D03*
X1058383Y883924D03*
Y877231D03*
Y870538D03*
X1063241Y893963D03*
Y887270D03*
X1058383Y900656D03*
Y890617D03*
X1063241Y917389D03*
Y910696D03*
Y904003D03*
X1058383Y914042D03*
Y907349D03*
X1063241Y930774D03*
Y924081D03*
X1058383Y927428D03*
Y920735D03*
X1063241Y947507D03*
Y940814D03*
X1058383Y944160D03*
Y937467D03*
X1063241Y964239D03*
Y954200D03*
X1058383Y960892D03*
Y950853D03*
Y957546D03*
Y954200D03*
X1063241Y977625D03*
Y970932D03*
X1058383Y980971D03*
Y974278D03*
Y967585D03*
X1063241Y991011D03*
Y984318D03*
X1058383Y987664D03*
Y994357D03*
X1063241Y1031168D03*
Y1024475D03*
Y1017782D03*
X1058383Y1027822D03*
Y1017782D03*
X1063241Y1044554D03*
Y1037861D03*
X1058383Y1047900D03*
Y1041207D03*
Y1034515D03*
X1063241Y1057940D03*
Y1051247D03*
X1058383Y1061286D03*
Y1054593D03*
X1063241Y1078018D03*
Y1071326D03*
Y1064633D03*
X1058383Y1074672D03*
Y1067979D03*
X1063241Y1094751D03*
Y1088058D03*
X1058383Y1091404D03*
Y1084711D03*
X1063241Y1108137D03*
Y1101444D03*
X1058383Y1111483D03*
Y1104790D03*
Y1098097D03*
X1063241Y1124869D03*
Y1114829D03*
X1058383Y1128215D03*
Y1121522D03*
X1063241Y1144948D03*
Y1138255D03*
Y1131562D03*
X1058383Y1141601D03*
Y1134908D03*
X1063241Y1161680D03*
Y1151641D03*
X1058383Y1158333D03*
Y1148294D03*
X1063241Y1175066D03*
Y1168373D03*
X1058383Y1171719D03*
Y1165026D03*
X1063241Y1188452D03*
Y1181759D03*
X1058383Y1185105D03*
Y1178412D03*
X1063241Y1205184D03*
Y1198491D03*
X1058383Y1208530D03*
Y1201837D03*
Y1195144D03*
X1063241Y1225263D03*
Y1218570D03*
Y1211877D03*
X1058383Y1215223D03*
Y1221916D03*
X1063241Y1241995D03*
Y1235302D03*
X1058383Y1238648D03*
Y1231955D03*
X1063241Y1248688D03*
X1058383Y1245341D03*
X1063241Y1258727D03*
X1058383Y1248688D03*
X1069088Y1273344D03*
X1066288D03*
X1055388D03*
X1063241Y1265420D03*
X1079383Y766798D03*
X1071941Y770144D03*
X1079383Y780184D03*
Y773491D03*
X1071941Y783530D03*
Y776837D03*
X1079383Y803609D03*
Y796916D03*
Y790223D03*
X1071941Y800263D03*
Y793570D03*
X1079383Y816995D03*
Y810302D03*
X1071941Y820341D03*
Y813648D03*
Y806955D03*
X1079383Y833727D03*
Y827034D03*
X1071941Y830381D03*
X1079383Y847113D03*
Y840420D03*
X1071941Y850459D03*
Y843766D03*
Y837074D03*
X1079383Y863845D03*
Y853806D03*
X1071941Y867192D03*
Y857152D03*
X1079383Y883924D03*
Y877231D03*
Y870538D03*
X1071941Y880577D03*
Y873885D03*
X1079383Y900656D03*
Y890617D03*
X1071941Y893963D03*
Y887270D03*
X1079383Y914042D03*
Y907349D03*
X1071941Y917389D03*
Y910696D03*
Y904003D03*
X1079383Y927428D03*
Y920735D03*
X1071941Y930774D03*
Y924081D03*
X1079383Y944160D03*
Y937467D03*
X1071941Y947507D03*
Y940814D03*
X1079383Y960892D03*
Y950853D03*
X1071941Y964239D03*
Y954200D03*
X1079383Y980971D03*
Y974278D03*
Y967585D03*
X1071941Y977625D03*
Y970932D03*
X1079383Y987664D03*
X1071941Y991011D03*
Y984318D03*
X1079383Y994357D03*
Y1027822D03*
Y1017782D03*
X1071941Y1031168D03*
Y1024475D03*
Y1017782D03*
X1079383Y1047900D03*
Y1041207D03*
Y1034515D03*
X1071941Y1044554D03*
Y1037861D03*
X1079383Y1061286D03*
Y1054593D03*
X1071941Y1057940D03*
Y1051247D03*
X1079383Y1074672D03*
Y1067979D03*
X1071941Y1078018D03*
Y1071326D03*
Y1064633D03*
X1079383Y1091404D03*
Y1084711D03*
X1071941Y1094751D03*
Y1088058D03*
X1079383Y1111483D03*
Y1104790D03*
Y1098097D03*
X1071941Y1108137D03*
Y1101444D03*
X1079383Y1128215D03*
Y1121522D03*
X1071941Y1124869D03*
Y1114829D03*
X1079383Y1141601D03*
Y1134908D03*
X1071941Y1144948D03*
Y1138255D03*
Y1131562D03*
X1079383Y1158333D03*
Y1148294D03*
X1071941Y1161680D03*
Y1151641D03*
X1079383Y1171719D03*
Y1165026D03*
X1071941Y1175066D03*
Y1168373D03*
X1079383Y1185105D03*
Y1178412D03*
X1071941Y1188452D03*
Y1181759D03*
X1079383Y1208530D03*
Y1201837D03*
Y1195144D03*
X1071941Y1205184D03*
Y1198491D03*
X1079383Y1221916D03*
Y1215223D03*
X1071941Y1225263D03*
Y1218570D03*
Y1211877D03*
X1079383Y1238648D03*
Y1231955D03*
X1071941Y1241995D03*
Y1235302D03*
X1071991Y1257262D03*
X1079383Y1245341D03*
X1071941Y1248688D03*
X1079383Y1258727D03*
X1088262Y1252293D03*
X1085088Y1273344D03*
X1082288D03*
X1079383Y1265420D03*
Y1262074D03*
X1074480Y1263742D03*
X1092941Y770144D03*
X1101641D03*
X1088083Y766798D03*
X1092709Y766775D03*
X1092941Y783530D03*
X1101641D03*
X1092941Y776837D03*
X1101641D03*
X1088083Y780184D03*
Y773491D03*
X1101641Y800263D03*
X1092941D03*
X1101641Y793570D03*
X1092941D03*
X1088083Y803609D03*
Y796916D03*
Y790223D03*
X1101641Y820341D03*
X1092941D03*
X1101641Y813648D03*
X1092941D03*
X1101641Y806955D03*
X1092941D03*
X1088083Y816995D03*
Y810302D03*
X1101641Y830381D03*
X1092941D03*
X1088083Y833727D03*
Y827034D03*
X1101641Y850459D03*
X1092941D03*
X1101641Y843766D03*
X1092941D03*
X1101641Y837074D03*
X1092941D03*
X1088083Y847113D03*
Y840420D03*
X1101641Y867192D03*
X1092941D03*
X1101641Y857152D03*
X1092941D03*
X1088083Y863845D03*
Y853806D03*
X1101641Y880577D03*
X1092941D03*
X1101641Y873885D03*
X1092941D03*
X1088083Y883924D03*
Y877231D03*
Y870538D03*
X1101641Y893963D03*
X1092941D03*
X1101641Y887270D03*
X1092941D03*
X1088083Y900656D03*
Y890617D03*
X1101641Y917389D03*
X1092941D03*
X1101641Y910696D03*
X1092941D03*
X1101641Y904003D03*
X1092941D03*
X1088083Y914042D03*
Y907349D03*
X1101641Y930774D03*
X1092941D03*
X1101641Y924081D03*
X1092941D03*
X1088083Y927428D03*
Y920735D03*
X1101641Y947507D03*
X1092941D03*
X1101641Y940814D03*
X1092941D03*
X1088083Y944160D03*
Y937467D03*
X1101641Y964239D03*
X1092941D03*
X1101641Y954200D03*
X1092941D03*
X1088083Y960892D03*
Y950853D03*
Y957546D03*
Y954200D03*
X1101641Y977625D03*
X1092941D03*
X1101641Y970932D03*
X1092941D03*
X1088083Y980971D03*
Y974278D03*
Y967585D03*
X1101641Y991011D03*
X1092941D03*
X1101641Y984318D03*
X1092941D03*
X1088083Y987664D03*
X1101641Y1031168D03*
X1092941D03*
X1101641Y1024475D03*
X1092941D03*
X1101641Y1017782D03*
X1092941D03*
X1088083Y1027822D03*
Y1017782D03*
X1101641Y1044554D03*
X1092941D03*
X1101641Y1037861D03*
X1092941D03*
X1088083Y1047900D03*
Y1041207D03*
Y1034515D03*
X1101641Y1057940D03*
X1092941D03*
X1101641Y1051247D03*
X1092941D03*
X1088083Y1061286D03*
Y1054593D03*
X1101641Y1061286D03*
Y1078018D03*
X1092941D03*
X1101641Y1071326D03*
X1092941D03*
X1101641Y1064633D03*
X1092941D03*
X1088083Y1074672D03*
Y1067979D03*
X1101641Y1094751D03*
X1092941D03*
X1101641Y1088058D03*
X1092941D03*
X1088083Y1091404D03*
Y1084711D03*
X1101641Y1108137D03*
X1092941D03*
X1101641Y1101444D03*
X1092941D03*
X1088083Y1111483D03*
Y1104790D03*
Y1098097D03*
X1101641Y1124869D03*
X1092941D03*
X1101641Y1114829D03*
X1092941D03*
X1088083Y1128215D03*
Y1121522D03*
X1101641Y1144948D03*
X1092941D03*
X1101641Y1138255D03*
X1092941D03*
X1101641Y1131562D03*
X1092941D03*
X1088083Y1141601D03*
Y1134908D03*
X1092941Y1161680D03*
X1101641D03*
Y1151641D03*
X1092941D03*
X1088083Y1158333D03*
Y1148294D03*
X1101641Y1175066D03*
X1092941D03*
X1101641Y1168373D03*
X1092941D03*
X1088083Y1171719D03*
Y1165026D03*
X1101641Y1181759D03*
X1092941D03*
Y1188452D03*
X1101641D03*
X1088083Y1185105D03*
Y1178412D03*
X1092941Y1205184D03*
X1101641D03*
X1092941Y1198491D03*
X1101641D03*
X1088083Y1208530D03*
Y1201837D03*
Y1195144D03*
X1101641Y1225263D03*
X1092941D03*
X1101641Y1218570D03*
X1092941D03*
Y1211877D03*
X1101641D03*
X1088083Y1221916D03*
Y1215223D03*
X1101641Y1241995D03*
X1092941D03*
X1101641Y1235302D03*
X1092941D03*
X1088083Y1238648D03*
Y1231955D03*
X1101554Y1257102D03*
X1101641Y1248688D03*
X1092941D03*
X1088083Y1245341D03*
X1090273Y1246800D03*
X1092941Y1258727D03*
X1088083Y1248688D03*
X1098788Y1273344D03*
X1095988D03*
X1092941Y1265420D03*
X1109083Y766798D03*
X1117783D03*
Y780184D03*
X1109083D03*
X1117783Y773491D03*
X1109083D03*
X1117783Y803609D03*
X1109083D03*
X1117783Y796916D03*
X1109083D03*
Y790223D03*
X1117783D03*
Y816995D03*
X1109083D03*
X1117783Y810302D03*
X1109083D03*
X1117783Y833727D03*
X1109083D03*
X1117783Y827034D03*
X1109083D03*
X1117783Y847113D03*
X1109083D03*
X1117783Y840420D03*
X1109083D03*
X1117783Y863845D03*
X1109083D03*
X1117783Y853806D03*
X1109083D03*
X1117783Y883924D03*
X1109083D03*
X1117783Y877231D03*
X1109083D03*
X1117783Y870538D03*
X1109083D03*
X1117783Y900656D03*
X1109083D03*
X1117783Y890617D03*
X1109083D03*
X1117783Y914042D03*
X1109083D03*
X1117783Y907349D03*
X1109083D03*
X1117783Y927428D03*
X1109083D03*
X1117783Y920735D03*
X1109083D03*
X1117783Y944160D03*
X1109083D03*
X1117783Y937467D03*
X1109083D03*
X1117783Y960892D03*
X1109083D03*
X1117783Y950853D03*
X1109083D03*
X1117783Y957546D03*
Y954200D03*
Y980971D03*
X1109083D03*
X1117783Y974278D03*
X1109083D03*
X1117783Y967585D03*
X1109083D03*
X1117783Y987664D03*
X1109083D03*
X1117783Y994357D03*
Y1027822D03*
X1109083D03*
X1117783Y1017782D03*
X1109083D03*
X1117783Y1047900D03*
X1109083D03*
X1117783Y1041207D03*
X1109083D03*
X1117783Y1034515D03*
X1109083D03*
X1117783Y1061286D03*
X1109083D03*
X1117783Y1054593D03*
X1109083D03*
X1117783Y1057940D03*
Y1074672D03*
X1109083D03*
X1117783Y1067979D03*
X1109083D03*
X1117783Y1091404D03*
X1109083D03*
X1117783Y1084711D03*
X1109083D03*
X1117783Y1111483D03*
X1109083D03*
X1117783Y1104790D03*
X1109083D03*
X1117783Y1098097D03*
X1109083D03*
X1117783Y1128215D03*
X1109083D03*
X1117783Y1121522D03*
X1109083D03*
X1117783Y1141601D03*
X1109083D03*
X1117783Y1134908D03*
X1109083D03*
X1117783Y1158333D03*
X1109083D03*
X1117783Y1148294D03*
X1109083D03*
X1117783Y1171719D03*
X1109083D03*
X1117783Y1165026D03*
X1109083D03*
X1117783Y1185105D03*
X1109083D03*
X1117783Y1178412D03*
X1109083D03*
X1117783Y1208530D03*
X1109083D03*
X1117783Y1201837D03*
X1109083D03*
X1117783Y1195144D03*
X1109083D03*
X1117783Y1221916D03*
X1109083D03*
X1117783Y1215223D03*
X1109083D03*
X1117783Y1238648D03*
X1109083D03*
X1117783Y1231955D03*
X1109083D03*
X1117783Y1245341D03*
X1109083D03*
X1117783Y1248688D03*
X1111988Y1273344D03*
X1114788D03*
X1109083Y1265420D03*
X1109050Y1262972D03*
X1131341Y770144D03*
X1122641D03*
X1122541Y766798D03*
X1131341Y783530D03*
X1122641D03*
X1131341Y776837D03*
X1122641D03*
X1131341Y800263D03*
X1122641D03*
X1131341Y793570D03*
X1122641D03*
X1131341Y820341D03*
X1122641D03*
X1131341Y813648D03*
X1122641D03*
X1131341Y806955D03*
X1122641D03*
X1131341Y830381D03*
X1122641D03*
X1131341Y850459D03*
X1122641D03*
X1131341Y843766D03*
X1122641D03*
X1131341Y837074D03*
X1122641D03*
X1131341Y867192D03*
X1122641D03*
X1131341Y857152D03*
X1122641D03*
X1131341Y880577D03*
X1122641D03*
X1131341Y873885D03*
X1122641D03*
X1131341Y893963D03*
X1122641D03*
X1131341Y887270D03*
X1122641D03*
X1131341Y917389D03*
X1122641D03*
X1131341Y910696D03*
X1122641D03*
X1131341Y904003D03*
X1122641D03*
X1131341Y930774D03*
X1122641D03*
X1131341Y924081D03*
X1122641D03*
Y947507D03*
X1131341D03*
Y940814D03*
X1122641D03*
X1131341Y964239D03*
X1122641D03*
X1131341Y954200D03*
X1122641D03*
X1131341Y977625D03*
X1122641D03*
X1131341Y970932D03*
X1122641D03*
X1131341Y991011D03*
X1122641D03*
X1131341Y984318D03*
X1122641D03*
X1131341Y1031168D03*
X1122641D03*
X1131341Y1024475D03*
X1122641D03*
X1131341Y1017782D03*
X1122641D03*
X1131341Y1044554D03*
X1122641D03*
X1131341Y1037861D03*
X1122641D03*
X1131341Y1057940D03*
X1122641D03*
X1131341Y1051247D03*
X1122641D03*
X1131341Y1078018D03*
X1122641D03*
X1131341Y1071326D03*
X1122641D03*
X1131341Y1064633D03*
X1122641D03*
X1131341Y1094751D03*
X1122641D03*
X1131341Y1088058D03*
X1122641D03*
X1131341Y1108137D03*
X1122641D03*
X1131341Y1101444D03*
X1122641D03*
X1131341Y1124869D03*
X1122641D03*
X1131341Y1114829D03*
X1122641D03*
X1131341Y1144948D03*
X1122641D03*
X1131341Y1138255D03*
X1122641D03*
X1131341Y1131562D03*
X1122641D03*
X1131341Y1161680D03*
X1122641D03*
X1131341Y1151641D03*
X1122641D03*
X1131341Y1175066D03*
X1122641D03*
X1131341Y1168373D03*
X1122641D03*
X1131341Y1188452D03*
X1122641D03*
X1131341Y1181759D03*
X1122641D03*
X1131341Y1205184D03*
X1122641D03*
X1131341Y1198491D03*
X1122641D03*
X1131341Y1225263D03*
X1122641D03*
X1131341Y1218570D03*
X1122641D03*
X1131341Y1211877D03*
X1122641D03*
X1131341Y1241995D03*
X1122641D03*
X1131341Y1235302D03*
X1122641D03*
X1131434Y1257291D03*
X1122641Y1248688D03*
X1131341D03*
X1122641Y1258727D03*
X1133200Y1255702D03*
X1126188Y1273344D03*
X1128988D03*
X1122620Y1264622D03*
X1152341Y770144D03*
X1147483Y766798D03*
X1138783D03*
X1152341Y783530D03*
Y776837D03*
X1147483Y780184D03*
X1138783D03*
Y773491D03*
X1147483D03*
X1152341Y800263D03*
X1147483Y803609D03*
X1138783D03*
X1152341Y793570D03*
X1147483Y796916D03*
X1138783D03*
X1147483Y790223D03*
X1138783D03*
X1152341Y820341D03*
X1147483Y816995D03*
X1138783D03*
X1152341Y813648D03*
Y806955D03*
X1147483Y810302D03*
X1138783D03*
X1147483Y833727D03*
X1138783D03*
X1152341Y830381D03*
X1147483Y827034D03*
X1138783D03*
X1152341Y850459D03*
Y843766D03*
Y837074D03*
X1147483Y847113D03*
X1138783D03*
X1147483Y840420D03*
X1138783D03*
X1152341Y867192D03*
Y857152D03*
X1147483Y863845D03*
X1138783D03*
X1147483Y853806D03*
X1138783D03*
X1152341Y880577D03*
Y873885D03*
X1147483Y883924D03*
X1138783D03*
X1147483Y877231D03*
X1138783D03*
X1147483Y870538D03*
X1138783D03*
X1152341Y893963D03*
Y887270D03*
X1138783Y900656D03*
X1147483D03*
X1138783Y890617D03*
X1147483D03*
X1152341Y917389D03*
Y910696D03*
Y904003D03*
X1147483Y914042D03*
X1138783D03*
X1147483Y907349D03*
X1138783D03*
X1152341Y930774D03*
Y924081D03*
X1147483Y927428D03*
X1138783D03*
X1147483Y920735D03*
X1138783D03*
X1152341Y947507D03*
Y940814D03*
X1147483Y944160D03*
X1138783D03*
X1147483Y937467D03*
X1138783D03*
X1152341Y964239D03*
Y954200D03*
X1147483Y960892D03*
X1138783D03*
X1147483Y950853D03*
X1138783D03*
X1147483Y957546D03*
Y954200D03*
X1152341Y977625D03*
Y970932D03*
X1147483Y980971D03*
X1138783D03*
X1147483Y974278D03*
X1138783D03*
X1147483Y967585D03*
X1138783D03*
X1152341Y991011D03*
Y984318D03*
X1147483Y987664D03*
X1138783D03*
Y994357D03*
X1152341Y1031168D03*
Y1024475D03*
Y1017782D03*
X1147483Y1027822D03*
X1138783D03*
X1147483Y1017782D03*
X1138783D03*
X1152341Y1044554D03*
Y1037861D03*
X1138783Y1047900D03*
X1147483D03*
Y1041207D03*
X1138783D03*
X1147483Y1034515D03*
X1138783D03*
X1152341Y1057940D03*
Y1051247D03*
X1147483Y1061286D03*
X1138783D03*
X1147483Y1054593D03*
X1138783D03*
X1152341Y1078018D03*
Y1071326D03*
Y1064633D03*
X1147483Y1074672D03*
X1138783D03*
X1147483Y1067979D03*
X1138783D03*
X1152341Y1094751D03*
Y1088058D03*
X1147483Y1091404D03*
X1138783D03*
X1147483Y1084711D03*
X1138783D03*
X1152341Y1108137D03*
Y1101444D03*
X1147483Y1111483D03*
X1138783D03*
X1147483Y1104790D03*
X1138783D03*
X1147483Y1098097D03*
X1138783D03*
X1152341Y1124869D03*
Y1114829D03*
X1147483Y1128215D03*
X1138783D03*
X1147483Y1121522D03*
X1138783D03*
X1152341Y1144948D03*
Y1138255D03*
Y1131562D03*
X1147483Y1141601D03*
X1138783D03*
X1147483Y1134908D03*
X1138783D03*
X1152341Y1161680D03*
Y1151641D03*
X1147483Y1158333D03*
X1138783D03*
Y1148294D03*
X1147483D03*
X1152341Y1175066D03*
Y1168373D03*
X1147483Y1171719D03*
X1138783D03*
X1147483Y1165026D03*
X1138783D03*
X1152341Y1188452D03*
Y1181759D03*
X1147483Y1185105D03*
X1138783D03*
X1147483Y1178412D03*
X1138783D03*
X1152341Y1205184D03*
Y1198491D03*
X1147483Y1208530D03*
X1138783D03*
X1147483Y1201837D03*
X1138783D03*
X1147483Y1195144D03*
X1138783D03*
X1152341Y1225263D03*
Y1218570D03*
Y1211877D03*
X1147483Y1221916D03*
X1138783D03*
X1147483Y1215223D03*
X1138783D03*
X1152341Y1241995D03*
Y1235302D03*
X1147483Y1238648D03*
X1138783D03*
X1147483Y1231955D03*
X1138783D03*
X1152341Y1248688D03*
X1147483Y1245341D03*
X1138783D03*
X1152341Y1258727D03*
X1138783Y1255381D03*
Y1258727D03*
Y1252034D03*
X1147483Y1248688D03*
X1152381Y1269684D03*
X1147681D03*
X1138201Y1270277D03*
X1152341Y1265420D03*
X1138783Y1262027D03*
X1137980Y1264212D03*
X1168483Y766798D03*
X1161041Y770144D03*
X1168483Y780184D03*
Y773491D03*
X1161041Y783530D03*
Y776837D03*
X1168483Y803609D03*
Y796916D03*
Y790223D03*
X1161041Y800263D03*
Y793570D03*
X1168483Y816995D03*
Y810302D03*
X1161041Y820341D03*
Y813648D03*
Y806955D03*
X1168483Y833727D03*
X1167633Y827034D03*
X1161041Y830381D03*
X1168483Y847113D03*
Y840420D03*
X1161041Y850459D03*
Y843766D03*
Y837074D03*
X1167633Y863845D03*
X1161041Y867192D03*
X1168483Y853806D03*
X1161041Y857152D03*
X1168483Y883924D03*
Y877231D03*
Y870538D03*
X1161041Y880577D03*
Y873885D03*
X1168483Y900656D03*
Y890617D03*
X1161041Y893963D03*
Y887270D03*
X1168483Y914042D03*
Y907349D03*
X1161041Y917389D03*
Y910696D03*
Y904003D03*
X1167633Y927428D03*
X1168483Y920735D03*
X1161041Y930774D03*
Y924081D03*
X1168483Y937467D03*
Y944160D03*
X1161041Y947507D03*
Y940814D03*
X1168483Y960892D03*
Y950853D03*
X1161041Y964239D03*
Y954200D03*
X1168483Y974278D03*
Y980971D03*
Y967585D03*
X1161041Y977625D03*
Y970932D03*
X1168483Y987664D03*
X1161041Y991011D03*
Y984318D03*
X1168483Y1027822D03*
Y1017782D03*
X1161041Y1031168D03*
Y1024475D03*
Y1017782D03*
X1168483Y1047900D03*
Y1041207D03*
Y1034515D03*
X1161041Y1044554D03*
Y1037861D03*
X1168483Y1054593D03*
Y1061286D03*
X1161041Y1057940D03*
Y1051247D03*
Y1061286D03*
X1168483Y1074672D03*
Y1067979D03*
X1161041Y1078018D03*
Y1071326D03*
Y1064633D03*
X1168483Y1091404D03*
X1167633Y1084711D03*
X1161041Y1094751D03*
Y1088058D03*
X1168483Y1111483D03*
Y1104790D03*
Y1098097D03*
X1161041Y1108137D03*
Y1101444D03*
X1168483Y1128215D03*
Y1121522D03*
X1161041Y1124869D03*
Y1114829D03*
X1168483Y1141601D03*
Y1134908D03*
X1161041Y1144948D03*
Y1138255D03*
Y1131562D03*
X1167633Y1158333D03*
X1168483Y1148294D03*
X1161041Y1161680D03*
Y1151641D03*
X1168483Y1171719D03*
Y1165026D03*
X1161041Y1175066D03*
Y1168373D03*
X1168483Y1185105D03*
Y1178412D03*
X1161041Y1188452D03*
Y1181759D03*
X1168483Y1208530D03*
Y1201837D03*
Y1195144D03*
X1161041Y1205184D03*
Y1198491D03*
X1168483Y1221916D03*
Y1215223D03*
X1161041Y1225263D03*
Y1218570D03*
Y1211877D03*
X1168483Y1238648D03*
X1167633Y1231955D03*
X1161041Y1241995D03*
Y1235302D03*
X1161065Y1258871D03*
X1168483Y1245341D03*
X1161041Y1248688D03*
X1168483Y1255381D03*
Y1258727D03*
Y1252034D03*
X1161781Y1269684D03*
X1168483Y1265420D03*
Y1262074D03*
X1182041Y770144D03*
X1177183Y766798D03*
X1181941D03*
X1182041Y783530D03*
Y776837D03*
X1177183Y780184D03*
Y773491D03*
X1182041Y800263D03*
Y793570D03*
X1177183Y803609D03*
Y796916D03*
Y790223D03*
X1182041Y813648D03*
Y806955D03*
X1181191Y820341D03*
X1177183Y816995D03*
Y810302D03*
X1181191Y830381D03*
X1177183Y833727D03*
Y827034D03*
X1182041Y850459D03*
Y837074D03*
Y843766D03*
X1177183Y847113D03*
Y840420D03*
X1181191Y867192D03*
X1177183Y863845D03*
X1181191Y857152D03*
X1177183Y853806D03*
X1182041Y873885D03*
Y880577D03*
X1177183Y883924D03*
Y877231D03*
Y870538D03*
X1182041Y893963D03*
Y887270D03*
X1177183Y900656D03*
Y890617D03*
X1182041Y917389D03*
Y910696D03*
Y904003D03*
X1177183Y914042D03*
Y907349D03*
X1181191Y930774D03*
Y924081D03*
X1177183Y927428D03*
Y920735D03*
X1182041Y940814D03*
Y947507D03*
X1177183Y937467D03*
Y944160D03*
X1182041Y964239D03*
Y954200D03*
X1177183Y960892D03*
Y950853D03*
Y957546D03*
Y954200D03*
X1182041Y970932D03*
Y977625D03*
X1177183Y974278D03*
Y980971D03*
Y967585D03*
X1182041Y991011D03*
Y984318D03*
X1177183Y987664D03*
Y994357D03*
X1182041Y1031168D03*
Y1017782D03*
Y1024475D03*
X1177183Y1027822D03*
Y1017782D03*
X1182041Y1044554D03*
Y1037861D03*
X1177183Y1047900D03*
Y1041207D03*
Y1034515D03*
X1182041Y1057940D03*
Y1051247D03*
X1177183Y1054593D03*
Y1061286D03*
X1181191Y1078018D03*
X1182041Y1071326D03*
Y1064633D03*
X1177183Y1074672D03*
Y1067979D03*
X1182041Y1094751D03*
X1181191Y1088058D03*
X1177183Y1091404D03*
Y1084711D03*
X1182041Y1101444D03*
Y1108137D03*
X1177183Y1111483D03*
Y1104790D03*
Y1098097D03*
X1182041Y1114829D03*
Y1124869D03*
X1177183Y1128215D03*
Y1121522D03*
X1182041Y1144948D03*
Y1138255D03*
Y1131562D03*
X1177183Y1141601D03*
Y1134908D03*
X1181191Y1161680D03*
Y1151641D03*
X1177183Y1158333D03*
Y1148294D03*
X1182041Y1168373D03*
Y1175066D03*
X1177183Y1171719D03*
Y1165026D03*
X1182041Y1188452D03*
Y1181759D03*
X1177183Y1185105D03*
Y1178412D03*
X1182041Y1205184D03*
Y1198491D03*
X1177183Y1208530D03*
Y1201837D03*
Y1195144D03*
X1181191Y1225263D03*
X1182041Y1211877D03*
Y1218570D03*
X1177183Y1221916D03*
Y1215223D03*
X1182041Y1241995D03*
X1181191Y1235302D03*
X1177183Y1238648D03*
Y1231955D03*
X1182041Y1248688D03*
X1177183Y1245341D03*
X1177120Y1248688D03*
X1176867Y1270029D03*
X1182041Y1265420D03*
X1181850Y1260192D03*
X1198183Y766798D03*
X1190741Y770144D03*
X1198183Y780184D03*
Y773491D03*
X1190741Y783530D03*
Y776837D03*
X1198183Y803609D03*
Y796916D03*
Y790223D03*
X1190741Y800263D03*
Y793570D03*
X1197333Y816995D03*
X1198183Y810302D03*
X1190741Y813648D03*
Y806955D03*
X1191591Y820341D03*
X1198183Y833727D03*
X1197333Y827034D03*
X1191591Y830381D03*
X1198183Y847113D03*
Y840420D03*
X1190741Y850459D03*
Y837074D03*
Y843766D03*
X1197333Y863845D03*
X1191591Y867192D03*
X1198183Y853806D03*
X1191591Y857152D03*
X1198183Y877231D03*
X1197333Y870538D03*
X1198183Y883924D03*
X1190741Y873885D03*
Y880577D03*
X1198183Y900656D03*
Y890617D03*
X1190741Y893963D03*
Y887270D03*
X1198183Y914042D03*
Y907349D03*
X1190741Y917389D03*
Y910696D03*
Y904003D03*
X1197383Y927428D03*
X1198183Y920735D03*
X1191591Y930774D03*
Y924081D03*
X1198183Y944160D03*
X1197333Y937467D03*
X1190741Y940814D03*
Y947507D03*
X1198183Y960892D03*
Y950853D03*
X1190741Y964239D03*
Y954200D03*
X1198183Y957546D03*
Y954200D03*
Y980971D03*
Y974278D03*
Y967585D03*
X1190741Y970932D03*
Y977625D03*
X1198183Y987664D03*
X1190741Y991011D03*
Y984318D03*
X1198183Y994357D03*
Y1027822D03*
Y1017782D03*
X1190741Y1031168D03*
Y1017782D03*
Y1024475D03*
X1198183Y1047900D03*
Y1041207D03*
Y1034515D03*
X1190741Y1044554D03*
Y1037861D03*
X1198183Y1054593D03*
Y1061286D03*
X1190741Y1057940D03*
Y1051247D03*
X1197333Y1074672D03*
X1198183Y1067979D03*
X1191591Y1078018D03*
X1190741Y1071326D03*
Y1064633D03*
X1198183Y1091404D03*
X1197333Y1084711D03*
X1190741Y1094751D03*
X1191591Y1088058D03*
X1198183Y1111483D03*
Y1098097D03*
Y1104790D03*
X1190741Y1101444D03*
Y1108137D03*
X1198183Y1128215D03*
Y1121522D03*
X1190741Y1114829D03*
Y1124869D03*
X1198183Y1141601D03*
X1197333Y1134908D03*
X1190741Y1144948D03*
Y1138255D03*
Y1131562D03*
X1198183Y1158333D03*
X1197333Y1148294D03*
X1191591Y1161680D03*
Y1151641D03*
X1198183Y1165026D03*
Y1171719D03*
X1190741Y1168373D03*
Y1175066D03*
X1198183Y1185105D03*
Y1178412D03*
X1190741Y1188452D03*
Y1181759D03*
X1198183Y1208530D03*
Y1201837D03*
Y1195144D03*
X1190741Y1205184D03*
Y1198491D03*
X1198183Y1221916D03*
Y1215223D03*
X1191591Y1225263D03*
X1190741Y1211877D03*
Y1218570D03*
X1197333Y1238648D03*
Y1231955D03*
X1190741Y1241995D03*
X1191591Y1235302D03*
X1198183Y1245341D03*
X1190966Y1258711D03*
X1190741Y1248688D03*
X1198183Y1252034D03*
X1191538Y1270004D03*
X1198180Y1262112D03*
X1196470Y1265382D03*
X1195994Y1580678D03*
Y1575686D03*
X1200950Y1580678D03*
Y1575686D03*
X1201294Y1599884D03*
X1195994Y1592590D03*
Y1587598D03*
X1200950Y1592590D03*
Y1587598D03*
X1201294Y1604876D03*
Y1611796D03*
Y1616788D03*
X1211741Y770144D03*
X1206883Y766798D03*
X1211641D03*
X1211741Y783530D03*
Y776837D03*
X1206883Y780184D03*
Y773491D03*
X1211741Y800263D03*
Y793570D03*
X1206883Y803609D03*
Y796916D03*
Y790223D03*
X1210891Y820341D03*
Y813648D03*
X1211741Y806955D03*
X1207148Y817554D03*
X1206883Y810302D03*
X1211741Y830381D03*
X1206883Y833727D03*
X1207733Y827034D03*
X1211741Y850459D03*
Y837074D03*
Y843766D03*
X1206883Y847113D03*
Y840420D03*
X1210891Y867492D03*
X1207733Y863845D03*
X1210891Y857152D03*
X1206883Y853806D03*
X1211741Y874185D03*
Y880577D03*
X1206883Y877231D03*
X1207201Y871084D03*
X1206883Y883924D03*
X1211741Y893963D03*
Y887270D03*
X1206883Y900656D03*
Y890617D03*
X1211741Y917389D03*
Y910696D03*
Y904003D03*
X1206883Y914042D03*
Y907349D03*
X1211741Y930774D03*
Y924081D03*
X1207683Y927428D03*
X1206883Y920735D03*
X1211741Y947507D03*
X1211001Y940814D03*
X1206883Y944660D03*
X1207733Y937467D03*
X1211741Y964239D03*
Y954200D03*
X1206883Y960892D03*
Y950853D03*
X1211741Y977625D03*
Y970932D03*
X1206883Y980971D03*
Y974278D03*
Y967585D03*
X1211741Y991011D03*
X1206883Y987664D03*
X1211741Y984318D03*
X1213983Y1000437D03*
X1216663Y1000395D03*
X1212533Y1002557D03*
X1205033D03*
X1207533D03*
X1210033D03*
X1211741Y1031168D03*
X1206883Y1027822D03*
Y1017782D03*
X1211741D03*
Y1024475D03*
Y1044554D03*
Y1037861D03*
X1206883Y1047900D03*
Y1041207D03*
Y1034515D03*
X1211741Y1051247D03*
Y1057940D03*
X1206883Y1054593D03*
Y1061286D03*
X1210891Y1078018D03*
X1211741Y1064633D03*
Y1071326D03*
X1207733Y1074672D03*
X1206883Y1067979D03*
X1211741Y1094751D03*
X1210891Y1088058D03*
X1206883Y1091404D03*
Y1084711D03*
X1211741Y1108137D03*
Y1101444D03*
X1206883Y1111483D03*
Y1098097D03*
Y1104790D03*
X1210891Y1124869D03*
X1211741Y1114829D03*
X1206883Y1128215D03*
Y1121522D03*
X1211741Y1144948D03*
Y1138255D03*
X1210891Y1131562D03*
X1206883Y1141601D03*
X1207733Y1134908D03*
X1211741Y1151641D03*
Y1161680D03*
X1206883Y1158333D03*
X1207733Y1148294D03*
X1211741Y1175066D03*
Y1168373D03*
X1206883Y1165026D03*
Y1171719D03*
X1211741Y1188452D03*
Y1181759D03*
X1206883Y1185105D03*
Y1178412D03*
X1211741Y1205184D03*
Y1198491D03*
X1206883Y1208530D03*
Y1201837D03*
Y1195144D03*
X1210891Y1225263D03*
X1211741Y1218570D03*
Y1211877D03*
X1206883Y1221916D03*
Y1215223D03*
X1211741Y1241995D03*
X1211328Y1234977D03*
X1207733Y1238648D03*
Y1231955D03*
X1206883Y1245341D03*
X1211741Y1248688D03*
X1208830Y1256692D03*
X1206883Y1248688D03*
X1207048Y1255174D03*
X1204608Y1273119D03*
X1202043Y1273123D03*
X1211240Y1265502D03*
X1213010Y1575686D03*
X1208054D03*
X1213010Y1580678D03*
X1208054D03*
X1206250Y1599884D03*
X1213354D03*
X1213010Y1587598D03*
X1208054D03*
X1213010Y1592590D03*
X1208054D03*
X1206250Y1604876D03*
Y1611796D03*
Y1616788D03*
X1213354D03*
Y1604876D03*
Y1611796D03*
X1227883Y766798D03*
X1220441Y770144D03*
X1227883Y780184D03*
Y773491D03*
X1220441Y783530D03*
Y776837D03*
X1227883Y803609D03*
Y796916D03*
Y790223D03*
X1220441Y800263D03*
Y793570D03*
X1227033Y816995D03*
X1227883Y810302D03*
X1221291Y820341D03*
Y813648D03*
X1220441Y806955D03*
X1227883Y833727D03*
X1227033Y827034D03*
X1220441Y830381D03*
X1227883Y847113D03*
Y840420D03*
X1220441Y850459D03*
Y837074D03*
Y843766D03*
X1227033Y863845D03*
X1221291Y867192D03*
X1227033Y853806D03*
X1221291Y857152D03*
X1227883Y870538D03*
Y883924D03*
Y877231D03*
X1220441Y873885D03*
Y880577D03*
X1227033Y900656D03*
X1227883Y890617D03*
X1220441Y893963D03*
Y887270D03*
X1227883Y914042D03*
Y907349D03*
X1220441Y917389D03*
Y910696D03*
Y904003D03*
X1227033Y927428D03*
X1227883Y920735D03*
X1221291Y930774D03*
X1220441Y924081D03*
X1227883Y944160D03*
X1227033Y937467D03*
X1220441Y947507D03*
X1221291Y940814D03*
X1227883Y960892D03*
Y950853D03*
X1220441Y964239D03*
Y954200D03*
X1227883Y957546D03*
Y954200D03*
Y974278D03*
Y967585D03*
X1220441Y977625D03*
Y970932D03*
X1227883Y980971D03*
Y987664D03*
X1220441Y991011D03*
Y984318D03*
X1227883Y994357D03*
X1233703Y999608D03*
X1231023Y999650D03*
X1227883Y1027822D03*
X1220441Y1031168D03*
X1227883Y1017782D03*
X1220441D03*
Y1024475D03*
X1227883Y1047900D03*
Y1041207D03*
Y1034515D03*
X1220441Y1044554D03*
Y1037861D03*
X1227883Y1061286D03*
Y1054593D03*
X1220441Y1051247D03*
Y1057940D03*
Y1061286D03*
X1227033Y1074672D03*
Y1067979D03*
X1221291Y1078018D03*
X1220441Y1064633D03*
Y1071326D03*
X1227883Y1091404D03*
Y1084711D03*
X1220441Y1094751D03*
X1221291Y1088058D03*
X1227883Y1104790D03*
X1227033Y1111483D03*
X1227883Y1098097D03*
X1220441Y1108137D03*
Y1101444D03*
X1227883Y1128215D03*
X1227033Y1121522D03*
X1221291Y1124869D03*
X1220441Y1114829D03*
X1227883Y1134908D03*
Y1141601D03*
X1220441Y1144948D03*
Y1138255D03*
X1221291Y1131562D03*
X1227883Y1158333D03*
Y1148294D03*
X1220441Y1151641D03*
Y1161680D03*
X1227883Y1171719D03*
Y1165026D03*
X1220441Y1175066D03*
Y1168373D03*
X1227883Y1185105D03*
Y1178412D03*
X1220441Y1188452D03*
Y1181759D03*
X1227883Y1208530D03*
Y1201837D03*
X1227033Y1195144D03*
X1220441Y1205184D03*
Y1198491D03*
X1227033Y1221916D03*
X1227883Y1215223D03*
X1221291Y1225263D03*
X1220441Y1218570D03*
Y1211877D03*
X1227883Y1238648D03*
X1227033Y1231955D03*
X1220441Y1241995D03*
X1221291Y1235302D03*
X1220441Y1248688D03*
X1227883Y1245341D03*
X1224189Y1259155D03*
X1226899Y1257968D03*
X1227847Y1251715D03*
X1220601Y1269684D03*
X1220931Y1260093D03*
X1233327Y1274515D03*
X1231377Y1275855D03*
X1227670Y1265162D03*
X1225540Y1266402D03*
X1225070Y1580678D03*
Y1575686D03*
X1220114D03*
Y1580678D03*
X1232174D03*
Y1575686D03*
X1218310Y1599884D03*
X1225414D03*
X1230370D03*
X1225070Y1592590D03*
X1220114D03*
X1225070Y1587598D03*
X1220114D03*
X1232174D03*
Y1592590D03*
X1218310Y1616788D03*
Y1604876D03*
Y1611796D03*
X1225414D03*
Y1604876D03*
X1230370Y1611796D03*
Y1604876D03*
X1225414Y1616788D03*
X1230370D03*
X1236583Y766798D03*
Y780184D03*
Y773491D03*
Y803609D03*
Y796916D03*
Y790223D03*
X1237433Y816995D03*
X1236583Y810302D03*
Y833727D03*
X1237433Y827034D03*
X1236583Y847113D03*
Y840420D03*
X1237433Y863845D03*
Y853806D03*
X1236583Y870538D03*
Y883924D03*
Y877231D03*
Y900656D03*
Y890617D03*
Y914042D03*
Y907349D03*
X1237433Y927428D03*
X1236583Y920735D03*
Y944160D03*
X1237433Y937467D03*
X1236583Y960892D03*
Y950853D03*
Y974278D03*
Y967585D03*
Y980971D03*
Y987664D03*
Y1027822D03*
Y1017782D03*
Y1047900D03*
Y1041207D03*
Y1034515D03*
Y1061286D03*
Y1054593D03*
Y1057940D03*
X1237433Y1074672D03*
Y1067979D03*
X1236583Y1091404D03*
Y1084711D03*
Y1104790D03*
X1237433Y1111483D03*
X1236583Y1098097D03*
Y1128215D03*
X1237433Y1121522D03*
X1236583Y1134908D03*
Y1141601D03*
Y1158333D03*
Y1148294D03*
Y1171719D03*
Y1165026D03*
Y1185105D03*
Y1178412D03*
Y1208530D03*
Y1201837D03*
Y1195144D03*
X1237433Y1221916D03*
X1236583Y1215223D03*
Y1238648D03*
X1237433Y1231955D03*
X1236583Y1245341D03*
Y1248688D03*
X1237130Y1575686D03*
Y1580678D03*
X1244234D03*
X1249190D03*
X1244234Y1575686D03*
X1249190D03*
X1242430Y1599884D03*
X1237474D03*
X1249534D03*
X1237130Y1587598D03*
Y1592590D03*
X1249190D03*
X1244234D03*
Y1587598D03*
X1249190D03*
X1242430Y1616788D03*
X1237474D03*
X1242430Y1611796D03*
Y1604876D03*
X1237474Y1611796D03*
Y1604876D03*
X1249534Y1611796D03*
Y1604876D03*
Y1616788D03*
X1241142Y1675383D03*
Y1679920D03*
X1249016Y1679320D03*
X1241142Y1684454D03*
Y1689556D03*
Y1694093D03*
Y1698627D03*
X1249016Y1688391D03*
Y1693493D03*
Y1698030D03*
Y1683857D03*
X1241142Y1703729D03*
Y1708266D03*
Y1712800D03*
X1249016Y1707666D03*
Y1712203D03*
Y1702564D03*
X1241142Y1726974D03*
Y1722440D03*
Y1717903D03*
X1249016Y1730911D03*
Y1726377D03*
Y1721840D03*
Y1716737D03*
X1261250Y1575686D03*
X1256294D03*
X1261250Y1580678D03*
X1256294D03*
X1254490Y1599884D03*
X1261594D03*
X1261250Y1587598D03*
X1256294D03*
X1261250Y1592590D03*
X1256294D03*
X1254490Y1611796D03*
Y1604876D03*
Y1616788D03*
X1261594D03*
Y1611796D03*
Y1604876D03*
X1256890Y1675383D03*
Y1679920D03*
X1264764Y1679320D03*
X1256890Y1684454D03*
Y1689556D03*
Y1694093D03*
Y1698627D03*
X1264764Y1688391D03*
Y1693493D03*
Y1698030D03*
Y1683857D03*
X1256890Y1703729D03*
Y1708266D03*
Y1712800D03*
X1264764Y1707666D03*
Y1712203D03*
Y1702564D03*
X1256890Y1726974D03*
Y1722440D03*
Y1717903D03*
X1264764Y1730911D03*
Y1726377D03*
Y1721840D03*
Y1716737D03*
X1273310Y1580678D03*
Y1575592D03*
X1268354D03*
Y1580678D03*
X1280414Y1575686D03*
Y1580678D03*
X1266550Y1599884D03*
X1273654Y1599790D03*
X1278610D03*
X1273310Y1592590D03*
X1268354D03*
X1273310Y1587598D03*
X1268354D03*
X1280414D03*
Y1592590D03*
X1266550Y1616788D03*
Y1611796D03*
Y1604876D03*
X1273654Y1611796D03*
Y1604876D03*
X1278610Y1611796D03*
Y1604876D03*
X1273654Y1616788D03*
X1278610D03*
X1272638Y1675383D03*
Y1679920D03*
X1280512Y1679320D03*
X1272638Y1684454D03*
Y1689556D03*
Y1694093D03*
Y1698627D03*
X1280512Y1688391D03*
Y1693493D03*
Y1698030D03*
Y1683857D03*
X1272638Y1703729D03*
Y1708266D03*
Y1712800D03*
X1280512Y1707666D03*
Y1712203D03*
Y1702564D03*
X1272638Y1726974D03*
Y1722440D03*
Y1717903D03*
X1280512Y1730911D03*
Y1726377D03*
Y1721840D03*
Y1716737D03*
X1297012Y157449D03*
X1293802Y159299D03*
Y162999D03*
X1297007Y161149D03*
X1297012Y168549D03*
X1297007Y164849D03*
X1293802Y166699D03*
X1293511Y179048D03*
X1296999Y183349D03*
X1297007Y172249D03*
X1296999Y175949D03*
X1293802Y183349D03*
Y170399D03*
X1294163Y175865D03*
X1296999Y179649D03*
Y194449D03*
Y198149D03*
Y190749D03*
X1293802Y187049D03*
Y190749D03*
Y198149D03*
Y194449D03*
Y201849D03*
X1296999Y187049D03*
Y201849D03*
X1293805Y211099D03*
X1293798Y205833D03*
X1296999Y216649D03*
Y209249D03*
X1293807Y218499D03*
Y214799D03*
X1296999Y212949D03*
Y205549D03*
X1294357Y224688D03*
X1296999Y224049D03*
X1293807Y222199D03*
X1300393Y235762D03*
X1285370Y1575686D03*
Y1580678D03*
X1297430D03*
X1292474D03*
Y1575686D03*
X1297430D03*
X1285714Y1599884D03*
X1290670D03*
X1297774D03*
X1285370Y1587598D03*
Y1592590D03*
X1297430D03*
X1292474D03*
X1297430Y1587598D03*
X1292474D03*
X1290670Y1616788D03*
X1285714D03*
Y1611796D03*
X1290670D03*
X1285714Y1604876D03*
X1290670D03*
X1297774Y1611796D03*
Y1604876D03*
Y1616788D03*
X1296260Y1679320D03*
X1288386Y1675383D03*
Y1679920D03*
X1296260Y1688391D03*
Y1693493D03*
Y1698030D03*
Y1683857D03*
X1288386Y1684454D03*
Y1689556D03*
Y1694093D03*
Y1698627D03*
X1296260Y1707666D03*
Y1712203D03*
Y1702564D03*
X1288386Y1703729D03*
Y1708266D03*
Y1712800D03*
X1296260Y1730911D03*
Y1726377D03*
Y1721840D03*
Y1716737D03*
X1288386Y1726974D03*
Y1722440D03*
Y1717903D03*
X1303417Y164849D03*
X1300213Y162999D03*
X1300212Y166699D03*
X1306622D03*
X1300774Y155288D03*
X1309832Y161149D03*
X1303417D03*
X1309832Y168549D03*
X1303417D03*
X1309832Y157449D03*
X1306626Y162999D03*
Y159299D03*
X1313037Y162999D03*
X1309832Y164849D03*
X1313037Y159299D03*
X1303417Y157449D03*
X1300217Y159299D03*
X1313033Y166699D03*
X1300212Y170399D03*
X1306626D03*
X1303407Y183349D03*
X1309817Y175949D03*
X1300212Y174099D03*
X1313037Y170399D03*
X1300207Y177799D03*
X1303422Y172249D03*
X1313033Y174099D03*
X1306622D03*
X1300207Y185199D03*
X1306617Y181499D03*
Y185199D03*
X1309832Y172249D03*
X1313027Y181499D03*
Y185199D03*
X1303407Y175949D03*
Y179649D03*
X1306617Y177799D03*
X1309817Y179649D03*
X1300204Y181499D03*
X1309817Y194449D03*
X1306617Y188899D03*
X1303407Y194449D03*
X1306617Y196299D03*
X1300207D03*
X1303407Y190749D03*
Y187049D03*
X1300207Y192599D03*
X1309817Y187049D03*
X1306617Y192599D03*
X1313023Y199999D03*
X1306617D03*
X1300207D03*
X1303407Y201849D03*
X1300204Y188899D03*
X1313027Y192599D03*
X1309817Y190749D03*
X1313025Y188899D03*
X1309817Y198149D03*
X1303407D03*
X1300207Y203699D03*
Y207399D03*
X1303422Y209249D03*
X1313032Y214799D03*
X1306622Y218499D03*
X1303417Y212949D03*
Y216649D03*
X1300207Y214799D03*
X1309832Y209249D03*
X1313027Y203699D03*
X1300220Y218499D03*
X1309833Y220349D03*
X1303416Y205549D03*
X1306614Y203699D03*
X1306627Y214799D03*
X1316242Y209249D03*
X1300207Y211099D03*
X1303422Y220349D03*
X1301151Y225450D03*
X1309828Y224049D03*
X1306622Y222199D03*
X1300220D03*
X1313033D03*
X1303425Y224049D03*
X1309100Y236477D03*
X1300493Y238062D03*
X1314184Y849978D03*
X1313920Y854584D03*
X1312266Y857972D03*
X1312070Y877014D03*
X1310221Y880219D03*
X1308370Y877014D03*
X1312070Y896240D03*
X1310220Y893036D03*
X1308371Y902649D03*
X1312070Y915466D03*
X1308370D03*
X1308371Y921875D03*
X1312070Y934692D03*
X1308371Y941100D03*
X1308370Y934692D03*
X1312070Y953917D03*
X1308370D03*
X1310221Y957122D03*
X1308371Y973143D03*
X1310221Y976347D03*
X1307426Y978814D03*
X1311491Y985939D03*
X1314352Y996480D03*
X1314353Y1002888D03*
X1308803Y1006093D03*
X1314353Y1015705D03*
X1308803Y1025318D03*
Y1018910D03*
Y1044544D03*
X1310653Y1041340D03*
X1309976Y1062790D03*
X1305774Y1092168D03*
X1312502Y1082995D03*
X1314353Y1111834D03*
X1311486Y1097289D03*
X1314353Y1124651D03*
X1312503Y1115039D03*
Y1127856D03*
X1314353Y1118243D03*
Y1131060D03*
X1309490Y1575686D03*
X1304534D03*
X1309490Y1580678D03*
X1304534D03*
X1302730Y1599884D03*
X1309834D03*
X1314790D03*
X1309490Y1587598D03*
X1304534D03*
X1309490Y1592590D03*
X1304534D03*
X1302730Y1611796D03*
Y1604876D03*
Y1616788D03*
X1309834D03*
Y1611796D03*
Y1604876D03*
X1314790Y1616788D03*
Y1611796D03*
Y1604876D03*
X1308071Y1675383D03*
Y1679920D03*
Y1684454D03*
Y1689556D03*
Y1694093D03*
Y1698627D03*
Y1703729D03*
Y1708266D03*
Y1712800D03*
Y1726974D03*
Y1722440D03*
Y1717903D03*
X1319452Y162999D03*
X1316242Y168549D03*
X1319442Y159299D03*
X1316241Y157449D03*
X1320469Y155288D03*
X1322652Y161149D03*
X1316242D03*
X1319452Y166699D03*
X1329062Y168549D03*
X1316242Y164849D03*
X1322652D03*
X1329062D03*
X1326918Y161161D03*
X1329062Y157449D03*
X1322652D03*
X1319442Y170399D03*
X1318502Y176574D03*
Y186024D03*
Y182874D03*
X1329062Y172249D03*
X1316237D03*
X1331102Y176574D03*
X1327952Y186024D03*
Y182874D03*
X1325853Y174099D03*
X1331102Y179724D03*
Y182874D03*
Y186024D03*
X1325085Y176402D03*
X1324802Y179724D03*
Y186024D03*
Y182874D03*
X1315352Y186024D03*
Y179724D03*
X1319442Y174099D03*
X1332268D03*
X1318502Y189174D03*
X1315352Y195474D03*
X1327952Y189174D03*
X1331102Y195474D03*
X1327952Y198624D03*
X1321652D03*
X1324802Y195474D03*
X1327952D03*
X1318502D03*
X1321652D03*
X1327952Y201774D03*
X1321652D03*
X1331102Y189174D03*
X1315405Y189227D03*
X1325852Y214799D03*
X1319442Y218499D03*
X1329062Y209249D03*
X1319442Y207399D03*
X1329062Y216649D03*
Y212949D03*
X1325852Y211099D03*
X1319442D03*
X1324802Y204924D03*
X1327952D03*
X1318502D03*
X1315352D03*
X1322652Y209249D03*
X1325857Y218499D03*
X1322652Y216649D03*
X1319442Y222199D03*
X1329061Y224049D03*
X1329062Y220349D03*
X1325856Y222199D03*
X1322652Y224049D03*
Y220349D03*
X1326377Y235784D03*
X1321986Y236726D03*
X1326869Y844971D03*
X1323170D03*
X1321320Y848176D03*
X1330571Y851380D03*
X1323170D03*
X1319469D03*
X1321320Y854584D03*
X1317620D03*
X1315770Y857789D03*
X1328721Y854584D03*
X1330571Y864197D03*
X1326871D03*
X1323171D03*
Y857789D03*
X1325020Y854584D03*
X1321321Y860993D03*
X1319469Y857789D03*
X1328721Y867401D03*
X1325021D03*
Y860993D03*
X1330571Y877014D03*
X1328722Y880219D03*
X1323171Y870606D03*
X1326871Y877014D03*
X1321321Y873810D03*
X1315771Y877014D03*
X1321321Y880219D03*
X1319471Y877014D03*
X1315771Y883423D03*
X1326871D03*
X1323171D03*
X1325020Y873810D03*
X1323171Y877014D03*
X1325020Y880219D03*
X1328720Y899445D03*
X1315771Y896240D03*
Y889832D03*
X1328720Y893036D03*
Y886627D03*
X1325021D03*
X1323171Y889832D03*
X1321321Y893036D03*
X1319470Y896240D03*
X1321321Y899445D03*
X1328720Y905853D03*
X1325020D03*
X1328720Y912262D03*
X1323171Y909057D03*
Y902649D03*
X1321321Y912262D03*
X1315771Y915466D03*
X1319471D03*
X1328720Y925079D03*
Y918670D03*
X1325020Y925079D03*
X1323171Y928283D03*
Y921875D03*
X1321321Y918670D03*
X1328720Y931488D03*
X1321321D03*
X1323171Y941100D03*
X1325020Y944304D03*
X1323171Y947509D03*
X1328720Y944304D03*
Y937896D03*
X1315771Y934692D03*
X1321321Y937896D03*
X1319470Y934692D03*
X1321321Y957122D03*
X1323171Y966735D03*
X1325020Y963530D03*
X1323171Y960326D03*
X1321321Y950713D03*
X1315771Y953917D03*
Y966735D03*
X1319470Y953917D03*
X1328720Y957122D03*
Y963530D03*
Y950713D03*
X1321321Y969939D03*
X1325020Y982756D03*
X1323171Y979552D03*
X1321321Y976347D03*
X1315771Y973143D03*
X1319471D03*
X1328720Y969939D03*
X1330570Y973143D03*
X1326871D03*
X1328720Y982756D03*
X1328721Y976347D03*
X1315771Y979552D03*
X1327304Y1006093D03*
X1331003D03*
X1329153Y1009297D03*
Y1002888D03*
X1323603Y999684D03*
X1321753Y1009297D03*
X1319903Y1006093D03*
X1321753Y1002888D03*
X1323603Y1012501D03*
X1319903Y999684D03*
X1329153Y1028523D03*
Y1015705D03*
X1318053D03*
X1329153Y1022114D03*
X1325453Y1015705D03*
X1323603Y1018910D03*
X1321753Y1028523D03*
Y1022114D03*
X1323603Y1031727D03*
X1329153Y1034931D03*
Y1047749D03*
Y1041340D03*
X1325453Y1034931D03*
X1323603Y1038136D03*
X1321753Y1041340D03*
X1319903Y1044544D03*
X1321753Y1047749D03*
X1329153Y1060565D03*
Y1054157D03*
X1325453D03*
X1323603Y1050952D03*
Y1057361D03*
X1321753Y1060565D03*
X1319903Y1063770D03*
X1329153Y1073383D03*
X1316204Y1076587D03*
X1329153Y1066974D03*
X1323603Y1076587D03*
Y1070178D03*
X1325454Y1073383D03*
X1321753Y1066974D03*
X1329153Y1079791D03*
X1321753D03*
X1329153Y1086200D03*
Y1092608D03*
X1325452Y1092609D03*
X1323603Y1089404D03*
X1321752Y1086200D03*
X1319902Y1082995D03*
X1319849Y1091513D03*
X1331003Y1108630D03*
X1329153Y1099017D03*
X1323603Y1108630D03*
X1316203D03*
Y1102221D03*
X1325453Y1099017D03*
X1323603Y1102221D03*
X1319903D03*
X1325453Y1105426D03*
X1316203Y1115039D03*
X1331003D03*
X1327303Y1121447D03*
Y1115039D03*
X1325453Y1124651D03*
X1325454Y1118243D03*
X1321753D03*
X1319903Y1115039D03*
X1318053Y1124651D03*
X1327304Y1127856D03*
X1329153Y1118243D03*
X1331003Y1121447D03*
X1329152Y1137469D03*
X1329153Y1131060D03*
X1321752Y1137469D03*
X1321753Y1131060D03*
X1325453D03*
X1319903Y1134264D03*
X1331003D03*
X1323603D03*
X1321550Y1580678D03*
X1316594D03*
X1321550Y1575686D03*
X1316594D03*
X1328654D03*
Y1580678D03*
X1321894Y1599884D03*
X1326850D03*
X1321550Y1592590D03*
X1316594D03*
X1321550Y1587598D03*
X1316594D03*
X1328654D03*
Y1592590D03*
X1321894Y1611796D03*
Y1604876D03*
X1326850Y1611796D03*
Y1604876D03*
X1321894Y1616788D03*
X1326850D03*
X1323819Y1675383D03*
Y1679920D03*
X1315945Y1679320D03*
X1323819Y1684454D03*
Y1689556D03*
Y1694093D03*
Y1698627D03*
X1315945Y1688391D03*
Y1693493D03*
Y1698030D03*
Y1683857D03*
X1323819Y1703729D03*
Y1708266D03*
Y1712800D03*
X1315945Y1707666D03*
Y1712203D03*
Y1702564D03*
X1323819Y1726974D03*
Y1722440D03*
Y1717903D03*
X1315945Y1730911D03*
Y1726377D03*
Y1721840D03*
Y1716737D03*
X1339727Y161149D03*
X1341992Y156897D03*
X1344103Y155288D03*
X1342936Y159301D03*
X1335472Y161149D03*
X1346137Y168549D03*
X1342907Y166699D03*
X1332268D03*
X1346137Y164849D03*
X1339727D03*
X1335472Y168549D03*
X1332268Y162999D03*
X1342903Y170399D03*
X1339727Y168549D03*
X1335472Y164849D03*
X1346140Y161149D03*
X1342937Y162999D03*
X1335472Y157449D03*
X1346140D03*
X1339727D03*
X1339568Y176028D03*
X1339727Y179649D03*
X1342937Y181499D03*
Y185199D03*
X1346137Y172249D03*
X1335472D03*
X1332268Y170399D03*
X1334252Y176574D03*
X1339727Y183349D03*
X1346137D03*
X1339727Y190749D03*
X1342937Y188899D03*
X1334252Y195474D03*
X1346137Y194449D03*
Y190749D03*
X1337901Y196035D03*
X1339727Y187049D03*
X1337345Y201831D03*
X1339727Y201849D03*
X1337402Y198624D03*
X1342937Y192599D03*
X1346137Y187049D03*
X1346147Y201849D03*
Y198149D03*
X1336527Y214799D03*
X1339727Y216649D03*
X1346147Y212949D03*
Y216649D03*
X1336527Y218499D03*
X1342937D03*
Y214799D03*
X1346147Y209248D03*
X1337102Y206675D03*
X1332262Y218499D03*
Y214799D03*
Y211099D03*
X1339686Y205478D03*
X1332262Y207399D03*
X1339727Y209249D03*
Y220349D03*
X1336527Y222199D03*
X1346147Y220349D03*
X1332285Y226210D03*
X1342937Y222199D03*
X1332267D03*
X1343521Y841467D03*
X1336121D03*
X1345371Y851380D03*
X1341671D03*
X1337971D03*
X1334271D03*
X1347220Y848176D03*
X1339820D03*
X1332420D03*
X1345371Y864197D03*
X1343521Y854584D03*
X1341671Y864197D03*
X1337971D03*
X1336121Y854584D03*
X1334271Y864197D03*
X1343521Y867401D03*
X1336121D03*
X1339820Y860993D03*
X1347220D03*
X1332420D03*
X1345371Y877014D03*
X1343521Y880219D03*
X1341671Y877014D03*
X1337971D03*
X1336121Y880219D03*
X1334271Y877014D03*
X1339820Y873810D03*
X1332420D03*
X1347220D03*
X1332420Y886627D03*
X1345371Y896240D03*
Y889832D03*
X1341671Y896240D03*
Y889832D03*
X1337970Y896240D03*
X1337971Y889832D03*
X1336121Y893036D03*
X1334270Y889832D03*
X1336121Y899445D03*
X1347220D03*
X1339821Y893036D03*
X1343521D03*
X1347220Y886627D03*
X1339820D03*
X1332420Y905853D03*
X1341671Y909057D03*
Y902649D03*
X1336120Y912262D03*
X1334270Y909057D03*
X1334271Y902649D03*
X1347221Y912262D03*
X1345371Y915466D03*
X1341671D03*
X1337970D03*
X1332421Y925079D03*
X1341671Y928283D03*
Y921875D03*
X1336121Y918670D03*
X1334270Y928283D03*
X1334271Y921875D03*
X1347220Y918670D03*
X1336120Y931488D03*
X1347221D03*
X1341671Y947509D03*
Y941100D03*
X1334270Y947509D03*
X1334271Y941100D03*
X1332421Y944304D03*
X1345371Y934691D03*
X1341671D03*
X1337970D03*
X1336121Y937896D03*
X1347220D03*
X1337971Y953917D03*
X1345371D03*
X1341671D03*
Y960326D03*
X1347220Y957122D03*
X1343520Y963530D03*
X1339821D03*
X1341670Y966735D03*
X1347221Y950713D03*
X1334271Y960326D03*
X1336121Y957122D03*
X1332421Y963530D03*
X1334270Y966735D03*
X1336120Y950713D03*
X1347221Y969939D03*
X1337970Y973143D03*
X1347220Y976347D03*
X1345371Y973143D03*
X1341671Y979552D03*
Y973143D03*
X1336120Y969939D03*
X1336121Y976347D03*
X1334271Y979552D03*
X1332421Y982756D03*
X1345804Y1006093D03*
X1342104Y999684D03*
Y1006093D03*
X1338403D03*
X1336553Y1009297D03*
X1336554Y1002888D03*
X1334704Y999684D03*
X1347654Y1009297D03*
X1342103Y1012501D03*
X1334703D03*
X1332854Y1015705D03*
X1345804Y1025318D03*
X1343953Y1015705D03*
X1342104Y1025318D03*
Y1018910D03*
X1340254Y1015705D03*
X1336553Y1028523D03*
X1338403Y1025318D03*
X1336554Y1022114D03*
X1334704Y1018910D03*
X1347653Y1028523D03*
Y1022114D03*
X1342104Y1031727D03*
X1334703D03*
X1332854Y1034931D03*
X1345804Y1044544D03*
X1342104D03*
Y1038136D03*
X1338403Y1044544D03*
X1336554Y1041340D03*
X1334704Y1038136D03*
X1347653Y1041340D03*
X1336553Y1047749D03*
X1347653D03*
X1332854Y1054157D03*
X1342104Y1057361D03*
Y1050952D03*
X1336554Y1060565D03*
X1334704Y1057361D03*
X1334703Y1050952D03*
X1347653Y1060565D03*
X1345804Y1063770D03*
X1342104D03*
X1338403D03*
X1332854Y1073383D03*
X1342104Y1070178D03*
Y1076587D03*
X1336553Y1066974D03*
X1334703Y1070178D03*
X1334704Y1076587D03*
X1347654Y1066974D03*
X1336554Y1079791D03*
X1347653D03*
X1345804Y1082995D03*
X1342104Y1089404D03*
Y1082995D03*
X1338403D03*
X1336553Y1086200D03*
X1334703Y1089404D03*
X1332854Y1092608D03*
X1347654Y1086200D03*
X1342104Y1095813D03*
X1334703D03*
X1342104Y1102221D03*
X1338404D03*
X1336553Y1099017D03*
X1332853Y1105426D03*
Y1099017D03*
X1347654Y1105426D03*
Y1099017D03*
X1340254Y1111834D03*
X1332854D03*
X1347654D03*
X1334704Y1102221D03*
X1345803D03*
X1343953Y1105426D03*
X1336554D03*
X1343953Y1118243D03*
X1340253D03*
X1338403Y1115039D03*
X1336553Y1118243D03*
X1332853D03*
X1347653D03*
X1342104Y1127856D03*
X1334703D03*
X1345804Y1121447D03*
X1338403D03*
X1343953Y1131060D03*
X1342103Y1140973D03*
X1340254Y1131060D03*
X1336554D03*
X1334703Y1140973D03*
X1332854Y1131060D03*
X1347653D03*
X1338404Y1134264D03*
X1345804D03*
X1333610Y1575686D03*
Y1580678D03*
X1345670D03*
X1340714D03*
X1345670Y1575686D03*
X1340714D03*
X1338910Y1599884D03*
X1333954D03*
X1346014D03*
X1333610Y1587598D03*
Y1592590D03*
X1345670D03*
X1340714D03*
X1345670Y1587598D03*
X1340714D03*
X1338910Y1616788D03*
Y1611796D03*
Y1604876D03*
X1333954Y1616788D03*
Y1611796D03*
Y1604876D03*
X1346014Y1611796D03*
Y1604876D03*
Y1616788D03*
X1339567Y1675383D03*
Y1679920D03*
X1331693Y1679320D03*
X1347441D03*
X1339567Y1684454D03*
Y1689556D03*
Y1694093D03*
Y1698627D03*
X1331693Y1688391D03*
Y1693493D03*
Y1698030D03*
Y1683857D03*
X1347441Y1688391D03*
Y1693493D03*
Y1698030D03*
Y1683857D03*
X1339567Y1703729D03*
Y1708266D03*
Y1712800D03*
X1331693Y1707666D03*
Y1712203D03*
Y1702564D03*
X1347441Y1707666D03*
Y1712203D03*
Y1702564D03*
X1339567Y1726974D03*
Y1722440D03*
Y1717903D03*
X1331693Y1730911D03*
Y1726377D03*
Y1721840D03*
Y1716737D03*
X1347441Y1730911D03*
Y1726377D03*
Y1721840D03*
Y1716737D03*
X1352550Y157449D03*
X1349351Y159298D03*
X1355758D03*
X1355761Y162998D03*
X1358865Y166732D03*
Y158854D03*
Y162793D03*
X1349351Y166698D03*
X1352557Y164848D03*
X1355961Y155458D03*
X1349344Y162999D03*
X1348386Y156646D03*
X1352551Y161148D03*
X1358865Y170671D03*
Y174603D03*
Y182484D03*
Y178544D03*
X1355761Y170398D03*
Y177798D03*
X1352557Y179648D03*
X1358371Y188778D03*
X1358865Y195240D03*
Y199180D03*
X1349351Y196298D03*
X1352561Y194448D03*
X1352551Y190748D03*
X1349345Y188898D03*
X1355761Y192598D03*
X1349351D03*
X1352551Y187048D03*
X1355761Y188898D03*
X1349361Y199998D03*
X1352561Y201848D03*
X1355766Y214798D03*
X1349351Y218498D03*
X1352561Y216648D03*
X1355766Y218498D03*
X1358865Y207060D03*
Y203120D03*
Y213994D03*
Y217934D03*
X1352560Y205549D03*
X1355765Y207399D03*
X1349351Y214798D03*
X1352561Y212948D03*
X1349351Y211098D03*
X1352561Y220348D03*
X1355766Y222198D03*
X1349351D03*
X1360186Y226264D03*
X1358321Y841467D03*
X1350921D03*
X1360171Y851380D03*
X1356471D03*
X1352771D03*
X1349071D03*
X1363871D03*
X1362020Y848176D03*
X1354620D03*
X1360171Y864197D03*
X1358321Y854584D03*
X1356471Y864197D03*
X1352771D03*
X1350921Y854584D03*
X1349071Y864197D03*
X1363871D03*
X1358321Y867401D03*
X1350921D03*
X1362020Y860993D03*
X1354620D03*
X1360171Y877014D03*
X1358321Y880219D03*
X1356471Y877014D03*
X1352771D03*
X1350921Y880219D03*
X1349071Y877014D03*
X1363871D03*
X1354620Y873810D03*
X1362020D03*
X1360171Y889832D03*
X1356471D03*
X1354621Y893036D03*
X1352771Y889832D03*
X1349071D03*
X1363871Y896240D03*
Y889832D03*
X1362021Y899445D03*
X1354620D03*
Y886627D03*
X1362020D03*
Y912262D03*
X1360170Y909057D03*
X1360171Y902649D03*
X1358321Y905853D03*
X1354620Y912262D03*
Y905853D03*
X1350920D03*
X1349071Y909057D03*
X1349070Y902649D03*
X1363870Y915466D03*
X1362021Y918670D03*
X1360170Y928283D03*
X1360171Y921875D03*
X1358321Y925079D03*
X1354620D03*
Y918670D03*
X1350920Y925079D03*
X1349071Y928283D03*
X1349070Y921875D03*
X1362020Y931488D03*
X1354620D03*
X1360171Y941100D03*
X1358321Y944304D03*
X1354620D03*
X1360170Y947509D03*
X1350920Y944304D03*
X1349071Y947509D03*
X1349070Y941100D03*
X1362021Y937896D03*
X1354620D03*
X1363870Y934691D03*
X1363871Y953917D03*
X1360171Y960326D03*
X1362021Y957122D03*
X1354620D03*
X1358321Y963530D03*
X1354620D03*
X1360170Y966735D03*
X1354620Y950713D03*
X1362020D03*
X1349070Y960326D03*
X1350920Y963530D03*
X1349071Y966735D03*
X1362020Y969939D03*
X1354620D03*
X1363870Y973143D03*
X1362021Y976347D03*
X1360171Y979552D03*
X1358321Y982756D03*
X1356470Y973143D03*
X1354620Y982756D03*
X1354621Y976347D03*
X1350920Y982756D03*
X1349070Y979552D03*
X1352771Y973143D03*
X1351352Y996480D03*
X1349503Y999684D03*
X1362453Y1009297D03*
X1362454Y1002888D03*
X1360604Y999684D03*
X1355053Y1009297D03*
Y1002888D03*
X1360603Y1012501D03*
X1349504D03*
X1362453Y1028523D03*
X1362454Y1022114D03*
X1360604Y1018910D03*
X1358754Y1015705D03*
X1355053Y1028523D03*
Y1022114D03*
Y1015705D03*
X1351353D03*
X1349503Y1018910D03*
X1360603Y1031727D03*
X1349504D03*
X1362454Y1041340D03*
X1360604Y1038136D03*
X1358754Y1034931D03*
X1355053Y1041340D03*
Y1034931D03*
X1351353D03*
X1349503Y1038136D03*
X1362453Y1047749D03*
X1355053D03*
X1362454Y1060565D03*
X1360604Y1057361D03*
X1360603Y1050952D03*
X1358754Y1054157D03*
X1355053Y1060565D03*
Y1054157D03*
X1351353D03*
X1349503Y1057361D03*
X1349504Y1050952D03*
X1362453Y1066974D03*
X1360604Y1076587D03*
X1360603Y1070178D03*
X1358754Y1073383D03*
X1355053D03*
Y1066974D03*
X1351353Y1073383D03*
X1349503Y1076587D03*
X1349504Y1070178D03*
X1362453Y1079791D03*
X1355053D03*
X1362453Y1086200D03*
X1360603Y1089404D03*
X1358753Y1092608D03*
X1355053D03*
Y1086200D03*
X1351353Y1092608D03*
X1349504Y1089404D03*
X1360604Y1095813D03*
X1349504D03*
X1351354Y1099017D03*
X1356904Y1095813D03*
X1362454Y1099017D03*
X1360604Y1102221D03*
X1356904Y1108630D03*
X1355053Y1099017D03*
X1353204Y1102221D03*
X1349503Y1108630D03*
Y1102221D03*
X1358753Y1099017D03*
X1362453Y1118243D03*
X1360603Y1115039D03*
X1358753Y1118243D03*
X1355053D03*
X1353203Y1115039D03*
X1351353Y1118243D03*
X1349503Y1115039D03*
X1356903Y1127856D03*
X1349503D03*
X1360604Y1121447D03*
X1353204D03*
X1362453Y1131060D03*
X1358753D03*
X1356903Y1140973D03*
X1355053Y1131060D03*
X1351353D03*
X1349503Y1140973D03*
X1353204Y1134264D03*
X1360604D03*
X1357730Y1575686D03*
X1352774D03*
X1357730Y1580678D03*
X1352774D03*
X1350970Y1599884D03*
X1363030D03*
X1358074D03*
X1357730Y1587598D03*
X1352774D03*
X1357730Y1592590D03*
X1352774D03*
X1350970Y1611796D03*
Y1604876D03*
Y1616788D03*
X1363030D03*
Y1611796D03*
Y1604876D03*
X1358074Y1616788D03*
Y1611796D03*
Y1604876D03*
X1363189Y1679320D03*
X1355315Y1675383D03*
Y1679920D03*
X1363189Y1688391D03*
Y1693493D03*
Y1698030D03*
Y1683857D03*
X1355315Y1684454D03*
Y1689556D03*
Y1694093D03*
Y1698627D03*
X1363189Y1707666D03*
Y1712203D03*
Y1702564D03*
X1355315Y1703729D03*
Y1708266D03*
Y1712800D03*
X1363189Y1730911D03*
Y1726377D03*
Y1721840D03*
Y1716737D03*
X1355315Y1726974D03*
Y1722440D03*
Y1717903D03*
X1373121Y841467D03*
X1365721D03*
X1378671Y851380D03*
X1374971D03*
X1371271D03*
X1367571D03*
X1376820Y848176D03*
X1369420D03*
X1378671Y864197D03*
X1374971D03*
X1373121Y854584D03*
X1371271Y864197D03*
X1367571D03*
X1365721Y854584D03*
X1373121Y867401D03*
X1365721D03*
X1376820Y860993D03*
X1369420D03*
X1378671Y877014D03*
X1374971D03*
X1373121Y880219D03*
X1371271Y877014D03*
X1367571D03*
X1365721Y880219D03*
X1369420Y873810D03*
X1376820D03*
X1378671Y889832D03*
X1374971D03*
X1371271Y896240D03*
Y889832D03*
X1367570Y896240D03*
X1367571Y889832D03*
X1365721Y893036D03*
X1373120Y899445D03*
X1378671Y896240D03*
X1376820Y899445D03*
X1369421Y893036D03*
X1373121D03*
X1374971Y896240D03*
X1376820Y893036D03*
X1369420Y886627D03*
X1376820D03*
X1380520Y899445D03*
X1374971Y909057D03*
X1374970Y902649D03*
X1373121Y912262D03*
X1367571Y909057D03*
Y902649D03*
X1371271Y915466D03*
X1367571D03*
X1376820Y905853D03*
X1378671Y915466D03*
Y909057D03*
X1376820Y912262D03*
X1378671Y902649D03*
X1376820Y931488D03*
X1378671Y928283D03*
X1376820Y925079D03*
X1374971Y928283D03*
X1374970Y921875D03*
X1373120Y918670D03*
X1367571Y928283D03*
Y921875D03*
X1373120Y931488D03*
X1378671Y921875D03*
X1374971Y934691D03*
X1378671D03*
X1376820Y937896D03*
X1374970Y941100D03*
X1373120Y937896D03*
X1371271Y934691D03*
X1367571Y941100D03*
Y934691D03*
X1374971Y947509D03*
X1367571D03*
X1378671D03*
X1376820Y957122D03*
X1374970Y960326D03*
X1373120Y957122D03*
X1373121Y950713D03*
X1371271Y953917D03*
X1367571Y960326D03*
Y953917D03*
X1376820Y963530D03*
X1374971Y966735D03*
X1367571D03*
X1378671D03*
Y960326D03*
Y953917D03*
X1374971D03*
X1376822Y950713D03*
X1376820Y982756D03*
Y969939D03*
X1374970Y979552D03*
X1373120Y976347D03*
X1373121Y969939D03*
X1371271Y973143D03*
X1367571Y979552D03*
Y973143D03*
X1364303Y1006093D03*
X1377253Y1002888D03*
X1373554Y1009297D03*
X1373553Y1002888D03*
X1371704Y1006093D03*
X1368004D03*
Y999684D03*
X1375404Y1012501D03*
X1368003D03*
X1375404Y1006093D03*
X1379104D03*
X1375404Y999684D03*
X1379104D03*
X1377253Y1009297D03*
X1379104Y1012501D03*
Y1031727D03*
X1364303Y1025318D03*
X1375403Y1018910D03*
X1373553Y1028523D03*
Y1022114D03*
X1371704Y1025318D03*
X1369853Y1015705D03*
X1368004Y1025318D03*
Y1018910D03*
X1366154Y1015705D03*
X1375404Y1031727D03*
X1368004D03*
X1377253Y1028523D03*
X1375404Y1025318D03*
X1377253Y1022114D03*
X1379102Y1018910D03*
X1379104Y1025318D03*
X1377253Y1015705D03*
X1364303Y1044544D03*
X1375403Y1038136D03*
X1373553Y1041340D03*
X1371704Y1044544D03*
X1368004D03*
Y1038136D03*
X1373553Y1047749D03*
X1375404Y1044544D03*
X1377253Y1041340D03*
X1379104Y1044544D03*
Y1038136D03*
X1377253Y1047749D03*
X1375403Y1057361D03*
X1375404Y1050952D03*
X1373553Y1060565D03*
X1368004Y1057361D03*
Y1050952D03*
X1364303Y1063770D03*
X1371704D03*
X1368004D03*
X1379104Y1057361D03*
Y1063770D03*
X1377255Y1060565D03*
X1375404Y1063770D03*
X1377253Y1054157D03*
X1379104Y1050952D03*
X1380953Y1054157D03*
X1379104Y1076587D03*
Y1070178D03*
X1377253Y1073383D03*
X1375403Y1076587D03*
X1375404Y1070178D03*
X1373554Y1066974D03*
X1368004Y1076587D03*
Y1070178D03*
X1377253Y1079791D03*
X1373553D03*
X1377254Y1066974D03*
X1364303Y1082995D03*
X1377254Y1092608D03*
X1377253Y1086200D03*
X1375404Y1089404D03*
X1373554Y1086200D03*
X1371704Y1082995D03*
X1368004Y1089404D03*
Y1082995D03*
X1379104Y1095813D03*
X1375403D03*
X1368004D03*
X1375404Y1082995D03*
X1364304Y1108630D03*
Y1102221D03*
X1377253Y1105426D03*
X1375404Y1102221D03*
X1373554Y1099017D03*
X1371704Y1102221D03*
X1366153Y1105426D03*
X1373553Y1111834D03*
X1366153D03*
X1368004Y1102221D03*
X1369853Y1105426D03*
X1364303Y1115039D03*
X1377253Y1118243D03*
X1373553D03*
X1371703Y1115039D03*
X1369853Y1118243D03*
X1366153D03*
X1364303Y1127856D03*
X1379103D03*
X1371703D03*
X1368004Y1121447D03*
X1375404D03*
X1364303Y1140973D03*
X1379103D03*
X1377253Y1131060D03*
X1373553D03*
X1371703Y1140973D03*
X1369853Y1131060D03*
X1366153D03*
X1368004Y1134264D03*
X1375404D03*
X1374847Y1153069D03*
X1369790Y1580678D03*
X1364834D03*
X1369790Y1575592D03*
X1364834D03*
X1376894Y1575686D03*
Y1580678D03*
X1375090Y1599790D03*
X1370134D03*
X1369790Y1592590D03*
X1364834D03*
X1369790Y1587598D03*
X1364834D03*
X1376894D03*
Y1592590D03*
X1375090Y1611796D03*
Y1604876D03*
Y1616788D03*
X1370134Y1611796D03*
Y1604876D03*
Y1616788D03*
X1380521Y841467D03*
X1395321D03*
X1387921D03*
X1393471Y851380D03*
X1389771D03*
X1386071D03*
X1382371D03*
X1391620Y848176D03*
X1384220D03*
X1380521Y854584D03*
X1395321D03*
X1393471Y864197D03*
X1389771D03*
X1387921Y854584D03*
X1386071Y864197D03*
X1382371D03*
X1380521Y867401D03*
X1395321D03*
X1387921D03*
X1384220Y860993D03*
X1391620D03*
X1380521Y880219D03*
X1395321D03*
X1393471Y877014D03*
X1389771D03*
X1387921Y880219D03*
X1386071Y877014D03*
Y870606D03*
X1382371Y877014D03*
X1391620Y873810D03*
X1384220D03*
X1395321Y893036D03*
X1393471Y889832D03*
X1389771D03*
X1387921Y893036D03*
X1386071Y889832D03*
X1384221Y893036D03*
X1382371Y889832D03*
X1380520Y893036D03*
X1382371Y896240D03*
X1384220Y886627D03*
X1391620D03*
Y899445D03*
X1384221Y899446D03*
X1386071Y902649D03*
X1380520Y912262D03*
Y905853D03*
X1395320Y912262D03*
X1395321Y905853D03*
X1393471Y902649D03*
X1389771D03*
X1386071Y909057D03*
Y915466D03*
X1393471Y909057D03*
X1382371D03*
X1389771D03*
Y915466D03*
X1399020Y905853D03*
X1382371Y915466D03*
X1384220Y918670D03*
X1387920Y905853D03*
X1384220D03*
Y912262D03*
X1382371Y902649D03*
X1391620Y905853D03*
X1387920Y912262D03*
X1391620D03*
X1393471Y915466D03*
X1391621Y918670D03*
X1380520D03*
X1395187Y926265D03*
X1395320Y918670D03*
X1386071Y921875D03*
X1381189Y930811D03*
X1382371Y921875D03*
X1382809Y927986D03*
X1385070Y928468D03*
X1393471Y921875D03*
X1391550Y925219D03*
X1387921Y918670D03*
X1381189Y938045D03*
X1381287Y946239D03*
Y948539D03*
X1381189Y935745D03*
X1390234Y942097D03*
X1386030Y942163D03*
X1383730D03*
X1381430D03*
X1392534Y942097D03*
X1394834D03*
X1381264Y965896D03*
Y963596D03*
X1393826Y956619D03*
X1387826D03*
X1391326D03*
X1385526D03*
X1390506Y971139D03*
X1392896D03*
X1381003Y981269D03*
Y978969D03*
X1380926Y971099D03*
X1383226D03*
X1387826D03*
X1385526D03*
X1396346D03*
X1381003Y986421D03*
X1381243Y992971D03*
Y995271D03*
X1381003Y988721D03*
X1393716Y985579D03*
X1391326D03*
X1396286Y985549D03*
X1388506Y985609D03*
X1386206D03*
X1381369Y1007156D03*
X1381373Y1004848D03*
X1391326Y1014539D03*
X1393716D03*
Y1000059D03*
X1391326D03*
X1385526Y1014539D03*
X1387826D03*
X1383226D03*
X1386226Y1000079D03*
X1396356Y1000039D03*
X1388526Y1000079D03*
X1396546Y1014469D03*
X1381128Y1022427D03*
X1381140Y1026821D03*
X1388102Y1028854D03*
X1390602D03*
X1393102D03*
X1395602D03*
X1384466Y1034270D03*
Y1031970D03*
X1393904Y1044544D03*
X1384653Y1041340D03*
X1380953Y1047749D03*
X1388353D03*
X1380953Y1041340D03*
X1388353D03*
X1392053D03*
X1395753D03*
Y1047749D03*
X1392053D03*
X1382804Y1044544D03*
X1386504D03*
X1384653Y1047749D03*
X1390204Y1044544D03*
X1382804Y1050952D03*
X1380953Y1060565D03*
X1393904Y1050952D03*
X1392053Y1060565D03*
Y1054157D03*
X1388353Y1060565D03*
X1386504Y1050952D03*
X1384653Y1054157D03*
X1382804Y1057361D03*
X1386504D03*
X1390204Y1050952D03*
X1393904Y1057361D03*
X1395753Y1054157D03*
X1382804Y1063770D03*
X1384653Y1060565D03*
X1386504Y1063770D03*
X1388353Y1054157D03*
X1390204Y1057361D03*
X1393904Y1063770D03*
X1390204D03*
X1395753Y1060565D03*
Y1079791D03*
X1384653Y1073383D03*
X1382804Y1070178D03*
X1380953Y1073383D03*
Y1066974D03*
X1395753Y1073383D03*
X1392053Y1066974D03*
X1386504Y1076587D03*
Y1070178D03*
X1382803Y1076587D03*
X1380953Y1079791D03*
X1388353D03*
X1393904Y1076587D03*
X1392053Y1079791D03*
X1384653Y1066974D03*
X1388353Y1073383D03*
X1392053D03*
X1390204Y1070178D03*
X1393904D03*
X1388353Y1066974D03*
X1395753D03*
X1393903Y1089404D03*
Y1082995D03*
X1392053Y1092608D03*
X1392054Y1086200D03*
X1388353Y1092608D03*
X1384653Y1086200D03*
X1386504Y1095813D03*
X1382804D03*
X1395754Y1099017D03*
X1380953Y1092608D03*
X1393904Y1095813D03*
X1390203D03*
X1380954Y1105426D03*
X1393904Y1102221D03*
X1392054Y1099017D03*
X1390204Y1108630D03*
X1388353Y1099017D03*
X1386504Y1102221D03*
X1382803Y1108630D03*
Y1102221D03*
X1380954Y1111834D03*
X1380953Y1118243D03*
X1393903Y1115039D03*
X1392053Y1118243D03*
X1390203Y1121447D03*
X1388353Y1124651D03*
Y1118243D03*
X1386503Y1115039D03*
X1384653Y1118243D03*
X1382803Y1115039D03*
X1386503Y1127856D03*
X1392054Y1124651D03*
X1393903Y1121447D03*
Y1127856D03*
X1395754Y1118243D03*
Y1124651D03*
X1382803Y1121447D03*
X1390204Y1127856D03*
X1380953Y1131060D03*
X1390204Y1134264D03*
X1388354Y1131060D03*
X1386503Y1140973D03*
X1384653Y1131060D03*
X1382804Y1134264D03*
X1390203Y1140973D03*
X1392054Y1131060D03*
Y1137469D03*
X1393903Y1134264D03*
Y1140973D03*
X1395754Y1131060D03*
Y1137469D03*
X1388354D03*
X1381850Y1575686D03*
Y1580678D03*
X1387150Y1599884D03*
X1382194D03*
X1381850Y1587598D03*
Y1592590D03*
X1387150Y1616788D03*
X1382194D03*
X1387150Y1611796D03*
Y1604876D03*
X1382194Y1611796D03*
Y1604876D03*
X1408269Y844971D03*
X1402721Y841467D03*
X1397171Y851380D03*
X1408271D03*
X1404571D03*
X1400871D03*
X1411971D03*
X1399020Y848176D03*
X1397171Y864197D03*
X1408271D03*
X1404571D03*
X1402721Y854584D03*
X1400871Y864197D03*
X1410121Y854584D03*
X1411971Y864197D03*
X1410121Y867401D03*
X1402721D03*
X1406420Y860993D03*
X1399020D03*
X1397171Y877014D03*
X1410121Y880219D03*
X1408271Y877014D03*
X1404571D03*
X1402721Y880219D03*
X1400871Y877014D03*
X1411971D03*
X1399020Y873810D03*
X1406420D03*
X1397171Y889832D03*
X1410121Y893036D03*
X1408271Y889832D03*
X1404571D03*
X1402721Y893036D03*
X1400871Y889832D03*
X1411971D03*
X1406420Y886627D03*
X1399020D03*
X1406420Y899445D03*
X1399020D03*
Y912262D03*
X1400871Y915466D03*
X1402720Y912262D03*
X1400871Y902649D03*
X1397171D03*
X1408271D03*
X1404571Y909057D03*
Y902649D03*
X1411971D03*
X1404571Y915466D03*
X1406420Y912262D03*
X1408271Y915466D03*
X1397171Y909057D03*
X1411971D03*
Y915466D03*
X1408270Y909057D03*
X1410120Y905853D03*
X1400870Y909057D03*
X1406420Y905853D03*
X1402720D03*
X1397171Y915466D03*
X1410121Y912262D03*
X1406420Y918670D03*
X1410121Y925079D03*
Y931488D03*
X1404571Y921875D03*
X1408271D03*
X1410121Y918670D03*
X1411971Y921875D03*
X1401528Y927155D03*
X1399028D03*
X1401817Y929464D03*
X1399317D03*
X1400871Y921875D03*
X1399020Y918670D03*
X1397171Y921875D03*
X1402720Y918670D03*
X1411971Y934691D03*
X1406420Y925079D03*
X1408271Y928283D03*
X1406420Y931488D03*
X1411971Y928283D03*
X1403016Y949498D03*
Y947198D03*
X1406420Y937896D03*
X1404016Y936469D03*
X1410120Y937896D03*
X1410121Y944304D03*
X1406421D03*
X1408271Y941100D03*
X1411971D03*
X1404016Y944229D03*
Y941929D03*
X1408270Y947509D03*
X1411971D03*
X1408271Y934691D03*
X1403046Y963634D03*
Y965934D03*
X1410121Y957122D03*
Y950713D03*
Y963530D03*
X1406421Y950713D03*
Y957122D03*
X1408270Y953917D03*
Y960326D03*
X1411971Y953917D03*
Y960326D03*
X1404016Y954072D03*
Y956372D03*
X1401326Y956619D03*
X1398826D03*
X1406421Y963530D03*
X1408270Y966735D03*
X1411971D03*
X1403046Y978035D03*
Y980335D03*
X1410121Y976347D03*
Y969939D03*
Y982756D03*
X1406421Y969939D03*
X1406409Y976347D03*
X1408270Y973143D03*
X1411971D03*
X1404016Y971266D03*
Y968966D03*
X1398826Y971099D03*
X1406421Y982756D03*
X1408270Y979552D03*
X1411971D03*
X1404016Y983110D03*
X1403046Y992421D03*
Y994721D03*
X1404016Y985410D03*
X1398826Y985579D03*
X1404016Y997520D03*
X1403046Y1009174D03*
Y1006874D03*
X1410553Y1009297D03*
Y1002888D03*
X1412404Y999684D03*
Y1006093D03*
Y1012501D03*
X1406853Y1002888D03*
Y1009297D03*
X1408703Y999684D03*
Y1006093D03*
Y1012501D03*
X1404016Y1012151D03*
Y999820D03*
X1398826Y1000059D03*
X1404016Y1014451D03*
X1399156Y1014469D03*
X1403046Y1021962D03*
Y1019662D03*
X1410553Y1028523D03*
Y1022114D03*
Y1015705D03*
X1398102Y1028854D03*
X1406853Y1028523D03*
X1412404Y1018910D03*
X1406853Y1015705D03*
Y1022114D03*
X1408703Y1018910D03*
X1412404Y1025318D03*
X1408703D03*
X1404016Y1026703D03*
X1412404Y1031727D03*
X1408703D03*
X1404016Y1029003D03*
Y1031303D03*
X1405004Y1044544D03*
X1410553Y1034931D03*
X1406854Y1047749D03*
X1399453D03*
X1403153D03*
X1403154Y1041340D03*
X1399454D03*
X1401304Y1044544D03*
X1412403Y1038136D03*
Y1044544D03*
X1406853Y1034931D03*
Y1041340D03*
X1408703Y1038136D03*
Y1044544D03*
X1410554Y1041340D03*
X1404016Y1033603D03*
X1399426Y1036883D03*
Y1034583D03*
Y1032283D03*
X1410554Y1047749D03*
X1397604Y1044544D03*
X1403153Y1054157D03*
X1406853D03*
X1408703Y1050952D03*
X1401304Y1057361D03*
X1410553Y1060565D03*
Y1054157D03*
X1397604Y1063770D03*
X1405003Y1057361D03*
X1408703D03*
Y1063770D03*
X1412404Y1050952D03*
Y1057361D03*
Y1063770D03*
X1397604Y1057361D03*
X1401304Y1050952D03*
X1399453Y1054157D03*
X1405004Y1050952D03*
X1397604D03*
X1401304Y1063770D03*
X1399453Y1060565D03*
X1403153D03*
X1405003Y1063770D03*
X1406853Y1060565D03*
X1397604Y1076587D03*
X1408703D03*
X1406853Y1073383D03*
X1403153D03*
Y1066974D03*
X1401304Y1076587D03*
X1399453Y1066974D03*
X1410553Y1073383D03*
Y1066974D03*
X1403154Y1079791D03*
X1410553D03*
X1408702Y1070178D03*
X1399453Y1073383D03*
Y1079791D03*
X1412404Y1070178D03*
Y1076587D03*
X1397604Y1070178D03*
X1401304D03*
X1405004D03*
X1406853Y1066974D03*
X1408703Y1089404D03*
Y1082995D03*
X1405003D03*
X1401304Y1089404D03*
X1397604Y1082995D03*
X1410553Y1092608D03*
Y1086200D03*
X1408703Y1095813D03*
X1405003D03*
X1397604D03*
X1412404Y1082995D03*
Y1089404D03*
X1412403Y1095813D03*
X1403153Y1099017D03*
X1401303Y1102221D03*
X1399453Y1105426D03*
X1397604Y1108630D03*
X1410553Y1105426D03*
X1399453Y1111834D03*
X1410553D03*
X1397604Y1102221D03*
X1399453Y1099017D03*
X1412404Y1102221D03*
Y1108630D03*
X1401304D03*
X1403154Y1105426D03*
Y1111834D03*
X1405003Y1102221D03*
Y1108630D03*
X1406853Y1099017D03*
Y1105426D03*
Y1111834D03*
X1408703Y1102221D03*
Y1108630D03*
X1410554Y1099017D03*
X1399453Y1124651D03*
Y1118243D03*
X1397604Y1115039D03*
X1410553Y1124651D03*
Y1118243D03*
X1412404Y1115039D03*
Y1121447D03*
Y1127856D03*
X1397603Y1121447D03*
Y1127856D03*
X1401304Y1115039D03*
Y1121447D03*
Y1127856D03*
X1403154Y1118243D03*
Y1124651D03*
X1405003Y1115039D03*
Y1121447D03*
Y1127856D03*
X1406853Y1118243D03*
Y1124651D03*
X1408703Y1115039D03*
Y1121447D03*
Y1127856D03*
X1399454Y1137469D03*
X1399453Y1131060D03*
X1410554Y1137769D03*
X1410553Y1131060D03*
X1412403Y1134264D03*
X1397603D03*
Y1140973D03*
X1401304Y1134264D03*
X1401303Y1140973D03*
X1403154Y1131060D03*
Y1137569D03*
X1405003Y1134264D03*
Y1140973D03*
X1406853Y1131060D03*
Y1137769D03*
X1408703Y1134264D03*
X1428620Y848176D03*
X1415669Y844971D03*
X1421220Y848176D03*
X1417520D03*
X1426771Y851380D03*
X1423070D03*
X1419370D03*
X1415671D03*
X1413822Y860993D03*
X1426771Y864197D03*
X1424921Y854584D03*
X1423071Y864197D03*
X1419371D03*
X1417521Y854584D03*
X1415671Y864197D03*
Y857789D03*
X1424921Y867401D03*
X1417521D03*
X1421220Y860993D03*
X1428621D03*
X1426771Y877014D03*
X1424921Y880219D03*
X1423071Y877014D03*
X1419371D03*
X1417521Y880219D03*
X1415671Y877014D03*
X1413821Y873810D03*
X1428621D03*
X1421220D03*
X1413820Y886627D03*
X1426771Y889832D03*
X1424921Y893036D03*
X1423071Y889832D03*
X1419371D03*
X1417521Y893036D03*
X1415671Y896240D03*
Y889832D03*
X1413821Y899445D03*
X1428620D03*
Y886627D03*
X1421220D03*
X1413820Y912262D03*
X1413821Y905853D03*
X1426771Y902649D03*
X1423071Y909057D03*
Y902649D03*
X1419371D03*
X1415670D03*
X1423071Y915466D03*
X1419371Y909057D03*
X1415671Y915466D03*
X1421221Y905853D03*
X1417521D03*
X1430471Y909057D03*
X1426772D03*
X1428621Y905853D03*
X1424921D03*
X1424922Y912262D03*
X1417522D03*
X1415671Y909057D03*
X1421222Y912262D03*
X1419371Y915466D03*
X1426771D03*
X1428620Y912262D03*
X1424921Y918670D03*
X1430471Y915466D03*
X1415671Y921875D03*
X1423071Y928283D03*
X1417520Y925079D03*
Y931488D03*
X1413820Y918670D03*
X1423071Y921875D03*
X1417520Y918670D03*
X1426771Y921875D03*
X1421220Y918670D03*
X1419371Y921875D03*
X1428620Y918670D03*
X1424921Y931488D03*
X1419371Y928283D03*
X1413820Y931488D03*
X1424921Y925079D03*
X1419371Y934691D03*
X1421220Y931488D03*
Y925079D03*
X1415671Y928283D03*
X1413820Y925079D03*
X1426771Y928283D03*
X1424920Y937896D03*
X1421220D03*
X1417520D03*
X1413820D03*
X1423070Y941100D03*
X1423071Y947509D03*
X1413821Y944304D03*
X1415671Y941100D03*
X1417521Y944304D03*
X1419371Y941100D03*
X1421220Y944304D03*
X1424921D03*
X1426771Y941100D03*
X1415670Y947509D03*
X1419370D03*
X1426771D03*
X1423071Y934691D03*
X1415671D03*
X1423071Y960326D03*
Y953917D03*
Y966735D03*
X1413821Y950713D03*
Y957122D03*
X1415670Y953917D03*
Y960326D03*
X1417521Y950713D03*
Y957122D03*
X1419370Y953917D03*
Y960326D03*
X1421220Y950713D03*
Y957122D03*
X1424921Y950713D03*
Y957122D03*
X1426771Y953917D03*
Y960326D03*
X1413821Y963530D03*
X1415670Y966735D03*
X1417521Y963530D03*
X1419370Y966735D03*
X1421220Y963530D03*
X1424921D03*
X1426771Y966735D03*
X1423071Y979552D03*
Y973143D03*
X1413821Y969939D03*
Y976347D03*
X1415670Y973143D03*
X1417521Y969939D03*
Y976347D03*
X1419370Y973143D03*
X1421220Y969939D03*
Y976347D03*
X1424921Y969939D03*
Y976347D03*
X1426771Y973143D03*
X1413821Y982756D03*
X1415670Y979552D03*
X1417521Y982756D03*
X1419370Y979552D03*
X1421220Y982756D03*
X1424921D03*
X1426771Y979552D03*
X1423503Y1006093D03*
Y999684D03*
Y1012501D03*
X1414254Y1002888D03*
Y1009297D03*
X1416103Y999684D03*
Y1006093D03*
Y1012501D03*
X1417954Y1002888D03*
Y1009297D03*
X1419803Y999684D03*
Y1006093D03*
Y1012501D03*
X1421653Y1002888D03*
Y1009297D03*
X1425354Y1002888D03*
Y1009297D03*
X1427203Y999684D03*
Y1006093D03*
Y1012501D03*
X1423503Y1025318D03*
Y1018910D03*
Y1031727D03*
X1421653Y1028523D03*
X1414254D03*
X1417954D03*
X1425354D03*
X1414254Y1015705D03*
Y1022114D03*
X1416103Y1018910D03*
X1417954Y1015705D03*
Y1022114D03*
X1419803Y1018910D03*
X1421653Y1015705D03*
Y1022114D03*
X1425354Y1015705D03*
Y1022114D03*
X1427203Y1018910D03*
X1416103Y1025318D03*
X1419803D03*
X1427203D03*
X1416103Y1031727D03*
X1419803D03*
X1427203D03*
X1429053Y1041340D03*
X1427203Y1044544D03*
X1423503Y1038136D03*
X1425353Y1047749D03*
X1429053D03*
X1414254Y1034931D03*
Y1041340D03*
X1416103Y1038136D03*
Y1044544D03*
X1417954Y1034931D03*
Y1041340D03*
X1419803Y1038136D03*
Y1044544D03*
X1421653Y1034931D03*
Y1041340D03*
X1423503Y1044544D03*
X1425354Y1034931D03*
X1425353Y1041340D03*
X1427203Y1038136D03*
X1421653Y1047749D03*
X1414254D03*
X1417954D03*
X1429053Y1060565D03*
X1423503Y1057361D03*
Y1050952D03*
Y1063770D03*
X1425353Y1054157D03*
X1425355Y1060565D03*
X1414254Y1054157D03*
X1416103Y1050952D03*
X1417954Y1054157D03*
X1419803Y1050952D03*
X1421653Y1054157D03*
X1414254Y1060565D03*
X1416103Y1057361D03*
X1417954Y1060565D03*
X1419803Y1057361D03*
X1421653Y1060565D03*
X1416103Y1063770D03*
X1419803D03*
X1427203D03*
X1429053Y1054157D03*
X1427203Y1050952D03*
X1430903D03*
X1430904Y1057361D03*
X1427204D03*
X1425353Y1073383D03*
X1423503Y1076587D03*
Y1070178D03*
X1429053Y1079791D03*
X1425353D03*
X1429053Y1073383D03*
X1427203Y1076587D03*
X1414254Y1066974D03*
Y1073383D03*
X1416103Y1070178D03*
Y1076587D03*
X1417954Y1066974D03*
Y1073383D03*
X1419803Y1070178D03*
Y1076587D03*
X1421653Y1066974D03*
Y1073383D03*
X1414254Y1079791D03*
X1417954D03*
X1421653D03*
X1429053Y1066974D03*
X1425353D03*
X1427204Y1070178D03*
X1429053Y1092608D03*
X1427204Y1089404D03*
X1425354Y1086200D03*
X1423503Y1082995D03*
X1427203Y1095812D03*
X1429053Y1086200D03*
X1416103Y1082995D03*
X1419803D03*
X1414254Y1086200D03*
Y1092608D03*
X1416103Y1089404D03*
Y1095813D03*
X1417954Y1086200D03*
Y1092608D03*
X1419803Y1089404D03*
Y1095813D03*
X1421653Y1086200D03*
Y1092608D03*
X1423503Y1089404D03*
Y1095813D03*
X1425353Y1092608D03*
X1427202Y1082995D03*
X1429053Y1099017D03*
X1423503Y1108630D03*
Y1102221D03*
X1414254Y1099017D03*
Y1105426D03*
Y1111834D03*
X1416103Y1102221D03*
Y1108630D03*
X1417954Y1099017D03*
Y1105426D03*
Y1111834D03*
X1419803Y1102221D03*
Y1108630D03*
X1421653Y1099017D03*
Y1105426D03*
Y1111834D03*
X1425354Y1099017D03*
Y1105426D03*
Y1111834D03*
X1427203Y1102221D03*
Y1108630D03*
X1429054Y1105426D03*
Y1111834D03*
X1423503Y1121447D03*
Y1115039D03*
Y1127856D03*
X1414254Y1118243D03*
Y1124651D03*
X1416103Y1115039D03*
Y1121447D03*
Y1127856D03*
X1417954Y1118243D03*
Y1124651D03*
X1419803Y1115039D03*
Y1121447D03*
Y1127856D03*
X1421653Y1118243D03*
Y1124651D03*
X1425354Y1118243D03*
Y1124651D03*
X1427203Y1115039D03*
Y1121447D03*
Y1127856D03*
X1429054Y1118243D03*
Y1124651D03*
X1423503Y1134264D03*
X1414254Y1131060D03*
Y1137769D03*
X1416103Y1134264D03*
X1417954Y1131060D03*
Y1137769D03*
X1419803Y1134264D03*
X1421653Y1131060D03*
Y1137769D03*
X1425354Y1131060D03*
Y1137769D03*
X1427203Y1134264D03*
X1429054Y1131060D03*
Y1137769D03*
X1437871Y851380D03*
X1434171D03*
X1430470D03*
X1432321Y841467D03*
X1439721D03*
X1445271Y851380D03*
X1441571D03*
X1443420Y848176D03*
X1436020D03*
X1439721Y854584D03*
X1432321D03*
X1437871Y864197D03*
X1434171D03*
X1430471D03*
X1445271D03*
X1441571D03*
X1432321Y867401D03*
X1439721D03*
X1443420Y860993D03*
X1436020D03*
X1437871Y877014D03*
X1434171D03*
X1432321Y880219D03*
X1430471Y877014D03*
X1445271D03*
X1441571D03*
X1439721Y880219D03*
X1436020Y873810D03*
X1443420D03*
X1437871Y889832D03*
X1434171D03*
X1432321Y893036D03*
X1430471Y889832D03*
X1445271Y896240D03*
X1439721Y893036D03*
X1445271Y889832D03*
X1441571D03*
X1436020Y899445D03*
X1443420D03*
X1436020Y886627D03*
X1443420D03*
X1447120Y899445D03*
X1437871Y902649D03*
X1434171D03*
X1432320Y912262D03*
Y905853D03*
X1430471Y902649D03*
X1441571D03*
Y909057D03*
Y915466D03*
X1445271Y902649D03*
X1434171Y909057D03*
X1437871Y915466D03*
X1443420Y912262D03*
X1445271Y915466D03*
X1437871Y909057D03*
X1434171Y915466D03*
X1436020Y918670D03*
X1439720Y912262D03*
X1436020D03*
Y905853D03*
X1439720D03*
X1443420D03*
X1445271Y909057D03*
X1430244Y931358D03*
Y933658D03*
X1437871Y921875D03*
X1432320Y918670D03*
X1430471Y921875D03*
X1443420Y918670D03*
X1439777Y928348D03*
X1437477D03*
X1435177D03*
X1444377D03*
X1442077D03*
X1445271Y921875D03*
X1439720Y918670D03*
X1441571Y921875D03*
X1434171D03*
X1438402Y942151D03*
X1440702D03*
X1443002D03*
X1430564Y949138D03*
X1445392Y942195D03*
X1429726Y944537D03*
Y939937D03*
Y942237D03*
X1440015Y956539D03*
X1430564Y951438D03*
X1442413Y956539D03*
X1430534Y963828D03*
Y966128D03*
X1429544Y959298D03*
Y956998D03*
X1437565Y956619D03*
X1434545D03*
X1445045D03*
X1440015Y971139D03*
X1442413Y971099D03*
X1430404Y981208D03*
Y978908D03*
X1429544Y970798D03*
Y973098D03*
X1437565Y971139D03*
X1434545Y971099D03*
X1440015Y985579D03*
X1430604Y995298D03*
Y992998D03*
X1442413Y985579D03*
X1429544Y986898D03*
Y984598D03*
X1437565Y985579D03*
X1434545D03*
X1445045D03*
X1429544Y998398D03*
X1440015Y1014539D03*
Y1000059D03*
X1430584Y1009408D03*
Y1007108D03*
X1442413Y1014539D03*
Y1000059D03*
X1429544Y1012198D03*
Y1000698D03*
X1437565Y1000079D03*
X1434545D03*
X1445045D03*
X1429544Y1014498D03*
X1437436Y1014509D03*
X1434545Y1014539D03*
X1445036Y1014549D03*
X1430575Y1022185D03*
Y1019885D03*
X1439321Y1028854D03*
X1436821D03*
X1434321D03*
X1441821D03*
X1434083Y1031908D03*
X1443541Y1036914D03*
X1436453Y1041340D03*
X1442003Y1044544D03*
X1432753Y1047749D03*
X1440153D03*
X1447553Y1041340D03*
X1443853D03*
X1436453Y1047750D03*
X1443853D03*
X1430904Y1044544D03*
Y1038136D03*
X1434083Y1034408D03*
X1434813Y1037069D03*
X1439413D03*
X1437113D03*
X1432753Y1041340D03*
X1440153D03*
X1438304Y1044544D03*
X1434604D03*
X1432753Y1060565D03*
X1438303Y1057361D03*
X1432753Y1054157D03*
X1442004Y1057361D03*
X1438304Y1050952D03*
X1434604Y1063770D03*
X1442004D03*
X1438303D03*
X1442002Y1050952D03*
X1440153Y1054157D03*
X1436454D03*
X1434604Y1057361D03*
X1443854Y1054157D03*
Y1060565D03*
X1430903Y1063770D03*
X1440154Y1060565D03*
X1434603Y1050952D03*
X1436453Y1060565D03*
X1432753Y1073383D03*
X1430903Y1076587D03*
X1430904Y1070178D03*
X1443853Y1073383D03*
Y1066974D03*
X1438304Y1070178D03*
X1432754Y1079791D03*
X1443853D03*
X1436453Y1073383D03*
X1434602Y1070178D03*
X1436453Y1066974D03*
X1440153D03*
X1442002Y1070178D03*
X1447553Y1066974D03*
X1440154Y1079791D03*
X1436454D03*
X1438304Y1076587D03*
X1432753Y1066974D03*
X1442004Y1076587D03*
X1440153Y1073383D03*
X1434604Y1076587D03*
X1434603Y1082995D03*
X1432753Y1086200D03*
X1436453Y1092608D03*
X1443854Y1086200D03*
X1440153D03*
X1443854Y1092608D03*
X1438304Y1082995D03*
X1442004D03*
X1438303Y1095812D03*
X1434603D03*
X1442003Y1089403D03*
X1432754Y1092607D03*
X1430903Y1089403D03*
X1436454Y1086199D03*
X1430902Y1082995D03*
X1442003Y1095812D03*
X1440154Y1092607D03*
X1430903Y1095812D03*
X1434603Y1089403D03*
X1438303D03*
X1436454Y1105426D03*
X1434604Y1102221D03*
X1432753Y1099017D03*
X1442003Y1108630D03*
Y1102221D03*
X1440154Y1105426D03*
Y1099017D03*
X1438304Y1108630D03*
X1440154Y1111834D03*
X1443853Y1105426D03*
Y1111834D03*
X1438304Y1102221D03*
X1443853Y1099017D03*
X1430903Y1102221D03*
Y1108630D03*
X1432754Y1105426D03*
X1432753Y1111834D03*
X1434603Y1108630D03*
X1436454Y1111834D03*
Y1099016D03*
X1434604Y1121447D03*
Y1115039D03*
X1443854Y1124651D03*
X1443853Y1118243D03*
X1442004Y1121447D03*
Y1115039D03*
X1434604Y1127856D03*
X1430903Y1115039D03*
Y1121447D03*
Y1127856D03*
X1432753Y1118243D03*
Y1124651D03*
X1436454Y1118243D03*
Y1124651D03*
X1438303Y1115039D03*
Y1121447D03*
Y1127856D03*
X1440153Y1118243D03*
X1440154Y1124651D03*
X1442003Y1127856D03*
X1434604Y1134264D03*
X1443854Y1131060D03*
Y1137469D03*
X1430903Y1134264D03*
Y1140973D03*
X1432753Y1131060D03*
X1432754Y1137469D03*
X1434603Y1140973D03*
X1436454Y1131060D03*
Y1137469D03*
X1438303Y1134264D03*
Y1140973D03*
X1440154Y1131060D03*
Y1137469D03*
X1442003Y1134264D03*
Y1140973D03*
X1454521Y841467D03*
X1447121D03*
X1460071Y851380D03*
X1452671D03*
X1456371D03*
X1448971D03*
X1450820Y848176D03*
X1458220D03*
X1460071Y864197D03*
X1456371D03*
X1454521Y854584D03*
X1452671Y864197D03*
X1447121Y854584D03*
X1448971Y864197D03*
X1454521Y867401D03*
X1447121D03*
X1450820Y860993D03*
X1458220D03*
X1460071Y877014D03*
X1456371D03*
X1454521Y880219D03*
X1452671Y877014D03*
X1448971D03*
X1448970Y870606D03*
X1447121Y880219D03*
Y873810D03*
X1458220D03*
X1450820D03*
X1456370Y896240D03*
X1456371Y889832D03*
X1454521Y893036D03*
X1447121D03*
X1460071Y889832D03*
X1452671D03*
X1448971D03*
X1458220Y899445D03*
X1450820D03*
Y893036D03*
X1448971Y896240D03*
X1454520Y899445D03*
X1458220Y886627D03*
X1450820D03*
X1452671Y896240D03*
X1456371Y902649D03*
X1460071Y909057D03*
X1458221Y912262D03*
X1450820D03*
Y905853D03*
X1460070Y902649D03*
X1456371Y915466D03*
X1447122Y912262D03*
X1454521Y918670D03*
X1452671Y915466D03*
X1454522Y912262D03*
X1448971Y902649D03*
X1456370Y909057D03*
X1458220Y905853D03*
X1452671Y902649D03*
X1448970Y915466D03*
X1447120Y905853D03*
X1454520D03*
X1448971Y909057D03*
X1452671D03*
X1456371Y928283D03*
X1454522Y931488D03*
X1454520Y925079D03*
X1458220D03*
X1452426Y930125D03*
X1460071Y928283D03*
X1458220Y918670D03*
X1456371Y921875D03*
X1460070D03*
X1452670D03*
X1450820Y918670D03*
X1458220Y931488D03*
X1448971Y921875D03*
X1447120Y918670D03*
X1446677Y928348D03*
X1454520Y937896D03*
X1456371Y941100D03*
X1452426Y934725D03*
X1454520Y944304D03*
X1452321Y945354D03*
Y947654D03*
X1460070Y941100D03*
X1458221Y944304D03*
X1458220Y937896D03*
X1456371Y934691D03*
X1460070Y947509D03*
X1456371D03*
X1449992Y942195D03*
X1447692D03*
X1452426Y962325D03*
Y960025D03*
Y964625D03*
X1460070Y960326D03*
X1458220Y957122D03*
X1458221Y950713D03*
X1460071Y966735D03*
X1454520Y963530D03*
X1456371Y966735D03*
X1458220Y963529D03*
X1456370Y960326D03*
X1456371Y953917D03*
X1454520Y957122D03*
Y950713D03*
X1447545Y956619D03*
X1452426Y966925D03*
X1452333Y977669D03*
X1452476Y980736D03*
X1458221Y969939D03*
X1460070Y979552D03*
X1458220Y976347D03*
Y982756D03*
X1454521Y969939D03*
X1450045Y971099D03*
X1445445D03*
X1447745D03*
X1452426Y973825D03*
Y971525D03*
X1456371Y979552D03*
X1454520Y982756D03*
X1456371Y973143D03*
X1454520Y976347D03*
X1452426Y996825D03*
Y994525D03*
Y989925D03*
Y987625D03*
X1447545Y985579D03*
X1452436Y1010499D03*
X1452426Y1006025D03*
Y1003725D03*
Y1012925D03*
X1460503Y999684D03*
X1458654Y1009297D03*
X1458653Y1002888D03*
X1460504Y1012501D03*
X1456804Y999684D03*
X1454953Y1002888D03*
Y1009297D03*
X1456804Y1012501D03*
X1447545Y1000079D03*
X1447345Y1014539D03*
X1452416Y1022635D03*
X1452426Y1017525D03*
X1458653Y1028523D03*
Y1022114D03*
X1460503Y1018910D03*
Y1031727D03*
X1456804D03*
X1454953Y1028523D03*
Y1022114D03*
X1456803Y1018910D03*
X1454953Y1015705D03*
X1446934Y1028889D03*
X1452466Y1031794D03*
Y1029494D03*
Y1027194D03*
X1456804Y1025318D03*
X1458653Y1015705D03*
X1447424Y1036526D03*
X1449649Y1035928D03*
X1458653Y1041340D03*
X1458654Y1034931D03*
X1451253Y1041340D03*
X1460503Y1038136D03*
X1458653Y1047749D03*
X1447553D03*
X1451253D03*
X1445704Y1044544D03*
X1454953Y1034931D03*
X1456804Y1038136D03*
X1454953Y1041340D03*
X1456804Y1044544D03*
X1449404D03*
X1454953Y1047749D03*
X1453104Y1044544D03*
X1460503Y1057361D03*
X1458653Y1060565D03*
X1456804Y1050952D03*
X1451253Y1060565D03*
X1447553Y1054157D03*
X1460504Y1050952D03*
X1456804Y1063770D03*
X1458653Y1054157D03*
X1454954D03*
X1453104Y1057361D03*
Y1063770D03*
X1454954Y1060565D03*
X1456803Y1057361D03*
X1453103Y1050952D03*
X1445703Y1057361D03*
X1445704Y1063770D03*
X1447554Y1060565D03*
X1449403Y1057361D03*
X1449404Y1063770D03*
X1451254Y1054157D03*
X1445703Y1050952D03*
X1449404D03*
X1460503Y1076587D03*
X1451253Y1066974D03*
X1449404Y1070178D03*
X1460504D03*
X1458654Y1066974D03*
X1454953Y1073383D03*
X1458653Y1079791D03*
X1454954D03*
X1451253D03*
X1454953Y1066974D03*
X1445702Y1070178D03*
X1453104Y1076587D03*
X1456804D03*
Y1070178D03*
X1453104D03*
X1447553Y1073383D03*
X1449404Y1076587D03*
X1445704D03*
X1447553Y1079791D03*
X1451253Y1073383D03*
X1458653D03*
X1445703Y1089404D03*
X1458654Y1086200D03*
X1456804Y1082995D03*
X1453104Y1089404D03*
X1449404Y1082995D03*
X1460504Y1089404D03*
X1445704Y1095813D03*
X1460504D03*
X1456803D03*
X1445704Y1082995D03*
X1456804Y1089404D03*
X1449404Y1095813D03*
X1454954Y1092607D03*
X1451254D03*
X1449403Y1089403D03*
X1447554Y1086199D03*
X1453103Y1082994D03*
X1458654Y1092607D03*
X1453103Y1095812D03*
X1447554Y1092607D03*
X1451254Y1086199D03*
X1454954D03*
X1445704Y1102221D03*
X1458653Y1105426D03*
X1456804Y1108630D03*
X1454953Y1099017D03*
X1449404Y1108630D03*
X1453104Y1102221D03*
X1451254Y1099017D03*
X1447553D03*
X1458653Y1111834D03*
X1460504Y1108630D03*
X1451253Y1111834D03*
X1447553D03*
X1454953Y1105426D03*
X1445704Y1108630D03*
X1449404Y1102221D03*
X1458653Y1099017D03*
X1454953Y1111834D03*
X1453104Y1108630D03*
X1447553Y1105426D03*
X1451253D03*
X1460504Y1102221D03*
X1456804D03*
X1445703Y1115039D03*
X1458653Y1118243D03*
X1456803Y1115039D03*
X1454953Y1118243D03*
X1453103Y1115039D03*
X1451253Y1118243D03*
X1447553D03*
X1445704Y1127856D03*
X1460503D03*
X1453103D03*
X1460504Y1115039D03*
X1449404D03*
X1456804Y1121447D03*
X1449404D03*
X1445703Y1140973D03*
X1458653Y1131060D03*
X1454953D03*
X1453103Y1140973D03*
X1451253Y1131060D03*
X1447554Y1137469D03*
Y1131060D03*
X1449403Y1134264D03*
X1460503Y1140973D03*
X1456804Y1134264D03*
X1445703D03*
X1461517Y1575686D03*
Y1580678D03*
Y1587598D03*
Y1592590D03*
X1469321Y841467D03*
X1461921D03*
X1476721D03*
X1474871Y851380D03*
X1471171D03*
X1467471D03*
X1463771D03*
X1465620Y848176D03*
X1473020D03*
X1461921Y854584D03*
X1474871Y864197D03*
X1471171D03*
X1469321Y854584D03*
X1467471Y864197D03*
X1463771D03*
X1476721Y854584D03*
X1461921Y867401D03*
X1476721D03*
X1469321D03*
X1465620Y860993D03*
X1473020D03*
X1461921Y880219D03*
X1471171Y877014D03*
X1476721Y880219D03*
X1474871Y877014D03*
X1469321Y880219D03*
X1467471Y877014D03*
X1463771D03*
X1473020Y873810D03*
X1465620D03*
X1474871Y889832D03*
X1465621Y893036D03*
X1476721D03*
X1474871Y896240D03*
X1471171Y889832D03*
X1467471D03*
X1463771D03*
X1473021Y899445D03*
X1465620D03*
X1473020Y886627D03*
X1465620D03*
X1461920Y905853D03*
X1473020Y912262D03*
X1471171Y909057D03*
X1465620Y912262D03*
Y905853D03*
X1471171Y902649D03*
X1469321Y905853D03*
X1474870Y915466D03*
X1461920Y925079D03*
X1471170Y928283D03*
X1469321Y925079D03*
X1465620D03*
Y918670D03*
X1473021D03*
X1471171Y921875D03*
X1473020Y931488D03*
X1465620D03*
X1461920Y944304D03*
X1474871Y934691D03*
X1473021Y937896D03*
X1471171Y941100D03*
X1469321Y944304D03*
X1465620D03*
Y937896D03*
X1471170Y947509D03*
X1474871Y953917D03*
X1473021Y957122D03*
X1471171Y960326D03*
X1465620Y957122D03*
Y950713D03*
X1473020D03*
X1461920Y963530D03*
X1476721D03*
X1471170Y966735D03*
X1469321Y963530D03*
X1465620D03*
X1473021Y976347D03*
X1473020Y969939D03*
X1465620Y976347D03*
Y969939D03*
X1474870Y973143D03*
X1471171Y979552D03*
X1461920Y982756D03*
X1469321D03*
X1465620D03*
X1475303Y1006093D03*
X1473453Y1009297D03*
X1473454Y1002888D03*
X1471604Y999684D03*
X1466053Y1009297D03*
X1466054Y1002888D03*
X1467903Y1006093D03*
X1464204D03*
X1471603Y1012501D03*
X1462353Y1015705D03*
X1473453Y1028523D03*
X1466053D03*
Y1022114D03*
Y1015705D03*
X1477154D03*
X1475303Y1025318D03*
X1473453Y1022114D03*
X1471604Y1018910D03*
X1469754Y1015705D03*
X1471603Y1031727D03*
X1462353Y1034931D03*
X1473454Y1041340D03*
X1466053D03*
Y1034931D03*
X1475303Y1044544D03*
X1471604Y1038136D03*
X1469754Y1034931D03*
X1466053Y1047749D03*
X1473453D03*
X1462353Y1054157D03*
X1473453Y1060565D03*
X1471604Y1057361D03*
X1466053Y1060565D03*
Y1054157D03*
X1471603Y1050952D03*
X1469753Y1054157D03*
X1475304Y1063770D03*
X1462353Y1073383D03*
X1471604Y1076587D03*
X1469754Y1073383D03*
X1466053Y1066974D03*
X1473453D03*
X1471603Y1070178D03*
X1466053Y1073383D03*
X1473454Y1079791D03*
X1466053D03*
X1462353Y1092608D03*
X1475303Y1082995D03*
X1473453Y1086200D03*
X1469754Y1092608D03*
X1466053D03*
Y1086200D03*
X1471603Y1089404D03*
X1475304Y1095813D03*
X1471604D03*
X1467904D03*
X1464204D03*
X1462353Y1105426D03*
X1462354Y1099017D03*
X1475303Y1108630D03*
Y1102221D03*
X1473454Y1105426D03*
X1469753D03*
X1467904Y1102221D03*
X1464203D03*
X1473454Y1111834D03*
X1466053D03*
Y1099017D03*
X1471604Y1102221D03*
X1477153Y1099017D03*
X1469753D03*
X1473453D03*
X1471604Y1108630D03*
X1466053Y1105426D03*
X1462353Y1111834D03*
X1469753D03*
X1467904Y1108630D03*
X1464204D03*
X1477154Y1105426D03*
Y1111833D03*
X1462353Y1118243D03*
X1477153D03*
X1475303Y1115039D03*
X1473453Y1118243D03*
X1471604Y1121447D03*
X1469754Y1118243D03*
X1466053D03*
X1475303Y1127856D03*
X1467903D03*
X1467904Y1115039D03*
X1471604D03*
X1464204D03*
Y1121447D03*
X1462353Y1131060D03*
X1477153D03*
X1475303Y1140973D03*
X1473453Y1131060D03*
X1469753D03*
X1466053D03*
X1467903Y1140973D03*
X1471604Y1134264D03*
X1464204D03*
X1473577Y1580678D03*
Y1575686D03*
X1466473D03*
Y1580678D03*
X1471773Y1599884D03*
X1466817D03*
X1473577Y1592590D03*
Y1587598D03*
X1466473D03*
Y1592590D03*
X1466817Y1611796D03*
X1471773D03*
X1466817Y1604876D03*
X1471773D03*
Y1616788D03*
X1466817D03*
X1491521Y841467D03*
X1484121D03*
X1478571Y851380D03*
X1482271D03*
X1489671D03*
X1485971D03*
X1493371D03*
X1487820Y848176D03*
X1480420D03*
X1478571Y864197D03*
X1491521Y854584D03*
X1489671Y864197D03*
X1485971D03*
X1482271D03*
X1493371D03*
X1491521Y867401D03*
X1484121D03*
Y854584D03*
X1487820Y860993D03*
X1480420D03*
X1478571Y877014D03*
X1491521Y880219D03*
X1485971Y877014D03*
X1484121Y880219D03*
X1489671Y877014D03*
X1482271D03*
X1493371D03*
X1487820Y873810D03*
X1480420D03*
X1478570Y896240D03*
X1478571Y889832D03*
X1491521Y893036D03*
X1482271Y889832D03*
X1489671D03*
X1485971D03*
X1482270Y896240D03*
X1480421Y893036D03*
X1493371Y889832D03*
X1491520Y899445D03*
X1484120D03*
X1480420Y886627D03*
X1487820D03*
X1478571Y909057D03*
Y902649D03*
X1491520Y912262D03*
X1487820Y905853D03*
X1485971Y909057D03*
X1484121Y912262D03*
X1491520Y905853D03*
X1485970Y902649D03*
X1478571Y915466D03*
X1482271D03*
X1478571Y928283D03*
Y921875D03*
X1491520Y925079D03*
Y918670D03*
X1487820Y925079D03*
X1485971Y928283D03*
X1485970Y921875D03*
X1484120Y918670D03*
X1491520Y931488D03*
X1484121D03*
X1478571Y941100D03*
Y934691D03*
X1491520Y944304D03*
Y937896D03*
X1487820Y944304D03*
X1485970Y941100D03*
X1484120Y937896D03*
X1482271Y934691D03*
X1478571Y947509D03*
X1485971D03*
X1478571Y960326D03*
Y953917D03*
X1491520Y957122D03*
Y950713D03*
X1485970Y960326D03*
X1484120Y957122D03*
X1482271Y953917D03*
X1484121Y950713D03*
X1478570Y966735D03*
X1491520Y963530D03*
X1485971Y966735D03*
X1487820Y963530D03*
X1480420D03*
X1478571Y979552D03*
Y973143D03*
X1491521Y976347D03*
X1491520Y969939D03*
X1484120Y976347D03*
X1484121Y969939D03*
X1489671Y973143D03*
X1485970Y979552D03*
X1482271Y973143D03*
X1493370D03*
X1491520Y982756D03*
X1487820D03*
X1479004Y999684D03*
X1486403D03*
X1484553Y1002888D03*
X1482704Y1006093D03*
X1479003Y1012501D03*
X1486404D03*
X1491953Y1009297D03*
Y1002888D03*
X1484554Y1009297D03*
X1479004Y1025318D03*
Y1018910D03*
X1491953Y1028523D03*
Y1022114D03*
X1484553Y1028523D03*
X1486403Y1018910D03*
X1484553Y1022114D03*
X1482704Y1025318D03*
X1480853Y1015705D03*
X1479004Y1031727D03*
X1486404D03*
X1488253Y1015705D03*
X1491953D03*
X1479004Y1044544D03*
Y1038136D03*
X1491953Y1034931D03*
Y1041340D03*
X1488253Y1034931D03*
X1486403Y1038136D03*
X1484553Y1041340D03*
X1482704Y1044544D03*
X1491953Y1047749D03*
X1484553D03*
X1479004Y1057361D03*
Y1050952D03*
X1491953Y1054157D03*
X1486404Y1057361D03*
X1484553Y1060565D03*
X1488253Y1054157D03*
X1486404Y1050952D03*
X1491953Y1060565D03*
X1479004Y1063770D03*
X1482704D03*
X1479004Y1076587D03*
Y1070178D03*
X1486404Y1076587D03*
Y1070178D03*
X1488253Y1073383D03*
X1484553Y1066974D03*
X1491953Y1073383D03*
Y1066974D03*
X1484553Y1079791D03*
X1491953D03*
X1479004Y1089404D03*
Y1082995D03*
X1488254Y1092608D03*
X1486404Y1089404D03*
X1484554Y1086200D03*
X1482704Y1082995D03*
X1491954Y1092608D03*
X1491953Y1086200D03*
X1479004Y1095813D03*
X1490103D03*
X1493804D03*
X1479004Y1102221D03*
X1490104Y1108630D03*
Y1102221D03*
X1488254Y1099017D03*
X1484553D03*
X1482704Y1108630D03*
X1480853Y1099017D03*
X1491953Y1105426D03*
Y1111834D03*
X1493804Y1108630D03*
X1486404Y1102221D03*
X1479003Y1108629D03*
X1488254Y1105426D03*
X1484554Y1111833D03*
X1482703Y1102220D03*
X1480854Y1111833D03*
Y1105426D03*
X1486403Y1108630D03*
X1488254Y1111833D03*
X1484554Y1105426D03*
X1490103Y1115039D03*
X1488253Y1118243D03*
X1484553D03*
X1480853D03*
X1486403Y1115039D03*
X1491953Y1118243D03*
X1490103Y1127856D03*
X1482703D03*
X1493804Y1115039D03*
X1479004D03*
Y1121447D03*
X1493804D03*
X1486404D03*
X1482703Y1115038D03*
X1490103Y1140973D03*
X1488253Y1131060D03*
X1484553D03*
X1480853D03*
X1482703Y1140973D03*
X1491953Y1131060D03*
X1479004Y1134264D03*
X1493804D03*
X1486404D03*
X1490593Y1580678D03*
Y1575686D03*
X1485637D03*
Y1580678D03*
X1478533D03*
Y1575686D03*
X1490937Y1599884D03*
X1478877D03*
X1483833D03*
X1490593Y1587598D03*
X1485637D03*
Y1592590D03*
X1490593D03*
X1478533D03*
Y1587598D03*
X1490937Y1604876D03*
Y1611796D03*
Y1616788D03*
X1483833D03*
X1478877D03*
Y1611796D03*
X1483833D03*
X1478877Y1604876D03*
X1483833D03*
X1504471Y844671D03*
X1498921Y841467D03*
X1508171Y851380D03*
X1504471D03*
X1500771D03*
X1497071D03*
X1495220Y848176D03*
X1504471Y864197D03*
X1500771D03*
X1508170Y857789D03*
X1497071Y864197D03*
X1506321Y860993D03*
Y854584D03*
X1498921D03*
X1510021Y860993D03*
X1506320Y867401D03*
X1498921D03*
X1510021D03*
X1495220Y860993D03*
X1502621D03*
X1504471Y877014D03*
X1498921Y880219D03*
X1508171Y877014D03*
X1497071D03*
X1506321Y880219D03*
X1500771Y877014D03*
X1510021Y880219D03*
Y873810D03*
X1508170Y883423D03*
X1495220Y873810D03*
X1502621D03*
X1508171Y889832D03*
X1504471Y896240D03*
Y889832D03*
X1500771D03*
X1508171Y896240D03*
X1502621Y893036D03*
X1500771Y896240D03*
X1497071Y889832D03*
X1510021Y893036D03*
X1498921Y899445D03*
X1510021D03*
X1506320Y893036D03*
X1495220Y886627D03*
X1502621D03*
X1510021D03*
X1495221Y905853D03*
X1504471Y902649D03*
X1498920Y912262D03*
X1497070Y909057D03*
X1497071Y902649D03*
X1508171Y915466D03*
X1504471D03*
X1500770D03*
X1504471Y909057D03*
X1510021Y912262D03*
X1495221Y925079D03*
X1504471Y921875D03*
X1497070Y928283D03*
X1498921Y918670D03*
X1497071Y921875D03*
X1498920Y931488D03*
X1504471Y928283D03*
X1510021Y918670D03*
X1510020Y931488D03*
X1495221Y944304D03*
X1504471Y941100D03*
Y934691D03*
X1500770D03*
X1498921Y937896D03*
X1497071Y941100D03*
X1497070Y947509D03*
X1508171Y934691D03*
X1510021Y937896D03*
X1504471Y947509D03*
Y960326D03*
Y953917D03*
X1500771D03*
X1498921Y957122D03*
X1497071Y960326D03*
X1498920Y950713D03*
X1495221Y963530D03*
X1497070Y966735D03*
X1502621Y963530D03*
X1510021Y957122D03*
X1508171Y953917D03*
X1510021Y950713D03*
X1506320Y963530D03*
X1504471Y966735D03*
Y979552D03*
Y973143D03*
X1498921Y976347D03*
X1498920Y969939D03*
X1500770Y973143D03*
X1497071Y979552D03*
X1510021Y976347D03*
X1495221Y982756D03*
X1510043Y980606D03*
X1510021Y969939D03*
X1508171Y973143D03*
X1497503Y1012501D03*
Y999684D03*
X1504904Y1006093D03*
Y999684D03*
X1501203Y1006093D03*
X1499353Y1009297D03*
X1499354Y1002888D03*
X1510453Y1009297D03*
Y1002888D03*
X1508603Y1006093D03*
X1504903Y1012501D03*
X1504904Y1025318D03*
X1499353Y1028523D03*
X1501203Y1025318D03*
X1504904Y1031727D03*
X1497503D03*
X1495654Y1015705D03*
X1497504Y1018910D03*
X1499353Y1022114D03*
X1503054Y1015705D03*
X1504904Y1018910D03*
X1506753Y1015705D03*
X1510453Y1028523D03*
X1510452Y1022114D03*
X1508603Y1025318D03*
X1504904Y1044544D03*
X1501203D03*
X1499354Y1041340D03*
X1497504Y1038136D03*
X1495654Y1034931D03*
X1508604Y1044544D03*
X1499353Y1047749D03*
X1504904Y1038136D03*
X1510453Y1041340D03*
Y1047749D03*
X1504904Y1057361D03*
Y1050952D03*
X1499354Y1060565D03*
X1497504Y1057361D03*
X1497503Y1050952D03*
X1495654Y1054157D03*
X1504904Y1063770D03*
X1501203D03*
X1510453Y1060565D03*
X1508604Y1063770D03*
X1504904Y1076587D03*
Y1070178D03*
X1497504Y1076587D03*
X1497503Y1070178D03*
X1495654Y1073383D03*
X1499353Y1066974D03*
X1499354Y1079791D03*
X1510453Y1066974D03*
Y1079791D03*
X1499353Y1086200D03*
X1497503Y1089404D03*
X1495653Y1092608D03*
X1504904Y1089404D03*
Y1082995D03*
X1501203D03*
X1508604Y1082996D03*
X1510453Y1086200D03*
X1504903Y1095813D03*
X1503053Y1105426D03*
X1497503Y1102221D03*
X1495653Y1105426D03*
X1495654Y1099017D03*
X1508603Y1108630D03*
X1506754Y1111834D03*
X1499353D03*
X1503053Y1099017D03*
X1510453D03*
X1508602Y1102221D03*
X1497504Y1108630D03*
X1501204D03*
X1510453Y1111834D03*
X1499353Y1105426D03*
X1510453D03*
X1504904Y1108630D03*
X1495653Y1111834D03*
X1503053D03*
X1506753Y1105426D03*
X1504904Y1102221D03*
X1501204D03*
X1499354Y1099017D03*
X1506753Y1124651D03*
Y1118243D03*
X1504904Y1121447D03*
X1499353Y1118243D03*
X1497503Y1115039D03*
X1495653Y1118243D03*
X1508603Y1115039D03*
X1504904Y1127856D03*
X1497503D03*
X1501204Y1115039D03*
X1504904D03*
X1503053Y1118243D03*
X1510453D03*
X1501204Y1121447D03*
X1508603Y1121446D03*
X1510453Y1124650D03*
X1508603Y1127855D03*
X1506754Y1137469D03*
X1506753Y1131060D03*
X1503053D03*
X1499353D03*
X1495653D03*
X1504904Y1134264D03*
X1497503Y1140973D03*
X1510453Y1131060D03*
X1501204Y1134264D03*
X1508603Y1140973D03*
X1504903D03*
X1509757Y1575686D03*
Y1580678D03*
X1502653D03*
X1497697D03*
X1502653Y1575686D03*
X1497697D03*
X1502997Y1599884D03*
X1507953D03*
X1495893D03*
X1509757Y1587598D03*
Y1592590D03*
X1502653D03*
X1497697D03*
X1502653Y1587598D03*
X1497697D03*
X1502997Y1616788D03*
X1507953D03*
X1502997Y1604876D03*
Y1611796D03*
X1507953Y1604876D03*
Y1611796D03*
X1495893Y1604876D03*
Y1611796D03*
Y1616788D03*
X1505315Y1675383D03*
Y1679920D03*
Y1684454D03*
Y1689556D03*
Y1694093D03*
Y1698627D03*
Y1703729D03*
Y1708266D03*
Y1712800D03*
Y1726974D03*
Y1722440D03*
Y1717903D03*
X1511871Y844671D03*
X1513722Y848176D03*
X1511871Y851380D03*
X1521121Y860993D03*
Y854584D03*
X1515570Y864197D03*
X1513721Y854584D03*
Y860993D03*
X1521121Y867401D03*
X1517421D03*
X1513721D03*
X1511871Y870606D03*
X1522971D03*
X1517421Y873810D03*
X1511871Y883423D03*
X1517421Y880219D03*
X1522971Y883423D03*
X1511871Y889832D03*
X1517421Y886627D03*
X1521121D03*
X1513721D03*
X1526671Y889832D03*
X1524821Y912262D03*
X1511871Y909057D03*
Y902649D03*
X1524821Y905853D03*
X1513721D03*
X1511871Y928283D03*
Y921875D03*
X1524820Y925079D03*
X1513720D03*
X1524820Y931488D03*
X1511871Y941100D03*
X1524820Y944304D03*
X1513720D03*
X1511871Y947509D03*
X1525420Y949619D03*
X1525861Y962436D03*
X1511871Y960326D03*
Y966735D03*
X1524288Y965640D03*
X1513721Y963530D03*
Y982756D03*
X1517421Y969939D03*
X1515571Y973143D03*
X1519871Y984866D03*
X1512303Y999684D03*
X1525396Y1000648D03*
X1512303Y1012501D03*
X1517854Y1015705D03*
X1525254D03*
X1521554D03*
X1514154D03*
X1512303Y1018910D03*
Y1031727D03*
X1525254Y1034931D03*
X1521554D03*
X1517853D03*
X1514153D03*
X1512303Y1038136D03*
X1517853Y1054157D03*
X1514153D03*
X1512303Y1057361D03*
X1521553Y1054157D03*
X1512303Y1050952D03*
X1525564Y1064850D03*
X1523404Y1070178D03*
X1521553Y1066974D03*
X1512303Y1076587D03*
X1512304Y1070178D03*
X1514153Y1073383D03*
X1523404Y1082996D03*
X1514153Y1092608D03*
X1512303Y1089404D03*
X1521553Y1092608D03*
X1523403Y1095813D03*
X1519703D03*
X1512303D03*
X1521554Y1105426D03*
X1517853D03*
X1516003Y1108630D03*
Y1102221D03*
X1512303D03*
X1517853Y1111834D03*
X1521553D03*
X1514153Y1105426D03*
X1512303Y1108630D03*
X1514153Y1111834D03*
X1519703Y1108630D03*
X1521553Y1124651D03*
Y1118243D03*
X1519704Y1115039D03*
X1516004D03*
X1514153Y1124651D03*
X1512303Y1115039D03*
X1517853Y1118243D03*
X1519703Y1121446D03*
X1516003Y1127855D03*
X1512303D03*
Y1121446D03*
X1516003D03*
X1517853Y1124650D03*
X1519703Y1127855D03*
X1517854Y1131560D03*
X1512304Y1134264D03*
X1514154Y1131059D03*
X1521817Y1580678D03*
Y1575686D03*
X1514713D03*
Y1580678D03*
X1520013Y1599884D03*
X1515057D03*
X1521817Y1592590D03*
Y1587598D03*
X1514713D03*
Y1592590D03*
X1520013Y1604876D03*
X1515057D03*
X1520013Y1611796D03*
X1515057D03*
Y1616788D03*
X1520013D03*
X1521063Y1675383D03*
Y1679920D03*
X1513189Y1679320D03*
X1521063Y1684454D03*
Y1689556D03*
Y1694093D03*
Y1698627D03*
X1513189Y1688391D03*
Y1693493D03*
Y1698030D03*
Y1683857D03*
X1521063Y1703729D03*
Y1708266D03*
Y1712800D03*
X1513189Y1707666D03*
Y1712203D03*
Y1702564D03*
X1521063Y1726974D03*
Y1722440D03*
Y1717903D03*
X1513189Y1730911D03*
Y1726377D03*
Y1721840D03*
Y1716737D03*
X1527571Y979057D03*
X1526843Y972608D03*
X1527103Y1031726D03*
X1533877Y1575592D03*
X1538833D03*
X1533877Y1580678D03*
X1538833D03*
X1526773D03*
Y1575686D03*
X1539177Y1599790D03*
X1527117Y1599884D03*
X1532073D03*
X1533877Y1587598D03*
X1538833D03*
X1533877Y1592590D03*
X1538833D03*
X1526773D03*
Y1587598D03*
X1539177Y1611796D03*
Y1604876D03*
Y1616788D03*
X1527117D03*
Y1604876D03*
Y1611796D03*
X1532073Y1616788D03*
Y1604876D03*
Y1611796D03*
X1536811Y1675383D03*
Y1679920D03*
X1528937Y1679320D03*
X1536811Y1684454D03*
Y1689556D03*
Y1694093D03*
Y1698627D03*
X1528937Y1688391D03*
Y1693493D03*
Y1698030D03*
Y1683857D03*
X1536811Y1703729D03*
Y1708266D03*
Y1712800D03*
X1528937Y1707666D03*
Y1712203D03*
Y1702564D03*
X1536811Y1726974D03*
Y1722440D03*
Y1717903D03*
X1528937Y1730911D03*
Y1726377D03*
Y1721840D03*
Y1716737D03*
X1557997Y1575686D03*
Y1580678D03*
X1550893D03*
X1545937D03*
X1550893Y1575686D03*
X1545937D03*
X1556193Y1599884D03*
X1551237D03*
X1544133Y1599790D03*
X1557997Y1587598D03*
Y1592590D03*
X1545937D03*
X1550893D03*
Y1587598D03*
X1545937D03*
X1551237Y1616788D03*
X1556193D03*
Y1604876D03*
X1551237D03*
X1556193Y1611796D03*
X1551237D03*
X1544133Y1604876D03*
Y1611796D03*
Y1616788D03*
X1552559Y1675383D03*
Y1679920D03*
X1544685Y1679320D03*
X1552559Y1684454D03*
Y1689556D03*
Y1694093D03*
Y1698627D03*
X1544685Y1688391D03*
Y1693493D03*
Y1698030D03*
Y1683857D03*
X1552559Y1703729D03*
Y1708266D03*
Y1712800D03*
X1544685Y1707666D03*
Y1712203D03*
Y1702564D03*
X1552559Y1726974D03*
Y1722440D03*
Y1717903D03*
X1544685Y1730911D03*
Y1726377D03*
Y1721840D03*
Y1716737D03*
X1570057Y1580678D03*
X1575013D03*
X1570057Y1575686D03*
X1575013D03*
X1562953D03*
Y1580678D03*
X1575357Y1599884D03*
X1563297D03*
X1568253D03*
X1570057Y1592590D03*
X1575013D03*
X1570057Y1587598D03*
X1575013D03*
X1562953D03*
Y1592590D03*
X1575357Y1616788D03*
Y1604876D03*
Y1611796D03*
X1563297Y1604876D03*
Y1611796D03*
X1568253Y1604876D03*
Y1611796D03*
X1563297Y1616788D03*
X1568253D03*
X1560433Y1679320D03*
X1572244Y1675383D03*
Y1679920D03*
X1560433Y1688391D03*
Y1693493D03*
Y1698030D03*
Y1683857D03*
X1572244Y1684454D03*
Y1689556D03*
Y1694093D03*
Y1698627D03*
X1560433Y1707666D03*
Y1712203D03*
Y1702564D03*
X1572244Y1703729D03*
Y1708266D03*
Y1712800D03*
X1560433Y1730911D03*
Y1726377D03*
Y1721840D03*
Y1716737D03*
X1572244Y1726974D03*
Y1722440D03*
Y1717903D03*
X1582117Y1575686D03*
X1587073D03*
X1582117Y1580678D03*
X1587073D03*
X1587417Y1599884D03*
X1580313D03*
X1582117Y1587598D03*
X1587073D03*
X1582117Y1592590D03*
X1587073D03*
X1587417Y1604876D03*
Y1611796D03*
Y1616788D03*
X1580313D03*
Y1604876D03*
Y1611796D03*
X1587992Y1675383D03*
Y1679920D03*
X1580118Y1679320D03*
X1587992Y1684454D03*
Y1689556D03*
Y1694093D03*
Y1698627D03*
X1580118Y1688391D03*
Y1693493D03*
Y1698030D03*
Y1683857D03*
X1587992Y1703729D03*
Y1708266D03*
Y1712800D03*
X1580118Y1707666D03*
Y1712203D03*
Y1702564D03*
X1587992Y1726974D03*
Y1722440D03*
Y1717903D03*
X1580118Y1730911D03*
Y1726377D03*
Y1721840D03*
Y1716737D03*
X1597041Y770144D03*
X1605741D03*
X1605800Y766478D03*
X1605741Y776837D03*
X1597041D03*
X1605741Y783530D03*
X1597041D03*
X1605741Y793570D03*
X1597041D03*
X1596988Y800263D03*
X1605741D03*
X1595774Y806955D03*
X1606934D03*
X1596218Y813648D03*
X1606735D03*
X1597041Y820341D03*
X1605741D03*
X1597041Y830381D03*
X1605741D03*
Y837074D03*
X1597041D03*
Y843766D03*
X1605741D03*
X1596147Y850459D03*
X1606896D03*
X1596200Y857152D03*
X1606623D03*
X1597041Y867192D03*
X1605741D03*
X1597041Y873885D03*
X1605741D03*
X1597041Y880577D03*
X1605741D03*
X1597041Y887270D03*
X1605741D03*
X1606898Y893963D03*
X1597041D03*
X1605741Y904003D03*
X1597041D03*
Y917389D03*
X1605741D03*
X1597041Y910696D03*
X1605741D03*
X1597041Y924081D03*
X1605741D03*
X1606541Y930697D03*
X1596047Y930774D03*
X1596106Y940814D03*
X1606919D03*
X1605741Y947507D03*
X1597041D03*
X1605741Y954200D03*
X1597041D03*
Y964239D03*
X1605741D03*
X1597041Y977625D03*
X1605741D03*
Y970932D03*
X1597041D03*
Y984318D03*
X1605741D03*
X1597041Y991011D03*
X1605741D03*
X1601922Y1000198D03*
X1599489Y999665D03*
X1597041Y1024475D03*
X1605741D03*
X1597041Y1017782D03*
X1605741D03*
X1597041Y1031168D03*
X1605741D03*
X1597041Y1037861D03*
X1605741D03*
X1597041Y1044554D03*
X1605741D03*
Y1051247D03*
X1597041D03*
Y1057940D03*
X1605741D03*
X1597041Y1061286D03*
Y1064633D03*
X1605741D03*
X1606541Y1071326D03*
X1596141D03*
X1597041Y1078018D03*
X1605741D03*
Y1094751D03*
X1597041D03*
Y1088058D03*
X1605741D03*
Y1101444D03*
X1597041D03*
Y1108137D03*
X1605741D03*
X1606541Y1114829D03*
X1596241D03*
X1596511Y1124969D03*
X1606505Y1124674D03*
X1605741Y1138255D03*
X1597041D03*
X1605741Y1144948D03*
X1597041D03*
Y1131562D03*
X1605741D03*
Y1151641D03*
X1597041D03*
X1596653Y1161680D03*
X1605975Y1161581D03*
X1605741Y1168373D03*
X1597041D03*
X1605741Y1175066D03*
X1597041D03*
X1605741Y1181759D03*
X1597041D03*
X1606765Y1188452D03*
X1597041D03*
Y1198491D03*
X1605741D03*
Y1205184D03*
X1597041D03*
Y1211877D03*
X1605741D03*
X1597041Y1218570D03*
X1605741D03*
X1597041Y1225263D03*
X1605741D03*
X1607064Y1235302D03*
X1596178D03*
X1605741Y1241995D03*
X1597041D03*
Y1248688D03*
X1605741D03*
X1606481Y1258649D03*
X1603788Y1273144D03*
X1601388D03*
X1607897Y1264445D03*
X1606237Y1575686D03*
Y1580678D03*
X1594177D03*
X1599133D03*
X1594177Y1575686D03*
X1599133D03*
X1599477Y1599884D03*
X1604433D03*
X1592373D03*
X1606237Y1587598D03*
Y1592590D03*
X1594177D03*
X1599133D03*
X1594177Y1587598D03*
X1599133D03*
X1599477Y1616788D03*
X1604433D03*
X1599477Y1604876D03*
Y1611796D03*
X1604433Y1604876D03*
Y1611796D03*
X1592373Y1604876D03*
Y1611796D03*
Y1616788D03*
X1603740Y1675383D03*
Y1679920D03*
X1595866Y1679320D03*
X1603740Y1684454D03*
Y1689556D03*
Y1694093D03*
Y1698627D03*
X1595866Y1688391D03*
Y1693493D03*
Y1698030D03*
Y1683857D03*
X1603740Y1703729D03*
Y1708266D03*
Y1712800D03*
X1595866Y1707666D03*
Y1712203D03*
Y1702564D03*
X1603740Y1726974D03*
Y1722440D03*
Y1717903D03*
X1595866Y1730911D03*
Y1726377D03*
Y1721840D03*
Y1716737D03*
X1613183Y766798D03*
X1621883D03*
Y773491D03*
X1613183D03*
X1621883Y780184D03*
X1613183D03*
X1621883Y790223D03*
X1613183D03*
Y796916D03*
X1621883D03*
X1613183Y803609D03*
X1621883D03*
X1622916Y816995D03*
X1613183D03*
X1612363Y810302D03*
X1622986D03*
X1613183Y827034D03*
X1621883D03*
Y833727D03*
X1613183D03*
Y840420D03*
X1621883D03*
X1613183Y847113D03*
X1621943D03*
X1622060Y863845D03*
X1612408D03*
X1612474Y853955D03*
X1622961Y853806D03*
X1621883Y883924D03*
X1613183D03*
Y870538D03*
X1621883D03*
X1613183Y877231D03*
X1621883D03*
X1613183Y890617D03*
X1621883D03*
X1613183Y900656D03*
X1621883D03*
Y907349D03*
X1613183D03*
Y914042D03*
X1621883D03*
Y920735D03*
X1613183D03*
X1622535Y927526D03*
X1612168Y927428D03*
X1622845Y937467D03*
X1612312D03*
X1621883Y944160D03*
X1613183D03*
X1621883Y950853D03*
X1613183D03*
X1621883Y960892D03*
X1613183D03*
X1613083Y957546D03*
Y954200D03*
X1613183Y974278D03*
X1621883D03*
X1613183Y980971D03*
X1621883D03*
X1613183Y967585D03*
X1621883D03*
X1613183Y987664D03*
X1621883D03*
X1616609Y1000735D03*
X1616469Y1003135D03*
X1623539Y1000135D03*
X1620489Y1003135D03*
X1623589Y1002865D03*
X1620399Y1000325D03*
X1621883Y1017782D03*
X1613183D03*
Y1027822D03*
X1621883D03*
X1613183Y1034515D03*
X1621883D03*
X1613183Y1041207D03*
X1621883D03*
X1613183Y1047900D03*
X1621883D03*
Y1054593D03*
X1613183D03*
Y1061286D03*
X1621883D03*
Y1067979D03*
X1612983D03*
X1612283Y1074672D03*
X1622683D03*
X1621883Y1084711D03*
X1612383D03*
X1613183Y1091404D03*
X1621883D03*
Y1104790D03*
X1613183D03*
X1621883Y1098097D03*
X1613183D03*
X1621883Y1111483D03*
X1613183D03*
Y1128915D03*
X1621883Y1128215D03*
X1613183Y1121522D03*
X1621883D03*
Y1141601D03*
X1613183D03*
X1622726Y1135108D03*
X1611886Y1134908D03*
X1621883Y1158333D03*
X1613183D03*
X1621883Y1148294D03*
X1613183D03*
X1621883Y1165026D03*
X1613183D03*
Y1171719D03*
X1621883D03*
Y1178412D03*
X1613183D03*
X1621883Y1185105D03*
X1613183D03*
Y1195144D03*
X1621883D03*
Y1201837D03*
X1613183D03*
X1621883Y1208530D03*
X1613183D03*
X1621883Y1215223D03*
X1613183D03*
X1612147Y1221916D03*
X1622712D03*
X1612137Y1231862D03*
X1622681Y1231955D03*
X1621883Y1238648D03*
X1613183D03*
X1610150Y1257172D03*
X1621883Y1245341D03*
X1613183D03*
X1611475Y1259227D03*
X1621983Y1258727D03*
X1613183Y1252034D03*
X1613027Y1248805D03*
X1609056Y1250602D03*
X1618888Y1273344D03*
X1616088D03*
X1613019Y1261235D03*
X1618297Y1580678D03*
X1623253D03*
X1618297Y1575686D03*
X1623253D03*
X1611193D03*
Y1580678D03*
X1623597Y1599884D03*
X1611537D03*
X1616493D03*
X1618297Y1592590D03*
X1623253D03*
X1618297Y1587598D03*
X1623253D03*
X1611193D03*
Y1592590D03*
X1623597Y1616788D03*
Y1604876D03*
Y1611796D03*
X1611537Y1604876D03*
Y1611796D03*
X1616493Y1604876D03*
Y1611796D03*
X1611537Y1616788D03*
X1616493D03*
X1619488Y1675383D03*
Y1679920D03*
X1611614Y1679320D03*
X1619488Y1684454D03*
Y1689556D03*
Y1694093D03*
Y1698627D03*
X1611614Y1688391D03*
Y1693493D03*
Y1698030D03*
Y1683857D03*
X1619488Y1703729D03*
Y1708266D03*
Y1712800D03*
X1611614Y1707666D03*
Y1712203D03*
Y1702564D03*
X1619488Y1726974D03*
Y1722440D03*
Y1717903D03*
X1611614Y1730911D03*
Y1726377D03*
Y1721840D03*
Y1716737D03*
X1626741Y770144D03*
X1635441D03*
X1626741Y766798D03*
Y776837D03*
X1635441D03*
X1626741Y783530D03*
X1635441D03*
X1626741Y793570D03*
X1635441D03*
Y800263D03*
X1626741D03*
X1636341Y820341D03*
X1626741D03*
X1636574Y813648D03*
X1626741D03*
X1635441Y806955D03*
X1626741D03*
X1635441Y830381D03*
X1626741D03*
X1635441Y837074D03*
X1626741D03*
Y843766D03*
X1635441D03*
Y850459D03*
X1626741D03*
X1625705Y867192D03*
X1636441D03*
X1635441Y857152D03*
X1626741D03*
Y880577D03*
X1635441D03*
Y873885D03*
X1626741D03*
Y887270D03*
X1635441D03*
X1626741Y893963D03*
X1635441D03*
X1626741Y904003D03*
X1635441D03*
Y910696D03*
X1626741D03*
X1635441Y917389D03*
X1626741D03*
X1636316Y930774D03*
X1625803D03*
X1636646Y924081D03*
X1626741D03*
X1635441Y940814D03*
X1626741D03*
X1635441Y947507D03*
X1626741D03*
X1635441Y954200D03*
X1626741D03*
Y964239D03*
X1635441D03*
Y977625D03*
X1626741D03*
X1635441Y970932D03*
X1626741D03*
X1635441Y984318D03*
X1626741D03*
Y991011D03*
X1635441D03*
X1626249Y1002825D03*
X1635441Y1024475D03*
X1626741D03*
X1635441Y1017782D03*
X1626741D03*
X1635441Y1031168D03*
X1626741D03*
X1635441Y1037861D03*
X1626741D03*
X1635441Y1044554D03*
X1626741D03*
Y1057940D03*
X1635441D03*
Y1051247D03*
X1626741D03*
X1635441Y1064633D03*
X1626741D03*
X1635441Y1071326D03*
X1626741D03*
X1636241Y1078018D03*
X1625941D03*
Y1088058D03*
X1636241D03*
X1635441Y1094751D03*
X1626741D03*
Y1101444D03*
X1635441D03*
X1626741Y1108137D03*
X1635441D03*
X1626074Y1124640D03*
X1636341Y1124869D03*
X1635441Y1114829D03*
X1626741D03*
X1635441Y1144948D03*
X1626741D03*
X1635441Y1138255D03*
X1626741D03*
X1635441Y1130762D03*
X1626741D03*
Y1161680D03*
X1635441D03*
Y1151641D03*
X1626741D03*
Y1168373D03*
X1635441D03*
X1626741Y1175066D03*
X1635441D03*
X1626741Y1181759D03*
X1635441D03*
X1626741Y1188452D03*
X1635441D03*
X1626741Y1198491D03*
X1635441D03*
X1626741Y1205184D03*
X1635441D03*
Y1211877D03*
X1626741D03*
X1635441Y1218570D03*
X1626741D03*
X1636212Y1225263D03*
X1626055D03*
X1636376Y1235302D03*
X1625843D03*
X1635441Y1241995D03*
X1626741D03*
X1635688Y1257664D03*
X1626741Y1248688D03*
X1635441D03*
X1626741Y1258727D03*
X1629788Y1273344D03*
X1632588D03*
X1625729Y1266766D03*
X1630357Y1575592D03*
X1635313D03*
X1630357Y1580678D03*
X1635313D03*
X1640613Y1599790D03*
X1635657D03*
X1628553Y1599884D03*
X1630357Y1587598D03*
X1635313D03*
X1630357Y1592590D03*
X1635313D03*
X1640613Y1604876D03*
Y1611796D03*
X1635657Y1604876D03*
Y1611796D03*
X1640613Y1616788D03*
X1635657D03*
X1628553D03*
Y1604876D03*
Y1611796D03*
X1627362Y1679320D03*
Y1688391D03*
Y1693493D03*
Y1698030D03*
Y1683857D03*
Y1707666D03*
Y1712203D03*
Y1702564D03*
Y1730911D03*
Y1726377D03*
Y1721840D03*
Y1716737D03*
X1651583Y766798D03*
X1642883D03*
X1656441Y770144D03*
Y766798D03*
Y776837D03*
X1642883Y773491D03*
X1651583D03*
X1642883Y780184D03*
X1651583D03*
X1656441Y783530D03*
Y793570D03*
X1642883Y790223D03*
X1651583D03*
X1642883Y796916D03*
X1651583D03*
X1656441Y800263D03*
X1651583Y803609D03*
X1642883D03*
X1656441Y806955D03*
Y813648D03*
Y820341D03*
X1651583Y810302D03*
X1642883D03*
X1652545Y816995D03*
X1641945D03*
X1656441Y830381D03*
X1652767Y827034D03*
X1642018D03*
X1651583Y833727D03*
X1642883D03*
X1656441Y837074D03*
Y843766D03*
X1642883Y840420D03*
X1651583D03*
X1656441Y850459D03*
X1651583Y847113D03*
X1642883D03*
X1642058Y863845D03*
X1652742D03*
X1656441Y857152D03*
Y867192D03*
X1652559Y853806D03*
X1642032D03*
X1656441Y873885D03*
Y880577D03*
X1642883Y883924D03*
X1651583D03*
Y870538D03*
X1642883D03*
X1651583Y877231D03*
X1642883D03*
X1656441Y887270D03*
Y893963D03*
X1642883Y890617D03*
X1651583D03*
X1642883Y900656D03*
X1651583D03*
X1656441Y904003D03*
Y910696D03*
X1642883Y907349D03*
X1651583D03*
X1656441Y917389D03*
X1651583Y914042D03*
X1642883D03*
X1656441Y924081D03*
Y930774D03*
X1652630Y927428D03*
X1642038D03*
X1651583Y920735D03*
X1642883D03*
X1656441Y940814D03*
Y947507D03*
X1652501Y937467D03*
X1642065D03*
X1651583Y944160D03*
X1642883D03*
X1656441Y954200D03*
X1642883Y950853D03*
X1651583D03*
Y960892D03*
X1642883D03*
X1656441Y964239D03*
X1642783Y957546D03*
Y954200D03*
X1656441Y977625D03*
Y970932D03*
X1651583Y967585D03*
X1642883D03*
X1651583Y974278D03*
X1642883D03*
X1651583Y980971D03*
X1642883D03*
X1656441Y984318D03*
Y991011D03*
X1651583Y987664D03*
X1642883D03*
X1648205Y998632D03*
X1651583Y1017782D03*
X1642883D03*
X1656441D03*
Y1024475D03*
X1651583Y1027822D03*
X1642883D03*
X1656441Y1031168D03*
Y1044554D03*
Y1037861D03*
X1651583Y1034515D03*
X1642883D03*
X1651583Y1041207D03*
X1642883D03*
X1651583Y1047900D03*
X1642883D03*
Y1061286D03*
X1651583D03*
X1656441Y1051247D03*
Y1057940D03*
X1651583Y1054593D03*
X1642883D03*
X1656441Y1061286D03*
Y1064633D03*
Y1071326D03*
Y1078018D03*
X1652483Y1074672D03*
X1641983D03*
X1651583Y1067979D03*
X1642883D03*
X1656441Y1088058D03*
Y1094751D03*
X1652383Y1084711D03*
X1642083D03*
X1651583Y1091404D03*
X1642883D03*
X1656441Y1101444D03*
Y1108137D03*
X1642883Y1098097D03*
X1651583D03*
X1642883Y1104790D03*
X1651583D03*
X1642883Y1111483D03*
X1651583D03*
X1656441Y1114829D03*
Y1124869D03*
X1642883Y1121522D03*
X1651583D03*
X1642883Y1128215D03*
X1651583D03*
X1656441Y1131562D03*
Y1138255D03*
X1642883Y1134908D03*
X1651583D03*
X1642883Y1141601D03*
X1651583D03*
X1656441Y1144948D03*
Y1151641D03*
Y1161680D03*
X1652383Y1158333D03*
X1642083D03*
X1652794Y1148294D03*
X1641744D03*
X1656441Y1168373D03*
Y1175066D03*
X1642883Y1171719D03*
X1651583D03*
Y1165026D03*
X1642883D03*
X1656441Y1181759D03*
Y1188452D03*
X1651583Y1178412D03*
X1642883D03*
X1651583Y1185105D03*
X1642883D03*
X1656441Y1198491D03*
Y1205184D03*
X1642883Y1195144D03*
X1651583D03*
X1642883Y1201837D03*
X1651583D03*
X1642883Y1208530D03*
X1651583D03*
X1656441Y1211877D03*
X1652590Y1221916D03*
X1641793D03*
X1656441Y1225263D03*
Y1218570D03*
X1651583Y1215223D03*
X1642883D03*
X1656441Y1235302D03*
Y1241995D03*
X1652604Y1231955D03*
X1642054D03*
X1651583Y1238648D03*
X1642883D03*
X1656441Y1248688D03*
X1651583Y1245341D03*
X1642883D03*
Y1255381D03*
Y1258727D03*
Y1252034D03*
X1651679Y1248885D03*
X1653140Y1257862D03*
X1648588Y1273344D03*
X1645788D03*
X1656188Y1264964D03*
X1642788Y1264464D03*
X1642883Y1262074D03*
X1656170Y1260352D03*
X1647373Y1580678D03*
X1642417D03*
X1647373Y1575686D03*
X1642417D03*
X1647717Y1599884D03*
X1652673D03*
X1647373Y1592590D03*
X1642417D03*
X1647373Y1587598D03*
X1642417D03*
X1647717Y1616788D03*
X1652673D03*
X1647717Y1604876D03*
Y1611796D03*
X1652673Y1604876D03*
Y1611796D03*
X1665141Y770144D03*
X1672583Y766798D03*
X1665141Y776837D03*
Y783530D03*
X1672583Y773491D03*
Y780184D03*
X1665141Y793570D03*
Y800263D03*
X1672583Y790223D03*
Y796916D03*
Y803609D03*
X1665141Y806955D03*
Y813648D03*
X1666030Y820341D03*
X1672583Y810302D03*
Y816995D03*
X1665141Y830381D03*
X1672583Y827034D03*
Y833727D03*
X1665141Y837074D03*
Y843766D03*
X1672583Y840420D03*
X1665141Y850459D03*
X1672583Y847113D03*
X1666038Y857152D03*
X1665141Y867192D03*
X1672583Y853806D03*
Y863845D03*
X1665141Y873885D03*
Y880577D03*
X1672583Y870538D03*
Y877231D03*
Y883924D03*
X1665141Y887270D03*
Y893963D03*
X1672583Y890617D03*
Y900656D03*
X1665141Y904003D03*
Y910696D03*
Y917389D03*
X1672583Y907349D03*
Y914042D03*
X1665141Y924081D03*
X1666246Y930774D03*
X1672583Y920735D03*
Y927428D03*
X1665141Y940814D03*
Y947507D03*
X1672583Y937467D03*
Y944160D03*
X1665141Y954200D03*
Y964239D03*
X1672583Y950853D03*
Y960892D03*
Y957546D03*
Y954200D03*
X1665141Y977625D03*
Y970932D03*
X1672583Y967585D03*
Y974278D03*
Y980971D03*
X1665141Y984318D03*
Y991011D03*
X1672583Y987664D03*
Y994357D03*
X1665141Y1017782D03*
Y1024475D03*
Y1031168D03*
X1672583Y1017782D03*
Y1027822D03*
X1665141Y1044554D03*
Y1037861D03*
X1672583Y1034515D03*
Y1041207D03*
Y1047900D03*
X1665141Y1051247D03*
Y1057940D03*
X1672583Y1061286D03*
Y1054593D03*
X1665141Y1064633D03*
Y1071326D03*
Y1077118D03*
X1672583Y1067979D03*
Y1074672D03*
X1665141Y1088058D03*
Y1094751D03*
X1672583Y1084711D03*
Y1091404D03*
X1665141Y1101444D03*
Y1108137D03*
X1672583Y1098097D03*
Y1104790D03*
Y1111483D03*
X1665141Y1114829D03*
Y1124869D03*
X1672583Y1121522D03*
Y1128215D03*
X1665141Y1131562D03*
Y1138255D03*
Y1144948D03*
X1672583Y1134908D03*
Y1141601D03*
X1666141Y1151641D03*
X1665141Y1161680D03*
X1672583Y1148294D03*
Y1158333D03*
X1665141Y1168373D03*
Y1175066D03*
X1672583Y1165026D03*
Y1171719D03*
X1665141Y1181759D03*
Y1188452D03*
X1672583Y1178412D03*
Y1185105D03*
X1665141Y1198491D03*
Y1205184D03*
X1672583Y1195144D03*
Y1201837D03*
Y1208530D03*
X1665141Y1211877D03*
X1665941Y1225263D03*
X1665141Y1218570D03*
X1672583Y1215223D03*
Y1221916D03*
X1665141Y1235302D03*
Y1241995D03*
X1672583Y1231955D03*
Y1238648D03*
X1665141Y1248688D03*
X1672583Y1245341D03*
X1665688Y1257964D03*
X1672583Y1255381D03*
Y1258727D03*
Y1248688D03*
X1659488Y1273344D03*
X1662288D03*
X1672188Y1263764D03*
X1681283Y766798D03*
X1686141Y770144D03*
X1686041Y766798D03*
X1681283Y773491D03*
Y780184D03*
X1686141Y776837D03*
Y783530D03*
X1681283Y790223D03*
Y796916D03*
Y803609D03*
X1686141Y793570D03*
Y800263D03*
X1681283Y810302D03*
Y816995D03*
X1686141Y806955D03*
Y813648D03*
Y820341D03*
X1681283Y827034D03*
Y833727D03*
X1686141Y830381D03*
X1681283Y840420D03*
X1686141Y837074D03*
Y843766D03*
Y850459D03*
X1681283Y847113D03*
X1686141Y857152D03*
Y867192D03*
X1681283Y853806D03*
Y863845D03*
X1686141Y873885D03*
Y880577D03*
X1681283Y870538D03*
Y877231D03*
Y883924D03*
X1686141Y887270D03*
Y893963D03*
X1681283Y890617D03*
Y900656D03*
X1686141Y904003D03*
Y910696D03*
Y917389D03*
X1681283Y907349D03*
Y914042D03*
X1686141Y924081D03*
Y930774D03*
X1681283Y920735D03*
Y927428D03*
X1686141Y940814D03*
Y947507D03*
X1681283Y937467D03*
Y944160D03*
X1686141Y954200D03*
Y964239D03*
X1681283Y950853D03*
Y960892D03*
X1686141Y970932D03*
Y977625D03*
X1681283Y967585D03*
Y974278D03*
Y980971D03*
X1686141Y984318D03*
Y991011D03*
X1681283Y987664D03*
X1686141Y1017782D03*
Y1024475D03*
Y1031168D03*
X1681283Y1017782D03*
Y1027822D03*
X1686141Y1037861D03*
Y1044554D03*
X1681283Y1034515D03*
Y1041207D03*
Y1047900D03*
X1686141Y1051247D03*
Y1057940D03*
X1681283Y1061286D03*
Y1054593D03*
X1686141Y1064633D03*
Y1071326D03*
Y1078018D03*
X1681283Y1067979D03*
Y1074672D03*
X1686141Y1088058D03*
Y1094751D03*
X1681283Y1084711D03*
Y1091404D03*
X1686141Y1101444D03*
Y1108137D03*
X1681283Y1098097D03*
Y1104790D03*
Y1111483D03*
X1686141Y1114829D03*
Y1124869D03*
X1681283Y1121522D03*
Y1128215D03*
X1686141Y1131562D03*
Y1138255D03*
Y1144948D03*
X1681283Y1134908D03*
Y1141601D03*
X1686141Y1151641D03*
Y1161680D03*
X1681283Y1148294D03*
Y1158333D03*
X1686141Y1168373D03*
Y1175066D03*
X1681283Y1165026D03*
Y1171719D03*
X1686141Y1181759D03*
Y1188452D03*
X1681283Y1178412D03*
Y1185105D03*
X1686141Y1198491D03*
Y1205184D03*
X1681283Y1195144D03*
Y1201837D03*
Y1208530D03*
X1686141Y1211877D03*
Y1218570D03*
Y1225263D03*
X1681283Y1215223D03*
Y1221916D03*
Y1231955D03*
Y1238648D03*
X1686141Y1235302D03*
Y1241995D03*
X1681283Y1245341D03*
X1686141Y1248688D03*
Y1258727D03*
X1681179Y1252034D03*
X1675488Y1273344D03*
X1678288D03*
X1689188D03*
X1686119Y1264985D03*
X1681309Y1262074D03*
X1694841Y770144D03*
X1702283Y766798D03*
X1694841Y776837D03*
Y783530D03*
X1702283Y773491D03*
Y780184D03*
X1694841Y793570D03*
Y800263D03*
X1702283Y790223D03*
Y796916D03*
Y803609D03*
X1694841Y806955D03*
Y813648D03*
Y820341D03*
X1702283Y810302D03*
Y816995D03*
X1694841Y830381D03*
X1702283Y827034D03*
Y833727D03*
X1694841Y837074D03*
Y843766D03*
Y850459D03*
X1702283Y840420D03*
Y847113D03*
X1694841Y857152D03*
Y867192D03*
X1702283Y853806D03*
Y863845D03*
X1694841Y873885D03*
Y880577D03*
X1702283Y870538D03*
Y877231D03*
Y883924D03*
X1694841Y887270D03*
Y893963D03*
X1702283Y890617D03*
Y900656D03*
X1694841Y904003D03*
Y910696D03*
Y917389D03*
X1702283Y907349D03*
Y914042D03*
X1694841Y924081D03*
Y930774D03*
X1702283Y920735D03*
Y927428D03*
X1694841Y940814D03*
Y947507D03*
X1702283Y937467D03*
Y944160D03*
X1694841Y954200D03*
Y964239D03*
X1702283Y950853D03*
Y960892D03*
X1702183Y957546D03*
Y954200D03*
X1694841Y970932D03*
Y977625D03*
X1702283Y967585D03*
Y974278D03*
Y980971D03*
X1694841Y984318D03*
Y991011D03*
X1702283Y987664D03*
X1702183Y994357D03*
X1694841Y1017782D03*
Y1024475D03*
Y1031168D03*
X1702283Y1017782D03*
Y1027822D03*
X1694841Y1037861D03*
Y1044554D03*
X1702283Y1034515D03*
Y1041207D03*
Y1047900D03*
X1694841Y1051247D03*
Y1057940D03*
X1702283Y1054593D03*
Y1061286D03*
Y1057940D03*
X1694841Y1064633D03*
Y1071326D03*
Y1078018D03*
X1702283Y1067979D03*
Y1074672D03*
X1694841Y1088058D03*
Y1094751D03*
X1702283Y1084711D03*
Y1091404D03*
X1694841Y1101444D03*
Y1108137D03*
X1702283Y1098097D03*
Y1104790D03*
Y1111483D03*
X1694841Y1114829D03*
Y1124869D03*
X1702283Y1121522D03*
Y1128215D03*
X1694841Y1131562D03*
Y1138255D03*
Y1144948D03*
X1702283Y1134908D03*
Y1141601D03*
X1694841Y1151641D03*
Y1161680D03*
X1702283Y1148294D03*
Y1158333D03*
X1694841Y1168373D03*
Y1175066D03*
X1702283Y1165026D03*
Y1171719D03*
X1694841Y1181759D03*
Y1188452D03*
X1702283Y1178412D03*
Y1185105D03*
X1694841Y1198491D03*
Y1205184D03*
X1702283Y1195144D03*
Y1201837D03*
Y1208530D03*
X1694841Y1211877D03*
Y1218570D03*
Y1225263D03*
X1702283Y1215223D03*
Y1221916D03*
X1694841Y1235302D03*
Y1241995D03*
X1702283Y1231955D03*
Y1238648D03*
X1694841Y1248688D03*
X1695188Y1257064D03*
X1702283Y1245341D03*
X1699852Y1245418D03*
X1702283Y1248688D03*
X1691988Y1273344D03*
X1705188D03*
X1702249Y1265420D03*
X1702283Y1262074D03*
X1710983Y766798D03*
X1715841Y770144D03*
Y766798D03*
X1710983Y773491D03*
Y780184D03*
X1715841Y783530D03*
Y776837D03*
X1710983Y790223D03*
Y796916D03*
Y803609D03*
X1715841Y793570D03*
Y800263D03*
X1710983Y810302D03*
Y816995D03*
X1715841Y806955D03*
Y813648D03*
Y820341D03*
X1710983Y827034D03*
Y833727D03*
X1715841Y830381D03*
X1710983Y840420D03*
Y847113D03*
X1715841Y837074D03*
Y843766D03*
Y850459D03*
X1710983Y853806D03*
Y863845D03*
X1715841Y857152D03*
Y867192D03*
X1710983Y870538D03*
Y877231D03*
Y883924D03*
X1715841Y873885D03*
Y880577D03*
X1710983Y890617D03*
Y900656D03*
X1715841Y893963D03*
Y887270D03*
X1710983Y907349D03*
Y914042D03*
X1715841Y904003D03*
Y910696D03*
Y917389D03*
X1710983Y920735D03*
Y927428D03*
X1715841Y924081D03*
Y930774D03*
X1710983Y937467D03*
Y944160D03*
X1715841Y940814D03*
Y947507D03*
X1710983Y950853D03*
Y960892D03*
X1715841Y954200D03*
Y964239D03*
X1710983Y967585D03*
Y974278D03*
Y980971D03*
X1715841Y970932D03*
Y977625D03*
X1710983Y987664D03*
X1715841Y984318D03*
Y991011D03*
X1710983Y1017782D03*
Y1027822D03*
X1715841Y1017782D03*
Y1024475D03*
Y1031168D03*
X1710983Y1034515D03*
Y1041207D03*
Y1047900D03*
X1715841Y1037861D03*
Y1044554D03*
X1710983Y1054593D03*
Y1061286D03*
X1715841Y1051247D03*
Y1057940D03*
Y1061286D03*
X1710983Y1067979D03*
Y1074672D03*
X1715841Y1071326D03*
Y1064633D03*
Y1078018D03*
X1710983Y1084711D03*
Y1091404D03*
X1715841Y1088058D03*
Y1094751D03*
X1710983Y1098097D03*
Y1104790D03*
Y1111483D03*
X1715841Y1101444D03*
Y1108137D03*
X1710983Y1121522D03*
Y1128215D03*
X1715841Y1114829D03*
Y1124869D03*
X1710983Y1134908D03*
Y1141601D03*
X1715841Y1131562D03*
Y1138255D03*
Y1144948D03*
X1710983Y1148294D03*
Y1158333D03*
X1715841Y1151641D03*
Y1161680D03*
X1710983Y1165026D03*
Y1171719D03*
X1715841Y1168373D03*
Y1175066D03*
X1710983Y1178412D03*
Y1185105D03*
X1715841Y1181759D03*
Y1188452D03*
X1710983Y1195144D03*
Y1201837D03*
Y1208530D03*
X1715841Y1198491D03*
Y1205184D03*
X1710983Y1215223D03*
Y1221916D03*
X1715841Y1211877D03*
Y1218570D03*
Y1225263D03*
X1710983Y1231955D03*
Y1238648D03*
X1715841Y1235302D03*
Y1241995D03*
X1710983Y1245341D03*
X1715841Y1248688D03*
X1713620Y1258512D03*
X1711109Y1252034D03*
X1714440Y1255381D03*
X1707514Y1273444D03*
X1718888Y1273344D03*
X1721688D03*
X1715839Y1265420D03*
X1737020Y112177D03*
Y109677D03*
X1731983Y766798D03*
X1724541Y770144D03*
X1731983Y773491D03*
Y780184D03*
X1724541Y783530D03*
Y776837D03*
Y793570D03*
Y800263D03*
X1731983Y790223D03*
Y796916D03*
Y803609D03*
X1724541Y806955D03*
Y813648D03*
Y820341D03*
X1731983Y810302D03*
Y816995D03*
X1724541Y830381D03*
X1731983Y827034D03*
Y833727D03*
X1724541Y837074D03*
Y843766D03*
Y850459D03*
X1731983Y840420D03*
Y847113D03*
X1724541Y857152D03*
Y867192D03*
X1731983Y853806D03*
Y863845D03*
X1724541Y873885D03*
Y880577D03*
X1731983Y870538D03*
Y877231D03*
Y883924D03*
X1724541Y893963D03*
Y887270D03*
X1731983Y890617D03*
Y900656D03*
X1724541Y904003D03*
Y910696D03*
Y917389D03*
X1731983Y907349D03*
Y914042D03*
X1724541Y924081D03*
Y930774D03*
X1731983Y920735D03*
Y927428D03*
X1724541Y940814D03*
Y947507D03*
X1731983Y937467D03*
Y944160D03*
X1724541Y954200D03*
Y964239D03*
X1731983Y950853D03*
Y960892D03*
Y957546D03*
Y954200D03*
X1724541Y970932D03*
Y977625D03*
X1731983Y967585D03*
Y974278D03*
Y980971D03*
X1724541Y984318D03*
Y991011D03*
X1731983Y987664D03*
Y994357D03*
X1724541Y1017782D03*
Y1024475D03*
Y1031168D03*
X1731983Y1017782D03*
Y1027822D03*
X1724541Y1037861D03*
Y1044554D03*
X1731983Y1034515D03*
Y1041207D03*
Y1047900D03*
X1724541Y1051247D03*
Y1057940D03*
X1731983Y1054593D03*
Y1061286D03*
X1731683Y1057940D03*
X1724541Y1071326D03*
Y1064633D03*
Y1078018D03*
X1731983Y1074672D03*
Y1067979D03*
X1724541Y1088058D03*
Y1094751D03*
X1731983Y1084711D03*
Y1091404D03*
X1724541Y1101444D03*
Y1108137D03*
X1731983Y1098097D03*
Y1104790D03*
Y1111483D03*
X1724541Y1114829D03*
Y1124869D03*
X1731983Y1121522D03*
Y1128215D03*
X1724541Y1131562D03*
Y1138255D03*
Y1144948D03*
X1731983Y1134908D03*
Y1141601D03*
X1724541Y1151641D03*
Y1161680D03*
X1731983Y1148294D03*
Y1158333D03*
X1724541Y1168373D03*
Y1175066D03*
X1731983Y1165026D03*
Y1171719D03*
X1724541Y1181759D03*
Y1188452D03*
X1731983Y1178412D03*
Y1185105D03*
X1724541Y1198491D03*
Y1205184D03*
X1731983Y1195144D03*
Y1201837D03*
Y1208530D03*
X1724541Y1211877D03*
Y1218570D03*
Y1225263D03*
X1731983Y1215223D03*
Y1221916D03*
X1724541Y1235302D03*
Y1241995D03*
X1731983Y1231955D03*
Y1238648D03*
X1724541Y1248688D03*
X1724588Y1257164D03*
X1731983Y1245341D03*
X1727041Y1248688D03*
X1731983Y1255381D03*
Y1258727D03*
Y1252034D03*
Y1248688D03*
X1734888Y1273344D03*
X1737688D03*
X1731939Y1265420D03*
X1731983Y1262074D03*
X1747650Y109677D03*
Y112177D03*
X1744106Y109677D03*
Y112177D03*
X1740563Y109677D03*
Y112177D03*
X1740683Y766798D03*
X1745541Y770144D03*
X1754241D03*
X1745541Y766798D03*
X1740683Y773491D03*
Y780184D03*
X1745541Y776837D03*
X1754241D03*
X1745541Y783530D03*
X1754241D03*
X1740683Y790223D03*
Y796916D03*
Y803609D03*
X1745541Y793570D03*
X1754241D03*
X1745541Y800263D03*
X1754241D03*
X1740683Y810302D03*
Y816995D03*
X1745541Y806955D03*
X1754241D03*
X1745541Y813648D03*
X1754241D03*
X1745541Y820341D03*
X1754241D03*
X1740683Y827034D03*
Y833727D03*
X1745541Y830381D03*
X1754241D03*
X1740683Y840420D03*
Y847113D03*
X1754241Y843766D03*
X1745541D03*
Y837074D03*
X1754241D03*
X1745541Y850459D03*
X1754241D03*
X1740683Y853806D03*
Y863845D03*
X1745541Y857152D03*
X1754241D03*
Y867192D03*
X1745541D03*
X1740683Y870538D03*
Y877231D03*
Y883924D03*
X1745541Y873885D03*
X1754241D03*
X1745541Y880577D03*
X1754241D03*
X1740683Y890617D03*
Y900656D03*
X1754241Y893963D03*
X1745541D03*
Y887270D03*
X1754241D03*
X1740683Y907349D03*
Y914042D03*
X1754241Y904003D03*
X1745541D03*
X1754241Y910696D03*
X1745541D03*
X1754241Y917389D03*
X1745541D03*
X1740683Y920735D03*
Y927428D03*
X1754241Y924081D03*
X1745541D03*
X1754241Y930774D03*
X1745541D03*
X1740683Y937467D03*
Y944160D03*
X1754241Y940814D03*
X1745541D03*
X1754241Y947507D03*
X1745541D03*
X1740683Y950853D03*
Y960892D03*
X1754241Y954200D03*
X1745541D03*
X1754241Y964239D03*
X1745541D03*
X1740683Y967585D03*
Y974278D03*
Y980971D03*
X1754241Y970932D03*
X1745541D03*
X1754241Y977625D03*
X1745541D03*
X1740683Y987664D03*
X1754241Y984318D03*
X1745541D03*
X1754241Y991011D03*
X1745541D03*
X1740683Y1017782D03*
Y1027822D03*
X1754241Y1017782D03*
X1745541D03*
Y1024475D03*
X1754241D03*
X1745541Y1031168D03*
X1754241D03*
X1740683Y1034515D03*
Y1041207D03*
Y1047900D03*
X1754241Y1044554D03*
X1745541D03*
Y1037861D03*
X1754241D03*
X1740683Y1054593D03*
Y1061286D03*
X1745541Y1051247D03*
X1754241D03*
X1745541Y1057940D03*
X1754241D03*
X1740683Y1074672D03*
Y1067979D03*
X1754241Y1071326D03*
X1745541D03*
Y1064633D03*
X1754241D03*
Y1078018D03*
X1745541D03*
X1740683Y1084711D03*
Y1091404D03*
X1754241Y1088058D03*
X1745541D03*
X1754241Y1094751D03*
X1745541D03*
X1740683Y1098097D03*
Y1104790D03*
Y1111483D03*
X1754241Y1101444D03*
X1745541D03*
X1754241Y1108137D03*
X1745541D03*
X1740683Y1121522D03*
Y1128215D03*
X1754241Y1114829D03*
X1745541D03*
X1754241Y1124869D03*
X1745541D03*
X1740683Y1134908D03*
Y1141601D03*
X1754241Y1131562D03*
X1745541D03*
X1754241Y1138255D03*
X1745541D03*
X1754241Y1144948D03*
X1745541D03*
X1740683Y1148294D03*
Y1158333D03*
X1754241Y1151641D03*
X1745541D03*
X1754241Y1161680D03*
X1745541D03*
X1740683Y1165026D03*
Y1171719D03*
X1745541Y1175066D03*
X1754241D03*
Y1168373D03*
X1745541D03*
X1740683Y1178412D03*
Y1185105D03*
X1745541Y1181759D03*
X1754241D03*
Y1188452D03*
X1745541D03*
X1740683Y1195144D03*
Y1201837D03*
Y1208530D03*
X1754241Y1198491D03*
X1745541D03*
X1754241Y1205184D03*
X1745541D03*
X1740683Y1215223D03*
Y1221916D03*
X1754241Y1211877D03*
X1745541D03*
X1754241Y1218570D03*
X1745541D03*
X1754241Y1225263D03*
X1745541D03*
X1740683Y1231955D03*
Y1238648D03*
X1754241Y1235302D03*
X1745541D03*
X1754241Y1241995D03*
X1745541D03*
X1740683Y1245341D03*
X1754241Y1248688D03*
X1745541D03*
X1754488Y1257264D03*
X1745541Y1258727D03*
X1751388Y1273344D03*
X1748588D03*
X1745541Y1265420D03*
X1749088Y1310474D03*
X1746288D03*
X1770383Y766798D03*
X1761683D03*
X1770383Y773491D03*
X1761683D03*
Y780184D03*
X1770383D03*
X1761683Y790223D03*
X1770383D03*
X1761683Y796916D03*
X1770383D03*
X1761683Y803609D03*
X1770383D03*
X1761683Y810302D03*
X1770383D03*
X1761683Y816995D03*
X1770383D03*
X1761683Y827034D03*
X1770383D03*
X1761683Y833727D03*
X1770383D03*
X1761683Y840420D03*
X1770383D03*
X1761683Y847113D03*
X1770383D03*
X1761683Y853806D03*
X1770383D03*
X1761683Y863845D03*
X1770383D03*
X1761683Y870538D03*
X1770383D03*
X1761683Y877231D03*
X1770383D03*
X1761683Y883924D03*
X1770383D03*
X1761683Y890617D03*
X1770383D03*
X1761683Y900656D03*
X1770383D03*
X1761683Y907349D03*
X1770383D03*
X1761683Y914042D03*
X1770383D03*
Y927428D03*
X1761683D03*
Y920735D03*
X1770383D03*
X1761683Y937467D03*
X1770383D03*
X1761683Y944160D03*
X1770383D03*
X1761683Y950853D03*
X1770383D03*
X1761683Y960892D03*
X1770383D03*
X1761683Y957546D03*
Y954200D03*
Y967585D03*
X1770383D03*
X1761683Y974278D03*
X1770383D03*
X1761683Y980971D03*
X1770383D03*
X1761683Y987664D03*
X1770383D03*
X1761683Y994357D03*
Y1017782D03*
X1770383D03*
X1761683Y1027822D03*
X1770383D03*
X1761683Y1034515D03*
X1770383D03*
X1761683Y1041207D03*
X1770383D03*
X1761683Y1047900D03*
X1770383D03*
X1761683Y1054593D03*
X1770383D03*
X1761683Y1061286D03*
X1770383D03*
X1761683Y1067979D03*
X1770383D03*
X1761683Y1074672D03*
X1770383D03*
X1761683Y1084711D03*
X1770383D03*
X1761683Y1091404D03*
X1770383D03*
Y1098097D03*
X1761683D03*
Y1104790D03*
X1770383D03*
X1761683Y1111483D03*
X1770383D03*
X1761683Y1121522D03*
X1770383D03*
X1761683Y1128215D03*
X1770383D03*
X1761683Y1134908D03*
X1770383D03*
X1761683Y1141601D03*
X1770383D03*
X1761683Y1148294D03*
X1770383D03*
X1761683Y1158333D03*
X1770383D03*
X1761683Y1165026D03*
X1770383D03*
X1761683Y1171719D03*
X1770383D03*
X1761683Y1178412D03*
X1770383D03*
X1761683Y1185105D03*
X1770383D03*
X1761683Y1195144D03*
X1770383D03*
X1761683Y1201837D03*
X1770383D03*
X1761683Y1208530D03*
X1770383D03*
X1761683Y1215223D03*
X1770383D03*
X1761683Y1221916D03*
X1770383D03*
X1761683Y1231955D03*
X1770383D03*
X1761683Y1238648D03*
X1770383D03*
X1761683Y1245341D03*
X1770383D03*
X1756922Y1247632D03*
X1761683Y1255381D03*
Y1258727D03*
X1770299Y1252034D03*
X1761683Y1248688D03*
X1767388Y1273344D03*
X1764588D03*
X1761683Y1262074D03*
Y1265420D03*
X1775241Y770144D03*
X1783941D03*
X1773559Y767345D03*
X1775241Y776837D03*
X1783941D03*
X1775241Y783530D03*
X1783941D03*
X1775241Y793570D03*
X1783941D03*
X1775241Y800263D03*
X1783941D03*
X1775241Y806955D03*
X1783941D03*
X1775241Y813648D03*
X1783941D03*
X1775241Y820341D03*
X1783941D03*
Y830381D03*
X1775241D03*
Y837074D03*
X1783941D03*
X1775241Y843766D03*
X1783941D03*
X1775241Y850459D03*
X1783941D03*
X1775241Y857152D03*
X1783941D03*
X1775241Y867192D03*
X1783941D03*
X1775241Y873885D03*
X1783941D03*
X1775241Y880577D03*
X1783941D03*
X1775241Y887270D03*
X1783941D03*
X1775241Y893963D03*
X1783941D03*
X1775241Y904003D03*
X1783941D03*
X1775241Y910696D03*
X1783941D03*
X1775241Y917389D03*
X1783941D03*
X1775241Y924081D03*
X1783941D03*
X1775241Y930774D03*
X1783941D03*
X1775241Y940814D03*
X1783941D03*
X1775241Y947507D03*
X1783941D03*
X1775241Y954200D03*
X1783941D03*
X1775241Y964239D03*
X1783941D03*
X1775241Y970932D03*
X1783941D03*
X1775241Y977625D03*
X1783941D03*
X1775241Y984318D03*
X1783941D03*
X1775241Y991011D03*
X1783941D03*
X1775241Y1017782D03*
X1783941D03*
X1775241Y1024475D03*
X1783941D03*
X1775241Y1031168D03*
X1783941D03*
X1775241Y1037861D03*
X1783941D03*
X1775241Y1044554D03*
X1783941D03*
X1775241Y1051247D03*
X1783941D03*
X1775241Y1057940D03*
X1783941D03*
X1775241Y1061286D03*
Y1064633D03*
X1783941D03*
X1775241Y1071326D03*
X1783941D03*
X1775241Y1078018D03*
X1783941D03*
X1775241Y1088058D03*
X1783941D03*
X1775241Y1094751D03*
X1783941D03*
X1775241Y1101444D03*
X1783941D03*
X1775241Y1108137D03*
X1783941D03*
X1775241Y1114829D03*
X1783941D03*
X1775241Y1124869D03*
X1783941D03*
X1775241Y1131562D03*
X1783941D03*
X1775241Y1138255D03*
X1783941D03*
X1775241Y1144948D03*
X1783941D03*
Y1151641D03*
X1775241D03*
Y1161680D03*
X1783941D03*
X1775241Y1168373D03*
X1783941D03*
X1775241Y1175066D03*
X1783941D03*
X1775241Y1181759D03*
X1783941D03*
X1775241Y1188452D03*
X1783941D03*
X1775241Y1198491D03*
X1783941D03*
X1775241Y1205184D03*
X1783941D03*
X1775241Y1211877D03*
X1783941D03*
X1775241Y1218570D03*
X1783941D03*
X1775241Y1225263D03*
X1783941D03*
X1775241Y1235302D03*
X1783941D03*
X1775241Y1241995D03*
X1783941D03*
X1784188Y1257664D03*
X1775241Y1248688D03*
X1783941D03*
X1775241Y1258727D03*
X1781088Y1273344D03*
X1778288D03*
X1775241Y1265420D03*
X1791383Y766798D03*
X1800083D03*
X1791383Y773491D03*
X1800083D03*
X1791383Y780184D03*
X1800083D03*
X1791383Y790223D03*
X1800083D03*
X1791383Y796916D03*
X1800083D03*
X1791383Y803609D03*
X1800083D03*
X1791383Y810302D03*
X1800083D03*
X1791383Y816995D03*
X1800083D03*
X1791383Y827034D03*
X1800083D03*
Y833727D03*
X1791383D03*
Y840420D03*
X1800083D03*
X1791383Y847113D03*
X1800083D03*
X1791383Y853806D03*
X1800083D03*
X1791383Y863845D03*
X1800083D03*
X1791383Y870538D03*
X1800083D03*
X1791383Y877231D03*
X1800083D03*
X1791383Y883924D03*
X1800083D03*
X1791383Y890617D03*
X1800083D03*
X1791383Y900656D03*
X1800083D03*
X1791383Y907349D03*
X1800083D03*
X1791383Y914042D03*
X1800083D03*
X1791383Y920735D03*
X1800083D03*
X1791383Y927428D03*
X1800083D03*
X1791383Y937467D03*
X1800083D03*
X1791383Y944160D03*
X1800083D03*
Y950853D03*
X1791383D03*
Y960892D03*
X1800083D03*
X1791383Y957546D03*
Y954200D03*
Y967585D03*
X1800083D03*
X1791383Y974278D03*
X1800083D03*
X1791383Y980971D03*
X1800083D03*
X1791383Y987664D03*
X1800083D03*
X1791383Y994357D03*
Y1017782D03*
X1800083D03*
X1791383Y1027822D03*
X1800083D03*
X1791383Y1034515D03*
X1800083D03*
X1791383Y1041207D03*
X1800083D03*
X1791383Y1047900D03*
X1800083D03*
X1791383Y1054593D03*
X1800083D03*
X1791383Y1061286D03*
X1800083D03*
X1791383Y1067979D03*
X1800083D03*
X1791383Y1074672D03*
X1800083D03*
X1791383Y1084711D03*
X1800083D03*
X1791383Y1091404D03*
X1800083D03*
X1791383Y1098097D03*
X1800083D03*
X1791383Y1104790D03*
X1800083D03*
X1791383Y1111483D03*
X1800083D03*
X1791383Y1121522D03*
X1800083D03*
X1791383Y1128215D03*
X1800083D03*
Y1134908D03*
X1791383D03*
Y1141601D03*
X1800083D03*
X1791383Y1148294D03*
X1800083D03*
X1791383Y1158333D03*
X1800083D03*
X1791383Y1165026D03*
X1800083D03*
X1791383Y1171719D03*
X1800083D03*
X1791383Y1178412D03*
X1800083D03*
X1791383Y1185105D03*
X1800083D03*
X1791383Y1195144D03*
X1800083D03*
X1791383Y1201837D03*
X1800083D03*
X1791383Y1208530D03*
X1800083D03*
X1791383Y1215223D03*
X1800083D03*
X1791383Y1221916D03*
X1800083D03*
X1791383Y1231955D03*
X1800083D03*
X1791383Y1238648D03*
X1800083D03*
X1788373Y1241769D03*
X1791383Y1245341D03*
X1800083D03*
X1800427Y1248125D03*
X1800019Y1252034D03*
X1791383Y1248688D03*
X1797088Y1273344D03*
X1794288D03*
X1791383Y1265420D03*
Y1262074D03*
X1804941Y770144D03*
X1813641D03*
X1804841Y766798D03*
X1804941Y776837D03*
X1813641D03*
X1804941Y783530D03*
X1813641D03*
X1804941Y793570D03*
X1813641D03*
X1804941Y800263D03*
X1813641D03*
X1804941Y806955D03*
X1813641D03*
X1804941Y813648D03*
X1813641D03*
X1804941Y820341D03*
X1813641D03*
X1804941Y830381D03*
X1813641D03*
X1804941Y843766D03*
X1813641D03*
X1804941Y837074D03*
X1813641D03*
X1804941Y850459D03*
X1813641D03*
X1804941Y857152D03*
X1813641D03*
Y867192D03*
X1804941D03*
Y873885D03*
X1813641D03*
X1804941Y880577D03*
X1813641D03*
X1804941Y887270D03*
X1813641D03*
X1804941Y893963D03*
X1813641D03*
X1804941Y904003D03*
X1813641D03*
X1804941Y910696D03*
X1813641D03*
X1804941Y917389D03*
X1813641D03*
X1804941Y924081D03*
X1813641D03*
X1804941Y930774D03*
X1813641D03*
X1804941Y940814D03*
X1813641D03*
X1804941Y947507D03*
X1813641D03*
X1804941Y954200D03*
X1813641D03*
X1804941Y964239D03*
X1813641D03*
X1804941Y970932D03*
X1813641D03*
X1804941Y977625D03*
X1813641D03*
X1804941Y984318D03*
X1813641D03*
X1804941Y991011D03*
X1813641D03*
X1804941Y1017782D03*
X1813641D03*
X1804941Y1024475D03*
X1813641D03*
X1804941Y1031168D03*
X1813641D03*
X1804941Y1037861D03*
X1813641D03*
X1804941Y1044554D03*
X1813641D03*
Y1057940D03*
X1804941D03*
Y1051247D03*
X1813641D03*
X1804941Y1064633D03*
X1813641D03*
Y1071326D03*
X1804941D03*
X1813641Y1078018D03*
X1804941D03*
X1813641Y1088058D03*
X1804941D03*
X1813641Y1094751D03*
X1804941D03*
X1813641Y1101444D03*
X1804941D03*
X1813641Y1108137D03*
X1804941D03*
X1813641Y1114829D03*
X1804941D03*
X1813641Y1124869D03*
X1804941D03*
X1813641Y1131562D03*
X1804941D03*
X1813641Y1138255D03*
X1804941D03*
X1813641Y1144948D03*
X1804941D03*
X1813641Y1151641D03*
X1804941D03*
X1813641Y1161680D03*
X1804941D03*
X1813641Y1168373D03*
X1804941D03*
X1813641Y1175066D03*
X1804941D03*
X1813641Y1181759D03*
X1804941D03*
X1813641Y1188452D03*
X1804941D03*
X1813641Y1198491D03*
X1804941D03*
X1813641Y1205184D03*
X1804941D03*
X1813641Y1211877D03*
X1804941D03*
X1813641Y1218570D03*
X1804941D03*
X1813641Y1225263D03*
X1804941D03*
X1813641Y1235302D03*
X1804941D03*
X1813641Y1241995D03*
X1804941D03*
X1815063Y1233103D03*
X1813641Y1248688D03*
X1804941D03*
X1819054Y1253986D03*
X1804941Y1258727D03*
X1821083Y1252034D03*
X1813814Y1254693D03*
X1818188Y1273044D03*
X1810788Y1273344D03*
X1807988D03*
X1815388Y1273044D03*
X1804941Y1265420D03*
X1829783Y766798D03*
X1821083D03*
X1829783Y773491D03*
X1821083D03*
X1829783Y780184D03*
X1821083D03*
X1829783Y790223D03*
X1821083D03*
X1829783Y796916D03*
X1821083D03*
X1829783Y803609D03*
X1821083D03*
X1829783Y810302D03*
X1821083D03*
X1829783Y816995D03*
X1821083D03*
X1829783Y827034D03*
X1821083D03*
X1829783Y833727D03*
X1821083D03*
Y847113D03*
X1829783D03*
Y840420D03*
X1821083D03*
X1829783Y853806D03*
X1821083D03*
X1829783Y863845D03*
X1821083D03*
X1829783Y870538D03*
X1821083D03*
X1829783Y877231D03*
X1821083D03*
X1829783Y883924D03*
X1821083D03*
X1829783Y890617D03*
X1821083D03*
X1829783Y900656D03*
X1821083D03*
X1829783Y907349D03*
X1821083D03*
X1829783Y914042D03*
X1821083D03*
X1829783Y920735D03*
X1821083D03*
X1829783Y927428D03*
X1821083D03*
X1829783Y937467D03*
X1821083D03*
X1829783Y944160D03*
X1821083D03*
X1829783Y950853D03*
X1821083D03*
X1829783Y960892D03*
X1821083D03*
X1820983Y957546D03*
Y954200D03*
X1829783Y967585D03*
X1821083D03*
X1829783Y974278D03*
X1821083D03*
X1829783Y980971D03*
X1821083D03*
X1829783Y987664D03*
X1821083D03*
X1820983Y994357D03*
X1829783Y1017782D03*
X1821083D03*
X1829783Y1027822D03*
X1821083D03*
X1829783Y1034515D03*
X1821083D03*
X1829783Y1041207D03*
X1821083D03*
X1829783Y1047900D03*
X1821083D03*
X1829783Y1054593D03*
X1821083D03*
X1829783Y1061286D03*
X1821083D03*
X1829783Y1067979D03*
X1821083D03*
Y1074672D03*
X1829783D03*
X1821083Y1084711D03*
X1829783D03*
X1821083Y1091404D03*
X1829783D03*
X1821083Y1098097D03*
X1829783D03*
X1821083Y1104790D03*
X1829783D03*
X1821083Y1111483D03*
X1829783D03*
X1821083Y1121522D03*
X1829783D03*
X1821083Y1128215D03*
X1829783D03*
X1821083Y1134908D03*
X1829783D03*
X1821083Y1141601D03*
X1829783D03*
X1821083Y1148294D03*
X1829783D03*
X1821083Y1158333D03*
X1829783D03*
X1821083Y1165026D03*
X1829783D03*
X1821083Y1171719D03*
X1829783D03*
X1821083Y1178412D03*
X1829783D03*
X1821083Y1185105D03*
X1829783D03*
X1821083Y1195144D03*
X1829783D03*
X1821083Y1201837D03*
X1829783D03*
X1821083Y1208530D03*
X1829783D03*
X1821083Y1215223D03*
X1829783D03*
X1821083Y1221916D03*
X1829783D03*
X1821083Y1231955D03*
X1829783D03*
X1821083Y1238648D03*
X1829783D03*
Y1245341D03*
X1821083D03*
X1830379Y1250358D03*
X1821139Y1248155D03*
X1821083Y1262074D03*
Y1265420D03*
G54D42*
X174685Y637367D03*
X174393Y668511D03*
X205159Y1430034D03*
X393067Y1354446D03*
X422833D03*
X453169D03*
X468443Y1379662D03*
X482543Y1353962D03*
X526478Y1439952D03*
X718638Y1429579D03*
X1077638Y133866D03*
X1178470Y1466363D03*
X1369208Y1353946D03*
X1398974D03*
X1429310D03*
X1444043Y1379362D03*
X1459076Y1353946D03*
X1502956Y1439530D03*
X1682882Y618174D03*
Y669109D03*
X1679944Y1463655D03*
X1769790Y194789D03*
X1799350D03*
X1836248Y269763D03*
Y299056D03*
G54D33*
X48333Y444958D03*
X46759D03*
Y439446D03*
X48333D03*
X553063Y109171D03*
X554637D03*
Y114683D03*
X553063D03*
G54D127*
G01X198420Y1220162D02*
X204670D01*
G01X1363170Y200872D02*
X1359640Y197342D01*
X1357450D01*
X1356660Y198132D01*
X1354984D01*
X1353118Y199998D01*
X1349361D01*
G01X1355250Y211002D02*
X1354184Y209936D01*
Y204511D01*
X1352561Y202888D01*
Y201848D01*
G54D118*
G01X264340Y939945D02*
X263530D01*
X259543Y938735D01*
X258970Y938162D01*
G54D16*
X45775Y393408D03*
X45608Y386993D03*
X30616Y1256964D03*
Y1252965D03*
X62445Y443677D03*
X60316Y1256964D03*
X46616D03*
X68407Y763164D03*
X76316Y1256964D03*
X84795Y659641D03*
Y663141D03*
X87057Y667952D03*
X89025Y673881D03*
Y677881D03*
X85995Y725640D03*
X90016Y1256964D03*
X104967Y505374D03*
Y509374D03*
Y517925D03*
X96460Y649839D03*
X96530Y642149D03*
X96500Y646009D03*
X106016Y1256964D03*
X117241Y501638D03*
X117271Y507877D03*
Y512983D03*
X124117Y646822D03*
X122125Y667700D03*
X119716Y1256964D03*
Y1250499D03*
X143365Y694970D03*
X143265Y703270D03*
X140757Y1257952D03*
X142173Y1598155D03*
Y1602666D03*
X154135Y511095D03*
X144015Y522771D03*
X149416Y1256964D03*
X149779Y1546009D03*
X165416Y1256964D03*
X179116D03*
X208816D03*
X195116D03*
X224616Y1257520D03*
X238384Y1257456D03*
X254384Y1255756D03*
Y1251564D03*
X258783Y958053D03*
X327742Y205049D03*
X403421Y1418492D03*
X393426Y1412991D03*
Y1416491D03*
X411064Y929165D03*
X416948Y1415275D03*
X405037Y1413662D03*
X432842Y1626419D03*
X449017Y341362D03*
X450066Y1411678D03*
X446487Y1427968D03*
X458517Y341362D03*
X477940Y1402364D03*
X475417Y1408172D03*
X567482Y114132D03*
X567422Y109622D03*
X585523Y747887D03*
X608878Y145473D03*
X609045Y151888D03*
X610155Y774712D03*
X605647Y891364D03*
Y895384D03*
X616767Y34652D03*
X623807Y61272D03*
X631737Y421362D03*
X616737Y442862D03*
Y457862D03*
Y452862D03*
Y447862D03*
Y462862D03*
X646737Y416362D03*
Y431362D03*
Y457862D03*
Y452862D03*
Y447862D03*
Y462862D03*
X653246Y973428D03*
X653580Y989241D03*
Y985321D03*
X653516Y1256964D03*
X666497Y202362D03*
Y206362D03*
Y210362D03*
X670902Y1255932D03*
X684199Y35057D03*
X683216Y1256964D03*
X699780Y412255D03*
X699542Y417500D03*
X699502Y421540D03*
X708237Y484862D03*
Y488862D03*
X712916Y1256964D03*
X710737Y1301162D03*
Y1297162D03*
X705029Y1595623D03*
X705236Y1641851D03*
X716017Y82562D03*
X714564Y412269D03*
X728977Y411382D03*
X729049Y1249625D03*
X722769Y1593913D03*
X738237Y408362D03*
Y404362D03*
X742768Y1257681D03*
X747537Y74562D03*
X760737Y413212D03*
Y408212D03*
Y423212D03*
Y418212D03*
X759857Y469862D03*
Y464862D03*
X759862Y501662D03*
X759874Y497658D03*
X760334Y1257572D03*
X754629Y1581783D03*
Y1577203D03*
X775830Y432665D03*
X774825Y484802D03*
X774857Y488862D03*
X767204Y753179D03*
X772316Y1256964D03*
X788524Y432555D03*
X799037Y139262D03*
Y144262D03*
X810181Y276820D03*
X810235Y284311D03*
X797907Y308062D03*
X802016Y1256964D03*
X831716D03*
X849748Y301542D03*
X849907Y308852D03*
X860082Y269220D03*
X892498Y506875D03*
X903091Y507348D03*
X903597Y500117D03*
Y503631D03*
X909101Y493611D03*
X919417Y986242D03*
X928442Y197612D03*
X934885Y505977D03*
X934880Y501925D03*
X934911Y498083D03*
X955214Y403656D03*
Y399401D03*
X957123Y1559276D03*
X957163Y1563256D03*
X966306Y386189D03*
X966317Y402017D03*
X966373Y398138D03*
X1000517Y380862D03*
X991517Y387362D03*
Y383362D03*
Y391362D03*
X991598Y400607D03*
X1001763Y422682D03*
X1019677Y194609D03*
X1012847D03*
X1015780Y420548D03*
X1006752Y1257810D03*
Y1253869D03*
X1036458Y1256944D03*
X1022758D03*
X1028972Y1251503D03*
X1066158Y1256944D03*
Y1251277D03*
X1095858Y1256944D03*
X1092489Y1251409D03*
X1116924Y1253449D03*
X1125558Y1256944D03*
X1131978Y1251483D03*
X1155258Y1256944D03*
X1171517Y1020362D03*
X1184958Y1256944D03*
X1188675Y220362D03*
X1193290Y588714D03*
X1217250Y126942D03*
X1217217Y134600D03*
X1217247Y130810D03*
X1201404Y599133D03*
X1201764Y605605D03*
X1227610Y116962D03*
X1228610Y134262D03*
X1229140Y156672D03*
X1230527Y192482D03*
X1239237Y193362D03*
X1239110Y217462D03*
X1239137Y221562D03*
X1250102Y120107D03*
X1250103Y124107D03*
X1252670Y752449D03*
X1269881Y196622D03*
X1270110Y229462D03*
Y225462D03*
X1313224Y731375D03*
X1330817Y204900D03*
X1323300Y737747D03*
X1342108Y120618D03*
X1334126Y179062D03*
Y183068D03*
X1340603Y195530D03*
X1334252Y187059D03*
X1334214Y191009D03*
X1340554Y199534D03*
X1339151Y212239D03*
X1362679Y124123D03*
Y128285D03*
X1356079D03*
X1349109Y124718D03*
X1370483Y1402334D03*
X1369567Y1416491D03*
Y1412791D03*
X1387404Y928806D03*
X1393089Y1415275D03*
X1381462Y1413792D03*
Y1417304D03*
X1426617Y721944D03*
X1426614Y717865D03*
X1426193Y1412108D03*
X1422498Y1427948D03*
X1431777Y732212D03*
X1453237Y149362D03*
Y153362D03*
Y161862D03*
Y165862D03*
Y157862D03*
Y173862D03*
Y177862D03*
Y181862D03*
Y169862D03*
X1460224Y746305D03*
X1451490Y1408139D03*
X1464737Y145362D03*
X1481566Y309257D03*
X1589115Y215568D03*
X1589095Y207567D03*
X1589079Y235982D03*
X1604437Y725062D03*
X1610037Y583362D03*
X1640236Y647963D03*
Y681963D03*
Y715963D03*
X1629658Y1256944D03*
X1654746Y536071D03*
Y532071D03*
Y544622D03*
X1646315Y653741D03*
Y687742D03*
X1646433Y721761D03*
X1645743Y1257492D03*
X1667050Y539680D03*
X1666564Y534524D03*
X1667020Y528335D03*
X1659358Y1256944D03*
X1679195Y479078D03*
Y482590D03*
X1689058Y1256944D03*
X1704087Y199720D03*
X1694687Y198330D03*
X1694667Y202470D03*
X1693739Y475583D03*
X1693703Y486806D03*
X1694477Y481422D03*
X1693793Y537507D03*
X1713280Y39654D03*
Y43654D03*
Y47654D03*
Y51654D03*
X1718758Y1256944D03*
X1748458D03*
X1758129Y716448D03*
X1758229Y724648D03*
X1778158Y1256944D03*
X1793806Y1253019D03*
Y1256819D03*
X1809839Y1510437D03*
G36*
G01X453843Y1698263D02*
G02X441043Y1711068I-12800J5D01*
G02X453843Y1698273I0J-12800D01*
G01X449293D01*
G03X441043Y1690017I-8250J-5D01*
G03X449293Y1698263I0J8251D01*
G01X453843D01*
G37*
G36*
G01X1429237Y1698262D02*
G02X1416437Y1711067I-12800J5D01*
G02X1429237Y1698272I0J-12800D01*
G01X1424687D01*
G03X1416437Y1690016I-8250J-5D01*
G03X1424687Y1698262I0J8251D01*
G01X1429237D01*
G37*
G54D52*
X277098Y185236D03*
X322500Y1391830D03*
X395208Y185236D03*
X537477Y1395413D03*
X1133779Y1653543D03*
X1298642Y1391830D03*
X1513618Y1395413D03*
G54D109*
X1339045Y207575D03*
G54D25*
X36399Y960892D03*
Y957546D03*
Y967585D03*
Y1054593D03*
X52541Y964239D03*
Y1021129D03*
Y1024475D03*
Y1051247D03*
X66099Y780184D03*
Y773491D03*
Y786877D03*
Y803609D03*
Y796916D03*
Y790223D03*
Y816995D03*
Y810302D03*
Y833727D03*
Y823688D03*
Y827034D03*
Y847113D03*
Y840420D03*
Y853806D03*
Y860499D03*
Y863845D03*
Y883924D03*
Y877231D03*
Y870538D03*
Y890617D03*
Y897310D03*
Y900656D03*
Y914042D03*
Y907349D03*
Y927428D03*
Y920735D03*
Y934121D03*
Y944160D03*
Y937467D03*
Y960892D03*
Y950853D03*
Y957546D03*
Y980971D03*
Y974278D03*
Y967585D03*
Y994357D03*
Y987664D03*
Y1027822D03*
Y1021129D03*
Y1047900D03*
Y1041207D03*
Y1034515D03*
Y1054593D03*
Y1074672D03*
Y1067979D03*
Y1091404D03*
Y1081365D03*
Y1084711D03*
Y1098097D03*
Y1111483D03*
Y1104790D03*
Y1128215D03*
Y1118176D03*
Y1121522D03*
Y1141601D03*
Y1134908D03*
Y1148294D03*
Y1154987D03*
Y1158333D03*
Y1171719D03*
Y1165026D03*
Y1185105D03*
Y1178412D03*
Y1191798D03*
Y1208530D03*
Y1201837D03*
Y1195144D03*
Y1221916D03*
Y1215223D03*
Y1238648D03*
Y1228609D03*
Y1231955D03*
Y1245341D03*
X82241Y770144D03*
Y776837D03*
Y786877D03*
Y783530D03*
Y800263D03*
Y793570D03*
Y813648D03*
Y806955D03*
Y820341D03*
Y830381D03*
Y823688D03*
Y850459D03*
Y843766D03*
Y837074D03*
Y867192D03*
Y860499D03*
Y857152D03*
Y873885D03*
Y880577D03*
Y887270D03*
Y897310D03*
Y893963D03*
Y917389D03*
Y910696D03*
Y904003D03*
Y924081D03*
Y934121D03*
Y930774D03*
Y947507D03*
Y940814D03*
Y964239D03*
Y977625D03*
Y970932D03*
Y991011D03*
Y984318D03*
Y1021129D03*
Y1024475D03*
Y1031168D03*
Y1044554D03*
Y1037861D03*
Y1051247D03*
Y1071326D03*
Y1064633D03*
Y1078018D03*
Y1094751D03*
Y1088058D03*
Y1081365D03*
Y1108137D03*
Y1101444D03*
Y1124869D03*
Y1118176D03*
Y1114829D03*
Y1144948D03*
Y1138255D03*
Y1131562D03*
Y1161680D03*
Y1154987D03*
Y1151641D03*
Y1175066D03*
Y1168373D03*
Y1181759D03*
Y1191798D03*
Y1188452D03*
Y1205184D03*
Y1198491D03*
Y1218570D03*
Y1211877D03*
Y1225263D03*
Y1241995D03*
Y1235302D03*
Y1228609D03*
X95799Y960892D03*
Y957546D03*
Y967585D03*
Y1054593D03*
X125499Y780184D03*
Y773491D03*
Y786877D03*
Y803609D03*
Y796916D03*
Y790223D03*
Y816995D03*
Y810302D03*
Y833727D03*
Y823688D03*
Y827034D03*
Y847113D03*
Y840420D03*
Y853806D03*
Y860499D03*
Y863845D03*
Y883924D03*
Y877231D03*
Y870538D03*
Y890617D03*
Y897310D03*
Y900656D03*
Y914042D03*
Y907349D03*
Y927428D03*
Y920735D03*
Y934121D03*
Y944160D03*
Y937467D03*
Y960892D03*
Y950853D03*
X111941Y964239D03*
X125499Y957546D03*
Y980971D03*
Y974278D03*
Y967585D03*
Y994357D03*
Y987664D03*
X111941Y1021129D03*
Y1024475D03*
X125499Y1027822D03*
Y1021129D03*
Y1047900D03*
Y1041207D03*
Y1034515D03*
X111941Y1051247D03*
X125499Y1054593D03*
Y1074672D03*
Y1067979D03*
Y1091404D03*
Y1081365D03*
Y1084711D03*
Y1098097D03*
Y1111483D03*
Y1104790D03*
Y1128215D03*
Y1118176D03*
Y1121522D03*
Y1141601D03*
Y1134908D03*
Y1148294D03*
Y1154987D03*
Y1158333D03*
Y1171719D03*
Y1165026D03*
Y1185105D03*
Y1178412D03*
Y1191798D03*
Y1208530D03*
Y1201837D03*
Y1195144D03*
Y1221916D03*
Y1215223D03*
Y1238648D03*
Y1228609D03*
Y1231955D03*
Y1245341D03*
X141641Y770144D03*
Y776837D03*
Y786877D03*
Y783530D03*
Y800263D03*
Y793570D03*
Y813648D03*
Y806955D03*
Y820341D03*
Y830381D03*
Y823688D03*
Y850459D03*
Y843766D03*
Y837074D03*
Y867192D03*
Y860499D03*
Y857152D03*
Y873885D03*
Y880577D03*
Y887270D03*
Y897310D03*
Y893963D03*
Y917389D03*
Y910696D03*
Y904003D03*
Y924081D03*
Y934121D03*
Y930774D03*
Y947507D03*
Y940814D03*
Y964239D03*
Y977625D03*
Y970932D03*
Y991011D03*
Y984318D03*
Y1021129D03*
Y1024475D03*
Y1031168D03*
Y1044554D03*
Y1037861D03*
Y1051247D03*
Y1071326D03*
Y1064633D03*
Y1078018D03*
Y1094751D03*
Y1088058D03*
Y1081365D03*
Y1108137D03*
Y1101444D03*
Y1124869D03*
Y1118176D03*
Y1114829D03*
Y1144948D03*
Y1138255D03*
Y1131562D03*
Y1161680D03*
Y1154987D03*
Y1151641D03*
Y1175066D03*
Y1168373D03*
Y1181759D03*
Y1191798D03*
Y1188452D03*
Y1205184D03*
Y1198491D03*
Y1218570D03*
Y1211877D03*
Y1225263D03*
Y1241995D03*
Y1235302D03*
Y1228609D03*
X155199Y960892D03*
Y957546D03*
Y967585D03*
Y1054593D03*
X171341Y964239D03*
Y1021129D03*
Y1024475D03*
Y1051247D03*
X184899Y780184D03*
Y773491D03*
Y786877D03*
Y803609D03*
Y796916D03*
Y790223D03*
Y816995D03*
Y810302D03*
Y833727D03*
Y823688D03*
Y827034D03*
Y847113D03*
Y840420D03*
Y853806D03*
Y860499D03*
Y863845D03*
Y883924D03*
Y877231D03*
Y870538D03*
Y890617D03*
Y897310D03*
Y900656D03*
Y914042D03*
Y907349D03*
Y927428D03*
Y920735D03*
Y934121D03*
Y944160D03*
Y937467D03*
Y960892D03*
Y950853D03*
Y957546D03*
Y980971D03*
Y974278D03*
Y967585D03*
Y994357D03*
Y987664D03*
Y1027822D03*
Y1021129D03*
Y1047900D03*
Y1041207D03*
Y1034515D03*
Y1054593D03*
Y1074672D03*
Y1067979D03*
Y1091404D03*
Y1081365D03*
Y1084711D03*
Y1098097D03*
Y1111483D03*
Y1104790D03*
Y1128215D03*
Y1118176D03*
Y1121522D03*
Y1141601D03*
Y1134908D03*
Y1148294D03*
Y1154987D03*
Y1158333D03*
Y1171719D03*
Y1165026D03*
Y1185105D03*
Y1178412D03*
Y1191798D03*
Y1208530D03*
Y1201837D03*
Y1195144D03*
Y1221916D03*
Y1215223D03*
Y1238648D03*
Y1228609D03*
Y1231955D03*
Y1245341D03*
X201041Y770144D03*
Y776837D03*
Y786877D03*
Y783530D03*
Y800263D03*
Y793570D03*
Y813648D03*
Y806955D03*
Y820341D03*
Y830381D03*
Y823688D03*
Y850459D03*
Y843766D03*
Y837074D03*
Y867192D03*
Y860499D03*
Y857152D03*
Y873885D03*
Y880577D03*
Y887270D03*
Y897310D03*
Y893963D03*
Y917389D03*
Y910696D03*
Y904003D03*
Y924081D03*
Y934121D03*
Y930774D03*
Y947507D03*
Y940814D03*
Y964239D03*
Y977625D03*
Y970932D03*
Y991011D03*
Y984318D03*
X201141Y1021129D03*
Y1024475D03*
Y1031168D03*
Y1044554D03*
Y1037861D03*
Y1051247D03*
Y1071326D03*
Y1064633D03*
Y1078018D03*
Y1094752D03*
Y1088059D03*
Y1081366D03*
Y1108137D03*
Y1101444D03*
X201041Y1124869D03*
X201141Y1118177D03*
Y1114830D03*
Y1144948D03*
Y1138255D03*
X201041Y1131562D03*
X201141Y1161680D03*
Y1154988D03*
Y1151641D03*
Y1175066D03*
Y1168373D03*
Y1181759D03*
Y1191799D03*
Y1188452D03*
Y1205184D03*
Y1198491D03*
Y1218570D03*
Y1211877D03*
Y1225263D03*
Y1241995D03*
Y1235302D03*
Y1228609D03*
X214599Y960892D03*
Y957546D03*
X244299Y883924D03*
Y890617D03*
Y897310D03*
Y900656D03*
Y914042D03*
Y907349D03*
Y960892D03*
Y957546D03*
Y1185105D03*
Y1178412D03*
Y1191798D03*
Y1208530D03*
Y1201837D03*
Y1195144D03*
X260441Y880577D03*
Y887270D03*
Y897310D03*
Y893963D03*
Y910696D03*
Y904003D03*
Y1175066D03*
Y1181759D03*
Y1191798D03*
Y1188452D03*
Y1205184D03*
Y1198491D03*
X337779Y880219D03*
X335928Y883423D03*
X337779Y893036D03*
X335928Y889832D03*
X334079Y886627D03*
X337779D03*
X336361Y1121447D03*
X350727Y851380D03*
X354427Y844971D03*
X348878Y848176D03*
X352578D03*
X350729Y857789D03*
X352578Y860993D03*
X354429Y857789D03*
X341479Y880219D03*
X343329Y883423D03*
X350729Y870606D03*
X354429D03*
X352578Y873810D03*
X354429Y883423D03*
X348878Y899445D03*
Y893036D03*
X350729Y889832D03*
X354429D03*
X341478Y893036D03*
X343328Y889832D03*
X347029Y896240D03*
X354429D03*
X341479Y886627D03*
X350729Y896240D03*
X345179Y886627D03*
X348878Y912262D03*
X350729Y909057D03*
X354429D03*
X350729Y902649D03*
X354429D03*
X347029Y915466D03*
X354429D03*
X350729D03*
X348879Y931488D03*
X350729Y928283D03*
X354429D03*
Y921875D03*
X350729D03*
X348878Y918670D03*
X350729Y941100D03*
X348878Y937896D03*
X354429Y941100D03*
X347029Y934691D03*
X354429D03*
X350729D03*
Y947509D03*
X354429D03*
X348878Y950713D03*
X350729Y960326D03*
X348878Y957122D03*
X354429Y960326D03*
X350729Y966735D03*
X354429D03*
X350729Y953917D03*
X354429D03*
X347030D03*
X350729Y979552D03*
X354429D03*
X348878Y976347D03*
X347029Y973143D03*
X348878Y969939D03*
X347461Y1006093D03*
X349311Y1002888D03*
X351161Y999684D03*
X354861D03*
X351161Y1012501D03*
X349311Y1009297D03*
X354861Y1012501D03*
X351162Y1031727D03*
X349311Y1028523D03*
X354861Y1031727D03*
X349311Y1022114D03*
X351161Y1018910D03*
X354861D03*
X347461Y1025318D03*
X354862D03*
X351162D03*
X349311Y1047749D03*
Y1041340D03*
X351161Y1038136D03*
X354861D03*
X347461Y1044544D03*
X354861D03*
X351161D03*
X349311Y1060565D03*
X351161Y1057361D03*
X354861D03*
X347461Y1063770D03*
X351161D03*
X354861D03*
X351161Y1050952D03*
X354861D03*
Y1070178D03*
X351162D03*
X349311Y1066974D03*
Y1079791D03*
X351161Y1076587D03*
X354861D03*
X351161Y1089404D03*
X349311Y1086200D03*
X354861Y1089404D03*
X347461Y1082995D03*
X354861D03*
X351161D03*
X341911Y1105426D03*
X343762Y1108630D03*
X345611Y1111834D03*
X351161Y1102221D03*
X349312Y1111834D03*
X353011Y1105426D03*
X345611D03*
X341912Y1111834D03*
X354861Y1102221D03*
X353012Y1111834D03*
X351162Y1108630D03*
X353011Y1124651D03*
X354861Y1127856D03*
X347461Y1115039D03*
X341912Y1118243D03*
X340061Y1127856D03*
X343761D03*
X347461Y1121447D03*
X340061D03*
X343761D03*
X347461Y1127856D03*
X345611Y1124651D03*
X349312Y1137469D03*
X351161Y1134264D03*
X341911Y1131060D03*
X356279Y841467D03*
X361827Y844971D03*
X363679Y841467D03*
X369227Y844971D03*
X371079Y841467D03*
X358127Y844971D03*
X359978Y848176D03*
X365527Y844971D03*
X367378Y848176D03*
X371078Y867401D03*
X356278D03*
X363678D03*
X356278Y854584D03*
X358129Y857789D03*
X363678Y854584D03*
X365529Y857789D03*
X371078Y854584D03*
X359978Y860993D03*
X361829Y857789D03*
X367378Y860993D03*
X369229Y857789D03*
X358129Y870606D03*
X361829D03*
X365529D03*
X359978Y873810D03*
X367378D03*
X369229Y870606D03*
X356278Y880219D03*
X358129Y883423D03*
X363678Y880219D03*
X365529Y883423D03*
X371078Y880219D03*
X361829Y883423D03*
X369229D03*
X356278Y899445D03*
Y893036D03*
X358129Y896240D03*
X363678Y899445D03*
X367378D03*
X371078Y893036D03*
X359978Y886627D03*
X367378D03*
X356278Y912262D03*
X358129Y915466D03*
X363678Y912262D03*
X361829Y909057D03*
X367378Y912262D03*
X369229Y909057D03*
X361829Y902649D03*
X369229D03*
X359978Y905853D03*
X367378D03*
X363678D03*
X371078D03*
X356278Y931488D03*
X363678D03*
X356278Y918670D03*
X361829Y928283D03*
X367378Y931488D03*
X369229Y928283D03*
X361829Y921875D03*
X363678Y918670D03*
X369229Y921875D03*
X367378Y918670D03*
X359978Y925079D03*
X367378D03*
X363678D03*
X371078D03*
X356278Y937896D03*
X358129Y934691D03*
X361829Y941100D03*
X363678Y937896D03*
X369229Y941100D03*
X367378Y937896D03*
X361829Y947509D03*
X369229D03*
X367378Y944304D03*
X359978D03*
X371078D03*
X363678D03*
X356278Y950713D03*
Y957122D03*
X358129Y953917D03*
X361829Y966735D03*
X369229D03*
X359978Y963530D03*
X363678Y950713D03*
X367378D03*
X361829Y960326D03*
X363678Y957122D03*
X369229Y960326D03*
X367378Y957122D03*
X371078Y963530D03*
X359978Y982756D03*
X367378D03*
X363678D03*
X371078D03*
X369229Y979552D03*
X367378Y976347D03*
X361829Y979552D03*
X363678Y976347D03*
X356278D03*
Y969939D03*
X358129Y973143D03*
X363678Y969939D03*
X367378D03*
X358562Y1006093D03*
X356711Y1002888D03*
Y1009297D03*
X362262Y1012501D03*
X369662D03*
X364111Y1009297D03*
X367811D03*
X364111Y1002888D03*
X362262Y999684D03*
X371511Y1002888D03*
X369662Y999684D03*
X356711Y1028523D03*
Y1022114D03*
X362262Y1031727D03*
X364111Y1028523D03*
X369662Y1031727D03*
X367811Y1028523D03*
X358562Y1025318D03*
X360411Y1015705D03*
X371511D03*
X364111Y1022114D03*
X362262Y1018910D03*
X367811Y1022114D03*
X369662Y1018910D03*
X356711Y1047749D03*
Y1041340D03*
X364111D03*
X362262Y1038136D03*
X367811Y1041340D03*
X369662Y1038136D03*
X360411Y1034931D03*
X371511D03*
X364111D03*
X358562Y1044544D03*
X367811Y1034931D03*
X364111Y1047749D03*
X367811D03*
X356711Y1060565D03*
X358562Y1063770D03*
X364111Y1060565D03*
X362262Y1057361D03*
X367811Y1060565D03*
X369662Y1057361D03*
X362262Y1050952D03*
X369662D03*
X360411Y1054157D03*
X371511D03*
X364111D03*
X367811D03*
X356711Y1066974D03*
X367811Y1079791D03*
X369662Y1076587D03*
X362262Y1070178D03*
X364111Y1066974D03*
X369662Y1070178D03*
X367811Y1066974D03*
X356711Y1079791D03*
X364111D03*
X362262Y1076587D03*
X360411Y1073383D03*
X371511D03*
X364111D03*
X367811D03*
X356711Y1086200D03*
X358562Y1082995D03*
X362262Y1095813D03*
X369662D03*
X362262Y1089404D03*
X364111Y1086200D03*
X369662Y1089404D03*
X367811Y1086200D03*
X360411Y1092608D03*
X367811D03*
X364111D03*
X371511D03*
X364111Y1099017D03*
X367811D03*
X358561Y1108630D03*
X360412Y1111834D03*
X364112Y1105426D03*
X369661Y1108630D03*
X362261D03*
X365961D03*
X367812Y1111834D03*
X358561Y1121447D03*
X360412Y1124651D03*
X364111D03*
X367811D03*
X371511D03*
X356712D03*
X362262Y1127856D03*
X365962Y1121447D03*
X369662Y1127856D03*
X365961Y1115039D03*
X358561D03*
X369661D03*
X358561Y1134264D03*
X362261Y1140973D03*
X365962Y1134264D03*
X369661Y1140973D03*
X356712Y1137469D03*
X360412D03*
X364112D03*
X367812D03*
X371512D03*
X387727Y844971D03*
X376627D03*
X380327D03*
X384027D03*
X385879Y841467D03*
X372927Y844971D03*
X374778Y848176D03*
X378479Y841467D03*
X382178Y848176D03*
X378478Y867401D03*
X385878D03*
X387729Y857789D03*
X372929D03*
X378478Y854584D03*
X380329Y857789D03*
X384029D03*
X374778Y860993D03*
X376629Y857789D03*
X382178Y860993D03*
X385878Y854584D03*
X387729Y870606D03*
X372929D03*
X380329D03*
X374778Y873810D03*
X376629Y870606D03*
X382178Y873810D03*
X384029Y870606D03*
X372929Y883423D03*
X378478Y880219D03*
X380329Y883423D03*
X385878Y880219D03*
X387729Y883423D03*
X376629D03*
X384029D03*
X374778Y899445D03*
X382178D03*
Y893036D03*
X374778D03*
X385878D03*
X372929Y896240D03*
X380329D03*
X376629D03*
X384029D03*
X374778Y886627D03*
X382178D03*
X376629Y902649D03*
X380329D03*
X374778Y912262D03*
X376629Y909057D03*
X382178Y912262D03*
X380329Y909057D03*
X387729D03*
Y902649D03*
X372929Y915466D03*
X385878Y905853D03*
X380329Y915466D03*
X376629D03*
X384029D03*
X374778Y931488D03*
X376629Y928283D03*
X382178Y931488D03*
X380329Y928283D03*
X387729Y921875D03*
X376629D03*
X374778Y918670D03*
X380329Y921875D03*
X382178Y918670D03*
X387729Y928283D03*
X385878Y925079D03*
X380329Y941100D03*
X382178Y937896D03*
X376629Y947509D03*
X380329D03*
X376629Y941100D03*
X374778Y937896D03*
X372929Y934691D03*
X380329D03*
X376629D03*
X384029D03*
X387729Y947509D03*
Y941100D03*
X385878Y944304D03*
X376629Y960326D03*
X374778Y957122D03*
X380329Y960326D03*
X382178Y957122D03*
X374778Y950713D03*
X382178D03*
X372929Y953917D03*
X380329D03*
X376629D03*
X384029D03*
X387729Y960326D03*
Y966735D03*
X380329D03*
X376629D03*
X385878Y963530D03*
Y982756D03*
X387729Y979552D03*
X376629D03*
X380329D03*
X374778Y976347D03*
X382178D03*
X372929Y973143D03*
X374778Y969939D03*
X382178D03*
X384029Y973143D03*
X373362Y1006093D03*
X380762D03*
X377062D03*
X384462D03*
X375211Y1002888D03*
X377062Y999684D03*
X382611Y1002888D03*
X380762Y999684D03*
X377062Y1012501D03*
X375211Y1009297D03*
X380762Y1012501D03*
X382611Y1009297D03*
X377062Y1031727D03*
X375211Y1028523D03*
X380762Y1031727D03*
X382611Y1028523D03*
X375211Y1022114D03*
X377062Y1018910D03*
X382611Y1022114D03*
X380762Y1018910D03*
X377062Y1025318D03*
X384462D03*
X373360D03*
X380760D03*
X386311Y1015705D03*
X375211Y1047749D03*
X382611D03*
X375211Y1041340D03*
X377062Y1038136D03*
X382611Y1041340D03*
X380762Y1038136D03*
X373362Y1044544D03*
X380762D03*
X377062D03*
X384462D03*
X386311Y1034931D03*
X375211Y1060565D03*
X377062Y1057361D03*
X382611Y1060565D03*
X380762Y1057361D03*
X377062Y1050952D03*
X380762D03*
X373362Y1063770D03*
X384462D03*
X377062D03*
X380762D03*
X386311Y1054157D03*
X380762Y1070178D03*
X382611Y1066974D03*
X377062Y1070178D03*
X375211Y1066974D03*
Y1079791D03*
X377062Y1076587D03*
X382611Y1079791D03*
X380762Y1076587D03*
X386311Y1073383D03*
X377062Y1089404D03*
X375211Y1086200D03*
X380762Y1089404D03*
X382611Y1086200D03*
X373362Y1082995D03*
X386311Y1092608D03*
X384462Y1082995D03*
X377062D03*
X380762D03*
X386311Y1105426D03*
X382611Y1111834D03*
X375211Y1105426D03*
X377062Y1108630D03*
X380762Y1102221D03*
X378911Y1111834D03*
X384462Y1108630D03*
X386311Y1111834D03*
X378912Y1105426D03*
X375211Y1111834D03*
X382611Y1105426D03*
X375211Y1124651D03*
X378911D03*
X382611D03*
X386311D03*
X373362Y1121447D03*
X377062Y1127856D03*
X380762Y1121447D03*
X384462Y1127856D03*
X380762Y1115039D03*
X373362Y1134264D03*
X377061Y1140973D03*
X380762Y1134264D03*
X384461Y1140973D03*
X375212Y1137469D03*
X378912D03*
X382612D03*
X386312D03*
X391427Y844971D03*
X395127D03*
X398827D03*
X400679Y841467D03*
X389578Y848176D03*
X393279Y841467D03*
X396978Y848176D03*
X402527Y844971D03*
X400678Y867401D03*
X393278D03*
Y854584D03*
X395129Y857789D03*
X400678Y854584D03*
X402529Y857789D03*
X389578Y860993D03*
X391429Y857789D03*
X396978Y860993D03*
X398829Y857789D03*
X391429Y870606D03*
X395129D03*
X402529D03*
X389578Y873810D03*
X396978D03*
X398829Y870606D03*
X393278Y880219D03*
X395129Y883423D03*
X400678Y880219D03*
X402529Y883423D03*
X391429D03*
X398829D03*
X389578Y899445D03*
X393278D03*
X396978Y886627D03*
X389578D03*
Y912262D03*
X393278D03*
X395129Y909057D03*
Y902649D03*
X393278Y905853D03*
X389578D03*
X396978D03*
X393278Y931488D03*
X395129Y928283D03*
X389578Y918670D03*
X395129Y921875D03*
X393278Y918670D03*
X389578Y931488D03*
X393278Y925079D03*
X389578D03*
X396978D03*
X395129Y947509D03*
X389578Y937896D03*
X395129Y941100D03*
X393278Y937896D03*
Y944304D03*
X389578D03*
X396978D03*
X389578Y957122D03*
X395129Y960326D03*
X393278Y957122D03*
X395129Y966735D03*
X389578Y950713D03*
X393278D03*
X396978Y963530D03*
X393278D03*
X389578D03*
X398829Y973143D03*
X400678Y976347D03*
X402529Y979552D03*
Y973143D03*
X393278Y982756D03*
X389578D03*
X396978D03*
X393278Y976347D03*
X395129Y979552D03*
X389579Y976347D03*
X389578Y969939D03*
X393278D03*
X390011Y1002888D03*
X388162Y999684D03*
X393711Y1002888D03*
X395562Y999684D03*
X388162Y1012501D03*
X395562D03*
X390011Y1009297D03*
X393711D03*
X397411Y1015705D03*
X388162Y1031727D03*
X390011Y1028523D03*
X395562Y1031727D03*
X393711Y1028523D03*
X390011Y1022114D03*
X388162Y1018910D03*
X393711Y1022114D03*
X395562Y1018910D03*
X390011Y1041340D03*
X388162Y1038136D03*
X393711Y1041340D03*
X395562Y1038136D03*
X390011Y1047749D03*
X393711D03*
Y1034931D03*
X390011D03*
X397411D03*
X390011Y1060565D03*
X388162Y1057361D03*
X393711Y1060565D03*
X395562Y1057361D03*
X388162Y1050952D03*
X395562D03*
X393711Y1054157D03*
X390011D03*
X397411D03*
X390011Y1079791D03*
X388162Y1076587D03*
X393711Y1079791D03*
X395562Y1076587D03*
X388162Y1070178D03*
X390011Y1066974D03*
X395562Y1070178D03*
X393711Y1066974D03*
Y1073383D03*
X390011D03*
X397411D03*
X395562Y1095813D03*
X388162Y1089404D03*
X390011Y1086200D03*
X395562Y1089404D03*
X393711Y1086200D03*
X388162Y1095813D03*
X393711Y1092608D03*
X390011D03*
X397411D03*
X402962Y1082995D03*
X402961Y1089404D03*
X393711Y1099017D03*
X390011D03*
X401111D03*
X391862Y1108630D03*
X393711Y1111834D03*
X397411Y1105426D03*
X402962Y1108630D03*
Y1102221D03*
X395562Y1108630D03*
X399262D03*
X401111Y1111834D03*
X390011Y1124651D03*
X395562Y1121447D03*
X397411Y1124651D03*
X401111D03*
X391862Y1127856D03*
X393711Y1124651D03*
X399262Y1127856D03*
X402962Y1121447D03*
X388162D03*
X399262Y1115039D03*
X391862D03*
X402962D03*
X391861Y1140973D03*
X395562Y1134264D03*
X399261Y1140973D03*
X402962Y1134264D03*
X388162D03*
X390012Y1137469D03*
X393712D03*
X397412D03*
X401112D03*
X406227Y844971D03*
X409927D03*
X413627D03*
X417327D03*
X404378Y848176D03*
X408079Y841467D03*
X411778Y848176D03*
X415479Y841467D03*
X419178Y848176D03*
X408078Y867401D03*
X415478D03*
X408078Y854584D03*
X409929Y857789D03*
X415478Y854584D03*
X417329Y857789D03*
X404378Y860993D03*
X406229Y857789D03*
X411778Y860993D03*
X413629Y857789D03*
X419178Y860993D03*
X404378Y873810D03*
X406229Y870606D03*
X408078Y880219D03*
X409929Y883423D03*
X406229D03*
X419178Y873810D03*
X417329Y870606D03*
X411778Y873810D03*
X413629Y870606D03*
X417329Y883423D03*
X415478Y880219D03*
X413629Y883423D03*
X404378Y886627D03*
X411778D03*
X419178D03*
X408511Y1079791D03*
X406662Y1089404D03*
X410362D03*
X404811Y1086200D03*
X419611D03*
X414062Y1082995D03*
X410362D03*
X406662D03*
X408511Y1092608D03*
X414062Y1089404D03*
X419611Y1092608D03*
X412211Y1086200D03*
X404811Y1099017D03*
X408511Y1105426D03*
X412211Y1111834D03*
X415911D03*
X414062Y1102221D03*
X417762Y1108630D03*
X419611Y1105426D03*
X408511Y1099017D03*
X410362Y1108630D03*
X408511Y1111834D03*
X412211Y1105426D03*
X419611Y1111834D03*
X415911Y1105426D03*
X404811Y1124651D03*
X408511D03*
X406662Y1127856D03*
X410362Y1121447D03*
X414062Y1115039D03*
X406661Y1140973D03*
X410362Y1134264D03*
X404812Y1137469D03*
X408512D03*
X421027Y844971D03*
X424727D03*
X428427D03*
X433978Y848176D03*
X435829Y844671D03*
X422879Y841467D03*
X426578Y848176D03*
X430278D03*
Y867401D03*
X422878D03*
Y854584D03*
X424729Y857789D03*
X430278Y854584D03*
X433979Y860993D03*
X421029Y857789D03*
X426578Y860993D03*
X428429Y857789D03*
X432129D03*
X435829D03*
X432129Y870606D03*
X426578Y873810D03*
X424729Y870606D03*
X433979Y873810D03*
X428429Y870606D03*
X421029D03*
X435829D03*
X432129Y883423D03*
X430278Y880219D03*
X424729Y883423D03*
X422878Y880219D03*
X428429Y883423D03*
X421029D03*
X435829D03*
X433978Y886627D03*
X426578D03*
X428861Y1076587D03*
X430711Y1079791D03*
X421462Y1089404D03*
X423311Y1092608D03*
X427011D03*
X430710Y1086200D03*
X425162Y1082995D03*
Y1095813D03*
X430711Y1092608D03*
X423311Y1086200D03*
X428861Y1089404D03*
X427012Y1086200D03*
X450628Y844971D03*
X446927Y844671D03*
X452479Y841467D03*
X448778Y848176D03*
X443227Y844671D03*
X437678Y848176D03*
X452478Y867401D03*
X445078D03*
X437678D03*
X437679Y854584D03*
X452478D03*
X450629Y857789D03*
X445078Y854584D03*
X443229Y857789D03*
X448779Y860993D03*
X446929Y857789D03*
X441378Y860993D03*
X448779Y873810D03*
X446929Y870606D03*
X441378Y873810D03*
X439529Y870606D03*
X450629D03*
X443229D03*
X452479Y880219D03*
X446929Y883423D03*
X445078Y880219D03*
X439529Y883423D03*
X437678Y880219D03*
X450629Y883423D03*
X443229D03*
X448778Y886627D03*
X441378D03*
X467279Y841467D03*
X463578Y848176D03*
X459879Y841467D03*
X458027Y844971D03*
X454327D03*
X469127D03*
X465427D03*
X461727D03*
X456178Y848176D03*
X467278Y867401D03*
X459878D03*
X467278Y854584D03*
X465429Y857789D03*
X459878Y854584D03*
X458029Y857789D03*
X469129D03*
X463578Y860993D03*
X461729Y857789D03*
X456178Y860993D03*
X454329Y857789D03*
X469129Y870606D03*
X463578Y873810D03*
X461729Y870606D03*
X456178Y873810D03*
X454329Y870606D03*
X465429D03*
X458029D03*
X469129Y883423D03*
X467278Y880219D03*
X461729Y883423D03*
X459878Y880219D03*
X454329Y883423D03*
X465429D03*
X458029D03*
X463578Y886627D03*
X456178D03*
X483927Y844971D03*
X480227D03*
X476527D03*
X470978Y848176D03*
X482079Y841467D03*
X478378Y848176D03*
X474679Y841467D03*
X472827Y844971D03*
X474678Y867401D03*
X482078D03*
Y854584D03*
X480229Y857789D03*
X474678Y854584D03*
X472829Y857789D03*
X483929D03*
X478378Y860993D03*
X476529Y857789D03*
X470978Y860993D03*
X480229Y870606D03*
X476529D03*
X478378Y873810D03*
X483929Y870606D03*
X474678Y880219D03*
X476529Y883423D03*
X482078Y880219D03*
X483929Y883423D03*
X472829D03*
X480229D03*
X482078Y893036D03*
X483929Y896240D03*
X470978Y886627D03*
X478378D03*
X483929Y915466D03*
Y934691D03*
Y953917D03*
Y973143D03*
X484362Y1006093D03*
Y1025318D03*
Y1044544D03*
Y1063770D03*
Y1082995D03*
Y1121447D03*
X480662Y1127856D03*
X476962Y1121447D03*
X473262Y1127856D03*
X469562Y1121447D03*
X482511Y1124651D03*
X478811D03*
X475111D03*
X471411D03*
X484362Y1134264D03*
X482512Y1137469D03*
X476962Y1134264D03*
X475112Y1137469D03*
X480661Y1140973D03*
X478812Y1137469D03*
X473261Y1140973D03*
X493178Y848176D03*
X489478Y841467D03*
X487627Y844971D03*
X500578Y848176D03*
X496878Y841467D03*
X495027Y844971D03*
X491327D03*
X485778Y848176D03*
X498727Y844971D03*
X489478Y867401D03*
X496878D03*
X489478Y854584D03*
X487629Y857789D03*
X500578Y860993D03*
X498729Y857789D03*
X495029D03*
X491329D03*
X485778Y860993D03*
X496878Y854584D03*
X493178Y860993D03*
X487629Y870606D03*
X495029D03*
X485778Y873810D03*
X491329Y870606D03*
X493178Y873810D03*
X498729Y870606D03*
X500578Y873810D03*
X489478Y880219D03*
X491329Y883423D03*
X496878Y880219D03*
X498729Y883423D03*
X487629D03*
X495029D03*
X500578Y899445D03*
X485778D03*
X493178D03*
Y893036D03*
X496878D03*
X485778D03*
X491329Y896240D03*
X487629D03*
X495029D03*
X485778Y886627D03*
X493178D03*
X500578D03*
X485778Y912262D03*
X487629Y909057D03*
X493178Y912262D03*
X491329Y909057D03*
X500578Y912262D03*
X498729Y909057D03*
Y902649D03*
X487629D03*
X491329D03*
X487629Y915466D03*
X500578Y905853D03*
X495029Y915466D03*
X496878Y905853D03*
X491329Y915466D03*
X500578Y931488D03*
X498729Y921875D03*
X500578Y918670D03*
X498729Y928283D03*
X496878Y925079D03*
X500578D03*
X491329Y921875D03*
X493178Y918670D03*
X485778Y931488D03*
X491329Y928283D03*
X493178Y931488D03*
X487629Y928283D03*
Y921875D03*
X485778Y918670D03*
X498729Y947509D03*
Y941100D03*
X500578Y937896D03*
X496878Y944304D03*
X500578D03*
X487629Y947509D03*
X491329D03*
X487629Y941100D03*
X485778Y937896D03*
X491329Y941100D03*
X493178Y937896D03*
X487629Y934691D03*
X495029D03*
X491329D03*
X500578Y950713D03*
X487629Y966735D03*
X491329D03*
X498729D03*
X496878Y963530D03*
X485778Y950713D03*
X493178D03*
X491329Y960326D03*
X493178Y957122D03*
X487629Y960326D03*
X485778Y957122D03*
X500578D03*
X498729Y960326D03*
X495029Y953917D03*
X487629D03*
X491329D03*
X487629Y979552D03*
X485778Y976347D03*
X491329Y979552D03*
X493178Y976347D03*
X500578Y982756D03*
X496878D03*
X498729Y979552D03*
X500578Y976347D03*
X495029Y973143D03*
X487629D03*
X491329D03*
X485778Y969939D03*
X493178D03*
X500578D03*
X501011Y1002888D03*
X499162Y999684D03*
Y1012501D03*
X501011Y1009297D03*
X495462Y1006093D03*
X486211Y1002888D03*
X493611D03*
X488062Y999684D03*
X491762D03*
X491761Y1012501D03*
X493611Y1009297D03*
X488062Y1012501D03*
X486211Y1009297D03*
X497311Y1015705D03*
X499162Y1031727D03*
X501011Y1028523D03*
Y1022114D03*
X499162Y1018910D03*
X488062Y1031727D03*
X486211Y1028523D03*
X491762Y1031727D03*
X493611Y1028523D03*
X486211Y1022114D03*
X488062Y1018910D03*
X493611Y1022114D03*
X491762Y1018910D03*
X488062Y1025318D03*
X495462D03*
X491762D03*
X501011Y1041340D03*
X499162Y1038136D03*
X501011Y1047749D03*
Y1034931D03*
X497311D03*
X486211Y1047749D03*
X493611D03*
X486211Y1041340D03*
X488062Y1038136D03*
X493611Y1041340D03*
X491762Y1038136D03*
X488062Y1044544D03*
X495462D03*
X491762D03*
X501011Y1060565D03*
X499162Y1057361D03*
Y1050952D03*
X501011Y1054157D03*
X497311D03*
X486211Y1060565D03*
X488062Y1057361D03*
X493611Y1060565D03*
X491762Y1057361D03*
X488062Y1050952D03*
X491762D03*
X488062Y1063770D03*
X495462D03*
X491762D03*
X499162Y1070178D03*
X501011Y1066974D03*
Y1079791D03*
X499162Y1076587D03*
X497311Y1073383D03*
X501011D03*
X486211Y1079791D03*
X488062Y1076587D03*
X493611Y1079791D03*
X491762Y1076587D03*
X488062Y1070178D03*
X486211Y1066974D03*
X491762Y1070178D03*
X493611Y1066974D03*
X491762Y1089404D03*
X493611Y1086200D03*
X499162Y1089404D03*
X501011Y1086200D03*
X488062Y1089404D03*
X486211Y1086200D03*
X497311Y1092608D03*
X495462Y1082995D03*
X501011Y1092608D03*
X488062Y1082995D03*
X491762D03*
X488062Y1127856D03*
X499162Y1121447D03*
X495462Y1127856D03*
X491762Y1121447D03*
X489911Y1124651D03*
X486211D03*
X501011D03*
X497311D03*
X493611D03*
X493612Y1137469D03*
X488061Y1140973D03*
X501012Y1137469D03*
X495461Y1140973D03*
X491762Y1134264D03*
X489912Y1137469D03*
X486212D03*
X499162Y1134264D03*
X497312Y1137469D03*
X517227Y844971D03*
X511679Y841467D03*
X509827Y844971D03*
X504279Y841467D03*
X515378Y848176D03*
X513527Y844971D03*
X507978Y848176D03*
X506127Y844971D03*
X502427D03*
X511678Y867401D03*
X504278D03*
X517229Y857789D03*
X513529D03*
X509829D03*
X506129D03*
X515378Y860993D03*
X511678Y854584D03*
X507978Y860993D03*
X504278Y854584D03*
X502429Y857789D03*
X517229Y870606D03*
X502429D03*
X509829D03*
X513529D03*
X515378Y873810D03*
X506129Y870606D03*
X507978Y873810D03*
X511678Y880219D03*
X513529Y883423D03*
X504278Y880219D03*
X506129Y883423D03*
X509829D03*
X517229D03*
X502429D03*
X511678Y899445D03*
Y893036D03*
X507978D03*
X509829Y896240D03*
X517229D03*
X513529D03*
X504278Y899445D03*
X515378Y886627D03*
X507978D03*
X513529Y902649D03*
X517229D03*
X511678Y912262D03*
X513529Y909057D03*
X517229D03*
X513529Y915466D03*
X509829D03*
X517229D03*
X504278Y912262D03*
X506129Y909057D03*
Y902649D03*
X507978Y905853D03*
X504278D03*
X511678Y931488D03*
X513529Y928283D03*
X517229D03*
X506129D03*
Y921875D03*
X504278Y918670D03*
X513529Y921875D03*
X511678Y918670D03*
X517229Y921875D03*
X504278Y931488D03*
Y925079D03*
X507978D03*
X513529Y941100D03*
X511678Y937896D03*
X517229Y941100D03*
X513529Y934691D03*
X509829D03*
X517229D03*
X513529Y947509D03*
X517229D03*
X506129D03*
Y941100D03*
X504278Y937896D03*
X507978Y944304D03*
X504278D03*
X511678Y950713D03*
X513529Y960326D03*
X511678Y957122D03*
X517229Y960326D03*
Y966735D03*
X513529D03*
X504278Y950713D03*
X513529Y953917D03*
X517229D03*
X509829D03*
X506129Y966735D03*
X504278Y957122D03*
X506129Y960326D03*
X507978Y963530D03*
Y982756D03*
X504278D03*
Y976347D03*
X506129Y979552D03*
X513529D03*
X517229D03*
X511678Y976347D03*
X509829Y973143D03*
X511678Y969939D03*
X504278D03*
X517662Y1006093D03*
X513962D03*
X510262D03*
X517662Y1012501D03*
X504711Y1002888D03*
X506561Y999684D03*
X513962Y1012501D03*
X512111Y1009297D03*
X506562Y1012501D03*
X504711Y1009297D03*
X517661Y999684D03*
X512111Y1002888D03*
X513962Y999684D03*
Y1031727D03*
X512111Y1028523D03*
X517662Y1031727D03*
X512111Y1022114D03*
X513962Y1018910D03*
X517662D03*
X513962Y1025318D03*
X510262D03*
X517662D03*
X508411Y1015705D03*
X506562Y1031727D03*
X504711Y1028523D03*
Y1022114D03*
X506562Y1018910D03*
X504711Y1041340D03*
X506562Y1038136D03*
X512111Y1047749D03*
Y1041340D03*
X513962Y1038136D03*
X517662D03*
X504711Y1047749D03*
X510262Y1044544D03*
X508411Y1034931D03*
X513962Y1044544D03*
X517662D03*
X504711Y1034931D03*
X512111Y1060565D03*
X513962Y1057361D03*
X517662D03*
X510262Y1063770D03*
X513962D03*
X517662D03*
X513962Y1050952D03*
X517662D03*
X504711Y1060565D03*
X506562Y1057361D03*
Y1050952D03*
X508411Y1054157D03*
X504711D03*
X517662Y1070178D03*
X513962D03*
X512111Y1066974D03*
X504711Y1079791D03*
X506562Y1076587D03*
Y1070178D03*
X504711Y1066974D03*
X512111Y1079791D03*
X513962Y1076587D03*
X517662D03*
X508411Y1073383D03*
X504711D03*
X513962Y1089404D03*
X512111Y1086200D03*
X517662Y1089404D03*
X513962Y1082995D03*
X510262D03*
X517662D03*
X510262Y1095813D03*
X506561D03*
X506562Y1089404D03*
X504711Y1086200D03*
X508411Y1092608D03*
X504711D03*
X517662Y1102221D03*
X515811Y1099017D03*
X517662Y1127856D03*
X513962Y1121447D03*
X510262Y1127856D03*
X506562Y1121447D03*
X502862Y1127856D03*
X515811Y1124651D03*
X512111D03*
X508411D03*
X504711D03*
X517661Y1140973D03*
X513962Y1134264D03*
X512112Y1137469D03*
X506562Y1134264D03*
X504712Y1137469D03*
X515812D03*
X510261Y1140973D03*
X508412Y1137469D03*
X502861Y1140973D03*
X532028Y844671D03*
X526478Y848176D03*
X524627Y844971D03*
X519079Y841467D03*
X533878Y848176D03*
X530178D03*
X522778D03*
X520927Y844971D03*
X532029Y864197D03*
X533879Y854584D03*
X519078Y867401D03*
X526479D03*
X528329Y857789D03*
X522778Y860993D03*
X520929Y857789D03*
X526478Y854584D03*
X524629Y857789D03*
X519078Y854584D03*
X524629Y870606D03*
X532029D03*
X520929D03*
X522778Y873810D03*
X528329Y870606D03*
X530178Y873810D03*
X519078Y880219D03*
X520929Y883423D03*
X526479Y880219D03*
X528329Y883423D03*
X524629D03*
X526479Y899445D03*
X530178D03*
X519078D03*
Y893036D03*
X522778D03*
X520929Y896240D03*
X522778Y886627D03*
X530179D03*
Y912262D03*
X532029Y909057D03*
X524629Y902649D03*
X532029D03*
X526479Y912262D03*
X524629Y909057D03*
X526479Y905853D03*
X533879D03*
X522778D03*
X530179D03*
X519078Y912262D03*
X520929Y915466D03*
X526479Y931488D03*
X524629Y928283D03*
X530179Y931488D03*
X532029Y928283D03*
X524629Y921875D03*
X526479Y918670D03*
X532029Y921875D03*
X530179Y918670D03*
X526479Y925079D03*
X533879D03*
X522778D03*
X530179D03*
X519078Y931488D03*
Y918670D03*
X524629Y941100D03*
X526479Y937896D03*
X532029Y941100D03*
X530179Y937896D03*
X524629Y947509D03*
X532029D03*
X519078Y937896D03*
X533879Y944304D03*
X520929Y934691D03*
X526479Y944304D03*
X530178D03*
X522778D03*
X524629Y966735D03*
X532029D03*
X522778Y963530D03*
X526479Y950713D03*
X530178D03*
X532029Y960326D03*
X530178Y957122D03*
X524629Y960326D03*
X526479Y957122D03*
X533879Y963530D03*
X519078Y950713D03*
Y957122D03*
X520929Y953917D03*
X526479Y969939D03*
X530179D03*
X519078Y976347D03*
Y969939D03*
X520929Y973143D03*
X521362Y1006093D03*
X525062Y1012501D03*
X532461D03*
X526911Y1009297D03*
X530611D03*
X519511D03*
X519513Y1002888D03*
X530611D03*
X532461Y999684D03*
X526911Y1002888D03*
X525062Y999684D03*
X523211Y1015705D03*
X534311D03*
X525062Y1031727D03*
X526911Y1028523D03*
X532461Y1031727D03*
X530611Y1028523D03*
Y1022114D03*
X532461Y1018910D03*
X526911Y1022114D03*
X525062Y1018910D03*
X519511Y1028523D03*
Y1022114D03*
X521362Y1025318D03*
X526911Y1041340D03*
X525062Y1038136D03*
X530611Y1041340D03*
X532461Y1038136D03*
X526911Y1047749D03*
X530611D03*
X526911Y1034931D03*
X534311D03*
X523211D03*
X530611D03*
X519511Y1047749D03*
Y1041340D03*
X521362Y1044544D03*
X519511Y1060565D03*
X526911D03*
X525062Y1057361D03*
X530611Y1060565D03*
X532462Y1057361D03*
X525061Y1050952D03*
X532462Y1050953D03*
X523211Y1054157D03*
X521362Y1063770D03*
X534311Y1054157D03*
X526911D03*
X530611D03*
Y1079791D03*
X532462Y1076587D03*
X525062Y1070178D03*
X526911Y1066974D03*
X532462Y1070178D03*
X530611Y1066974D03*
X526911Y1079791D03*
X525062Y1076587D03*
X523211Y1073383D03*
X534311D03*
X526911D03*
X530611D03*
X519511Y1066974D03*
Y1079791D03*
X521362Y1095813D03*
X532461D03*
X525062D03*
Y1089404D03*
X526911Y1086200D03*
X532462Y1089404D03*
X530611Y1086200D03*
X526911Y1092608D03*
X534310D03*
X523211D03*
X530611D03*
X519511Y1086200D03*
X521362Y1082995D03*
X530611Y1099017D03*
X526911Y1124651D03*
X521362Y1121447D03*
X525062Y1127856D03*
X523211Y1124651D03*
X519511D03*
X532462Y1134264D03*
X525061Y1140973D03*
X523212Y1137469D03*
X534312D03*
X526912D03*
X521362Y1134264D03*
X519512Y1137469D03*
X543129Y851380D03*
X539429D03*
X535729Y864197D03*
X543128D03*
X546828D03*
X535729Y857789D03*
X543130D03*
X539429D03*
X541279Y860993D03*
Y854584D03*
X539429Y883423D03*
X537578Y880219D03*
X543129Y883423D03*
X544979Y880219D03*
X537578Y873810D03*
X539429Y870606D03*
X544979Y873810D03*
X543129Y870606D03*
X539428Y877014D03*
X546828D03*
X535729D03*
X543129D03*
X620799Y883924D03*
Y890617D03*
Y897310D03*
Y900656D03*
Y914042D03*
Y907349D03*
Y960892D03*
Y957546D03*
Y1185105D03*
Y1178412D03*
Y1191798D03*
Y1208530D03*
Y1201837D03*
Y1195144D03*
X636941Y880577D03*
Y887270D03*
Y897310D03*
Y893963D03*
Y910696D03*
Y904003D03*
Y1175066D03*
Y1181759D03*
Y1191798D03*
Y1188451D03*
Y1205184D03*
Y1198491D03*
X650499Y960892D03*
Y957546D03*
X680299Y780184D03*
Y773491D03*
Y786877D03*
Y803609D03*
Y796916D03*
Y790223D03*
Y816995D03*
Y810302D03*
Y833727D03*
Y823688D03*
Y827034D03*
Y847113D03*
Y840420D03*
Y853806D03*
Y860499D03*
Y863845D03*
Y883924D03*
Y877231D03*
Y870538D03*
Y890617D03*
Y897310D03*
Y900656D03*
Y914042D03*
Y907349D03*
Y927428D03*
Y920735D03*
Y934121D03*
Y944160D03*
Y937467D03*
Y960892D03*
Y950853D03*
Y957546D03*
Y980971D03*
Y974278D03*
Y967585D03*
Y994357D03*
Y987664D03*
X679999Y1027822D03*
X680299Y1021129D03*
X679999Y1047900D03*
Y1041207D03*
Y1034514D03*
Y1054593D03*
X680299Y1074672D03*
Y1067979D03*
Y1091404D03*
Y1081365D03*
Y1084711D03*
Y1098097D03*
Y1111483D03*
Y1104790D03*
Y1128215D03*
Y1118176D03*
Y1121522D03*
Y1141601D03*
Y1134908D03*
Y1148294D03*
Y1154987D03*
Y1158333D03*
Y1171719D03*
Y1165026D03*
Y1185105D03*
Y1178412D03*
Y1191798D03*
Y1208530D03*
Y1201837D03*
Y1195144D03*
Y1221916D03*
Y1215223D03*
Y1238648D03*
Y1228609D03*
Y1231955D03*
Y1245341D03*
X696441Y770144D03*
Y776837D03*
Y786877D03*
Y783530D03*
Y800263D03*
Y793570D03*
Y813648D03*
Y806955D03*
Y820341D03*
Y830381D03*
Y823688D03*
Y850459D03*
Y843766D03*
Y837074D03*
Y867192D03*
Y860499D03*
Y857152D03*
Y873885D03*
Y880577D03*
Y887270D03*
Y897310D03*
Y893963D03*
Y917389D03*
Y910696D03*
Y904003D03*
Y924081D03*
Y934121D03*
Y930774D03*
Y947507D03*
Y940814D03*
Y964239D03*
Y977625D03*
Y970932D03*
Y991011D03*
Y984318D03*
Y1021129D03*
Y1024475D03*
Y1031168D03*
X696141Y1044554D03*
Y1037861D03*
X696441Y1051247D03*
Y1071325D03*
Y1064633D03*
Y1078018D03*
Y1094751D03*
Y1088058D03*
Y1081365D03*
Y1108136D03*
Y1101444D03*
Y1124869D03*
Y1118176D03*
Y1114829D03*
Y1144947D03*
Y1138255D03*
Y1131562D03*
Y1161680D03*
Y1154987D03*
Y1151640D03*
Y1175066D03*
Y1168373D03*
Y1181758D03*
Y1191798D03*
Y1188451D03*
Y1205184D03*
Y1198491D03*
Y1218569D03*
Y1211877D03*
Y1225262D03*
Y1241995D03*
Y1235302D03*
Y1228609D03*
X709899Y960892D03*
Y957546D03*
X709999Y967585D03*
Y1054593D03*
X726141Y964239D03*
Y1021129D03*
Y1024475D03*
Y1051247D03*
X739699Y780184D03*
Y773491D03*
Y786877D03*
Y803609D03*
Y796916D03*
Y790223D03*
Y816995D03*
Y810302D03*
Y833727D03*
Y823688D03*
Y827034D03*
Y847113D03*
Y840420D03*
Y853806D03*
Y860499D03*
Y863845D03*
Y883924D03*
Y877231D03*
Y870538D03*
Y890617D03*
Y897310D03*
Y900656D03*
Y914042D03*
Y907349D03*
Y927428D03*
Y920735D03*
Y934121D03*
Y944160D03*
Y937467D03*
Y960892D03*
Y950853D03*
Y957546D03*
Y980971D03*
Y974278D03*
Y967585D03*
Y994357D03*
Y987664D03*
Y1027822D03*
Y1021129D03*
Y1047900D03*
Y1041207D03*
Y1034514D03*
Y1054593D03*
Y1074672D03*
Y1067979D03*
Y1091404D03*
Y1081365D03*
Y1084711D03*
Y1098097D03*
Y1111483D03*
Y1104790D03*
Y1128215D03*
Y1118176D03*
Y1121522D03*
Y1141601D03*
Y1134908D03*
Y1148294D03*
Y1154987D03*
Y1158333D03*
Y1171719D03*
Y1165026D03*
Y1185105D03*
Y1178412D03*
Y1191798D03*
Y1208530D03*
Y1201837D03*
Y1195144D03*
Y1221916D03*
Y1215223D03*
Y1238648D03*
Y1228609D03*
Y1231955D03*
Y1245341D03*
X755841Y770144D03*
Y776837D03*
Y786877D03*
Y783530D03*
Y800263D03*
Y793570D03*
Y813648D03*
Y806955D03*
Y820341D03*
Y830381D03*
Y823688D03*
Y850459D03*
Y843766D03*
Y837074D03*
Y867192D03*
Y860499D03*
Y857152D03*
Y873885D03*
Y880577D03*
Y887270D03*
Y897310D03*
Y893963D03*
Y917389D03*
Y910696D03*
Y904003D03*
Y924081D03*
Y934121D03*
Y930774D03*
Y947507D03*
Y940814D03*
Y964239D03*
Y977625D03*
X755741Y970932D03*
X755841Y991011D03*
Y984318D03*
Y1021129D03*
Y1024475D03*
Y1031168D03*
X755541Y1044554D03*
Y1037861D03*
X755841Y1051247D03*
X755676Y1071326D03*
X755741Y1064633D03*
X755841Y1078018D03*
Y1094751D03*
Y1088058D03*
Y1081365D03*
X755676Y1108137D03*
X755841Y1101444D03*
Y1124869D03*
Y1118176D03*
Y1114829D03*
Y1144947D03*
Y1138255D03*
Y1131562D03*
Y1161680D03*
Y1154987D03*
Y1151640D03*
Y1175066D03*
Y1168373D03*
X755676Y1181759D03*
X755841Y1191798D03*
X755676Y1188452D03*
X755841Y1205184D03*
Y1198491D03*
Y1218569D03*
Y1211877D03*
Y1225262D03*
Y1241995D03*
Y1235302D03*
Y1228609D03*
X769399Y960892D03*
Y957546D03*
Y967585D03*
Y1054593D03*
X785541Y964239D03*
Y1021129D03*
Y1024475D03*
Y1051247D03*
X799099Y780184D03*
Y773491D03*
Y786877D03*
Y803609D03*
Y796916D03*
Y790223D03*
Y816995D03*
Y810302D03*
Y833727D03*
Y823688D03*
Y827034D03*
Y847113D03*
Y840420D03*
Y853806D03*
Y860499D03*
Y863845D03*
Y883924D03*
Y877231D03*
Y870538D03*
Y890617D03*
Y897310D03*
Y900656D03*
Y914042D03*
Y907349D03*
Y927428D03*
Y920735D03*
Y934121D03*
Y944160D03*
Y937467D03*
Y960892D03*
Y950853D03*
Y957546D03*
Y980971D03*
Y974278D03*
Y967585D03*
Y994357D03*
Y987664D03*
Y1027822D03*
Y1021129D03*
Y1047900D03*
Y1041207D03*
Y1034515D03*
Y1054593D03*
Y1074672D03*
Y1067979D03*
Y1091404D03*
Y1081365D03*
Y1084711D03*
Y1098097D03*
Y1111483D03*
Y1104790D03*
Y1128215D03*
Y1118176D03*
Y1121522D03*
Y1141601D03*
Y1134908D03*
Y1148294D03*
Y1154987D03*
Y1158333D03*
Y1171719D03*
Y1165026D03*
Y1185105D03*
Y1178412D03*
Y1191798D03*
Y1208530D03*
Y1201837D03*
Y1195144D03*
Y1221916D03*
Y1215223D03*
Y1238648D03*
Y1228609D03*
Y1231955D03*
Y1245341D03*
X815241Y770144D03*
Y776837D03*
Y786877D03*
Y783530D03*
Y800263D03*
Y793570D03*
Y813648D03*
Y806955D03*
Y820341D03*
Y830381D03*
Y823688D03*
Y850459D03*
Y843766D03*
Y837074D03*
Y867192D03*
Y860499D03*
Y857152D03*
Y873885D03*
Y880577D03*
Y887270D03*
Y897310D03*
Y893963D03*
Y917389D03*
Y910696D03*
Y904003D03*
Y924081D03*
Y934121D03*
Y930774D03*
Y947507D03*
Y940814D03*
Y964239D03*
Y977625D03*
Y970932D03*
Y991011D03*
Y984318D03*
Y1021129D03*
Y1024475D03*
Y1031168D03*
Y1044554D03*
Y1037861D03*
X814941Y1051247D03*
X815241Y1071325D03*
Y1064633D03*
Y1078018D03*
Y1094751D03*
Y1088058D03*
Y1081365D03*
Y1108136D03*
Y1101444D03*
Y1124869D03*
Y1118176D03*
Y1114829D03*
Y1144947D03*
Y1138255D03*
Y1131562D03*
Y1161680D03*
Y1154987D03*
Y1151640D03*
Y1175066D03*
Y1168373D03*
Y1181758D03*
Y1191798D03*
Y1188451D03*
Y1205184D03*
Y1198491D03*
Y1218570D03*
Y1211877D03*
Y1225263D03*
Y1241995D03*
Y1235302D03*
Y1228609D03*
X828799Y960892D03*
Y957546D03*
Y967585D03*
Y1054593D03*
X844941Y964239D03*
Y1021129D03*
Y1024475D03*
Y1051247D03*
X1012541Y960892D03*
Y957546D03*
Y967585D03*
Y1054593D03*
X1028683Y964239D03*
Y1021129D03*
Y1024475D03*
Y1051247D03*
X1042241Y780184D03*
Y773491D03*
Y786877D03*
Y803609D03*
Y796916D03*
Y790223D03*
Y816995D03*
Y810302D03*
Y833727D03*
Y823688D03*
Y827034D03*
Y847113D03*
Y840420D03*
Y853806D03*
Y860499D03*
Y863845D03*
Y883924D03*
Y877231D03*
Y870538D03*
Y890617D03*
Y897310D03*
Y900656D03*
Y914042D03*
Y907349D03*
Y927428D03*
Y920735D03*
Y934121D03*
Y944160D03*
Y937467D03*
Y960892D03*
Y950853D03*
Y957546D03*
Y980971D03*
Y974278D03*
Y967585D03*
Y994357D03*
Y987664D03*
Y1027822D03*
Y1021129D03*
Y1047900D03*
Y1041207D03*
Y1034515D03*
Y1054593D03*
Y1074672D03*
Y1067979D03*
Y1091404D03*
Y1081365D03*
Y1084711D03*
Y1098097D03*
Y1111483D03*
Y1104790D03*
Y1128215D03*
Y1118176D03*
Y1121522D03*
Y1141601D03*
Y1134908D03*
Y1148294D03*
Y1154987D03*
Y1158333D03*
Y1171719D03*
Y1165026D03*
Y1185105D03*
Y1178412D03*
Y1191798D03*
Y1208530D03*
Y1201837D03*
Y1195144D03*
Y1221916D03*
Y1215223D03*
Y1238648D03*
Y1228609D03*
Y1231955D03*
Y1245341D03*
X1058383Y770144D03*
Y776837D03*
Y786877D03*
Y783530D03*
Y800263D03*
Y793570D03*
Y813648D03*
Y806955D03*
Y820341D03*
Y830381D03*
Y823688D03*
Y850459D03*
Y843766D03*
Y837074D03*
Y867192D03*
Y860499D03*
Y857152D03*
Y873885D03*
Y880577D03*
Y887270D03*
Y897310D03*
Y893963D03*
Y917389D03*
Y910696D03*
Y904003D03*
Y924081D03*
Y934121D03*
Y930774D03*
Y947507D03*
Y940814D03*
Y964239D03*
Y977625D03*
Y970932D03*
Y991011D03*
Y984318D03*
Y1021129D03*
Y1024475D03*
Y1031168D03*
Y1044554D03*
Y1037861D03*
Y1051247D03*
Y1071326D03*
Y1064633D03*
Y1078018D03*
Y1094751D03*
Y1088058D03*
Y1081365D03*
Y1108137D03*
Y1101444D03*
Y1124869D03*
Y1118176D03*
Y1114829D03*
Y1144948D03*
Y1138255D03*
Y1131562D03*
Y1161680D03*
Y1154987D03*
Y1151641D03*
Y1175066D03*
Y1168373D03*
Y1181759D03*
Y1191798D03*
Y1188452D03*
Y1205184D03*
Y1198491D03*
Y1218570D03*
Y1211877D03*
Y1225263D03*
Y1241995D03*
Y1235302D03*
Y1228609D03*
X1071941Y960892D03*
Y957546D03*
Y967585D03*
Y1054593D03*
X1101641Y780184D03*
Y773491D03*
Y786877D03*
Y803609D03*
Y796916D03*
Y790223D03*
Y816995D03*
Y810302D03*
Y833727D03*
Y823688D03*
Y827034D03*
Y847113D03*
Y840420D03*
Y853806D03*
Y860499D03*
Y863845D03*
Y883924D03*
Y877231D03*
Y870538D03*
Y890617D03*
Y897310D03*
Y900656D03*
Y914042D03*
Y907349D03*
Y927428D03*
Y920735D03*
Y934121D03*
Y944160D03*
Y937467D03*
Y960892D03*
Y950853D03*
X1088083Y964239D03*
X1101641Y957546D03*
Y980971D03*
Y974278D03*
Y967585D03*
Y994357D03*
Y987664D03*
X1088083Y1021129D03*
Y1024475D03*
X1101641Y1027822D03*
Y1021129D03*
Y1047900D03*
Y1041207D03*
Y1034515D03*
X1088083Y1051247D03*
X1101641Y1054593D03*
Y1074672D03*
Y1067979D03*
Y1091404D03*
Y1081365D03*
Y1084711D03*
Y1098097D03*
Y1111483D03*
Y1104790D03*
Y1128215D03*
Y1118176D03*
Y1121522D03*
Y1141601D03*
Y1134908D03*
Y1148294D03*
Y1154987D03*
Y1158333D03*
Y1171719D03*
Y1165026D03*
Y1185105D03*
Y1178412D03*
Y1191798D03*
Y1208530D03*
Y1201837D03*
Y1195144D03*
Y1221916D03*
Y1215223D03*
Y1238648D03*
Y1228609D03*
Y1231955D03*
Y1245341D03*
X1117783Y770144D03*
Y776837D03*
Y786877D03*
Y783530D03*
Y800263D03*
Y793570D03*
Y813648D03*
Y806955D03*
Y820341D03*
Y830381D03*
Y823688D03*
Y850459D03*
Y843766D03*
Y837074D03*
Y867192D03*
Y860499D03*
Y857152D03*
Y873885D03*
Y880577D03*
Y887270D03*
Y897310D03*
Y893963D03*
Y917389D03*
Y910696D03*
Y904003D03*
Y924081D03*
Y934121D03*
Y930774D03*
Y947507D03*
Y940814D03*
Y964239D03*
Y977625D03*
Y970932D03*
Y991011D03*
Y984318D03*
Y1021129D03*
Y1024475D03*
Y1031168D03*
Y1044554D03*
Y1037861D03*
Y1051247D03*
Y1071326D03*
Y1064633D03*
Y1078018D03*
Y1094751D03*
Y1088058D03*
Y1081365D03*
Y1108137D03*
Y1101444D03*
Y1124869D03*
Y1118176D03*
Y1114829D03*
Y1144948D03*
Y1138255D03*
Y1131562D03*
Y1161680D03*
Y1154987D03*
Y1151641D03*
Y1175066D03*
Y1168373D03*
Y1181759D03*
Y1191798D03*
Y1188452D03*
Y1205184D03*
Y1198491D03*
Y1218570D03*
Y1211877D03*
Y1225263D03*
Y1241995D03*
Y1235302D03*
Y1228609D03*
X1131341Y960892D03*
Y957546D03*
Y967585D03*
Y1054593D03*
X1147483Y964239D03*
Y1021129D03*
Y1024475D03*
Y1051247D03*
X1161041Y780184D03*
Y773491D03*
Y786877D03*
Y803609D03*
Y796916D03*
Y790223D03*
Y816995D03*
Y810302D03*
Y833727D03*
Y823688D03*
Y827034D03*
Y847113D03*
Y840420D03*
Y853806D03*
Y860499D03*
Y863845D03*
Y883924D03*
Y877231D03*
Y870538D03*
Y890617D03*
Y897310D03*
Y900656D03*
Y914042D03*
Y907349D03*
Y927428D03*
Y920735D03*
Y934121D03*
Y944160D03*
Y937467D03*
Y960892D03*
Y950853D03*
Y957546D03*
Y980971D03*
Y974278D03*
Y967585D03*
Y994357D03*
Y987664D03*
Y1027822D03*
Y1021129D03*
Y1047900D03*
Y1041207D03*
Y1034515D03*
Y1054593D03*
Y1074672D03*
Y1067979D03*
Y1091404D03*
Y1081365D03*
Y1084711D03*
Y1098097D03*
Y1111483D03*
Y1104790D03*
Y1128215D03*
Y1118176D03*
Y1121522D03*
Y1141601D03*
Y1134908D03*
Y1148294D03*
Y1154987D03*
Y1158333D03*
Y1171719D03*
Y1165026D03*
Y1185105D03*
Y1178412D03*
Y1191798D03*
Y1208530D03*
Y1201837D03*
Y1195144D03*
Y1221916D03*
Y1215223D03*
Y1238648D03*
Y1228609D03*
Y1231955D03*
Y1245341D03*
X1177183Y770144D03*
Y776837D03*
Y786877D03*
Y783530D03*
Y800263D03*
Y793570D03*
Y813648D03*
Y806955D03*
Y820341D03*
Y830381D03*
Y823688D03*
Y850459D03*
Y843766D03*
Y837074D03*
Y867192D03*
Y860499D03*
Y857152D03*
Y873885D03*
Y880577D03*
Y887270D03*
Y897310D03*
Y893963D03*
Y917389D03*
Y910696D03*
Y904003D03*
Y924081D03*
Y934121D03*
Y930774D03*
Y947507D03*
Y940814D03*
Y964239D03*
Y977625D03*
Y970932D03*
Y991011D03*
Y984318D03*
X1177283Y1021129D03*
Y1024475D03*
Y1031168D03*
Y1044554D03*
Y1037861D03*
Y1051247D03*
Y1071326D03*
Y1064633D03*
Y1078018D03*
Y1094752D03*
Y1088059D03*
Y1081366D03*
Y1108137D03*
Y1101444D03*
X1177183Y1124869D03*
X1177283Y1118177D03*
Y1114830D03*
Y1144948D03*
Y1138255D03*
X1177183Y1131562D03*
X1177283Y1161680D03*
Y1154988D03*
Y1151641D03*
Y1175066D03*
Y1168373D03*
Y1181759D03*
Y1191799D03*
Y1188452D03*
Y1205184D03*
Y1198491D03*
Y1218570D03*
Y1211877D03*
Y1225263D03*
X1177250Y1241995D03*
X1177283Y1235302D03*
Y1228609D03*
X1190741Y960892D03*
Y957546D03*
X1220441Y883924D03*
Y890617D03*
Y897310D03*
Y900656D03*
Y914042D03*
Y907349D03*
Y960892D03*
Y957546D03*
Y1185105D03*
Y1178412D03*
Y1191798D03*
Y1208530D03*
Y1201837D03*
Y1195144D03*
X1236583Y880577D03*
Y887270D03*
Y897310D03*
Y893963D03*
Y910696D03*
Y904003D03*
Y1175066D03*
Y1181759D03*
Y1191798D03*
Y1188452D03*
Y1205184D03*
Y1198491D03*
X1313921Y880219D03*
X1312070Y883423D03*
X1313921Y893036D03*
X1312070Y889832D03*
X1310221Y886627D03*
X1313921D03*
X1312503Y1121447D03*
X1326869Y851380D03*
X1330569Y844971D03*
X1325020Y848176D03*
X1328720D03*
X1326871Y857789D03*
X1328720Y860993D03*
X1330571Y857789D03*
X1317621Y880219D03*
X1319471Y883423D03*
X1326871Y870606D03*
X1330571D03*
X1328720Y873810D03*
X1330571Y883423D03*
X1325020Y899445D03*
Y893036D03*
X1326871Y889832D03*
X1330571D03*
X1317620Y893036D03*
X1319470Y889832D03*
X1323171Y896240D03*
X1330571D03*
X1317621Y886627D03*
X1326871Y896240D03*
X1321321Y886627D03*
X1325020Y912262D03*
X1326871Y909057D03*
X1330571D03*
X1326871Y902649D03*
X1330571D03*
X1323171Y915466D03*
X1330571D03*
X1326871D03*
X1325021Y931488D03*
X1326871Y928283D03*
X1330571D03*
Y921875D03*
X1326871D03*
X1325020Y918670D03*
X1326871Y941100D03*
X1325020Y937896D03*
X1330571Y941100D03*
X1323171Y934691D03*
X1330571D03*
X1326871D03*
Y947509D03*
X1330571D03*
X1325020Y950713D03*
X1326871Y960326D03*
X1325020Y957122D03*
X1330571Y960326D03*
X1326871Y966735D03*
X1330571D03*
X1326871Y953917D03*
X1330571D03*
X1323172D03*
X1326871Y979552D03*
X1330571D03*
X1325020Y976347D03*
X1323171Y973143D03*
X1325020Y969939D03*
X1323603Y1006093D03*
X1325453Y1002888D03*
X1327303Y999684D03*
X1331003D03*
X1327303Y1012501D03*
X1325453Y1009297D03*
X1331003Y1012501D03*
X1327304Y1031727D03*
X1325453Y1028523D03*
X1331003Y1031727D03*
X1325453Y1022114D03*
X1327303Y1018910D03*
X1331003D03*
X1323603Y1025318D03*
X1331004D03*
X1327304D03*
X1325453Y1047749D03*
Y1041340D03*
X1327303Y1038136D03*
X1331003D03*
X1323603Y1044544D03*
X1331003D03*
X1327303D03*
X1325453Y1060565D03*
X1327303Y1057361D03*
X1331003D03*
X1323603Y1063770D03*
X1327303D03*
X1331003D03*
X1327303Y1050952D03*
X1331003D03*
Y1070178D03*
X1327304D03*
X1325453Y1066974D03*
Y1079791D03*
X1327303Y1076587D03*
X1331003D03*
X1327303Y1089404D03*
X1325453Y1086200D03*
X1331003Y1089404D03*
X1323603Y1082995D03*
X1331003D03*
X1327303D03*
X1329153Y1105426D03*
X1325454Y1111834D03*
X1327303Y1102221D03*
X1321753Y1111834D03*
X1318054D03*
X1318053Y1105426D03*
X1327304Y1108630D03*
X1329154Y1111834D03*
X1331003Y1102221D03*
X1319904Y1108630D03*
X1321753Y1105426D03*
X1329153Y1124651D03*
X1331003Y1127856D03*
X1323603Y1121447D03*
X1319903Y1127856D03*
X1316203D03*
X1318054Y1118243D03*
X1321753Y1124651D03*
X1323603Y1127856D03*
X1319903Y1121447D03*
X1316203D03*
X1323603Y1115039D03*
X1325452Y1137469D03*
X1327303Y1134264D03*
X1318053Y1131060D03*
X1346137Y175949D03*
X1342937Y177799D03*
X1346137Y179649D03*
X1332421Y841467D03*
X1337969Y844971D03*
X1339821Y841467D03*
X1345369Y844971D03*
X1347221Y841467D03*
X1334269Y844971D03*
X1336120Y848176D03*
X1341669Y844971D03*
X1343520Y848176D03*
X1347220Y867401D03*
X1332420D03*
X1339820D03*
X1332420Y854584D03*
X1334271Y857789D03*
X1337971D03*
X1341671D03*
X1345371D03*
X1336120Y860993D03*
X1339820Y854584D03*
X1343520Y860993D03*
X1347220Y854584D03*
X1334271Y870606D03*
X1337971D03*
X1341671D03*
X1336120Y873810D03*
X1343520D03*
X1345371Y870606D03*
X1332420Y880219D03*
X1334271Y883423D03*
X1339820Y880219D03*
X1341671Y883423D03*
X1347220Y880219D03*
X1337971Y883423D03*
X1345371D03*
X1332420Y899445D03*
Y893036D03*
X1334271Y896240D03*
X1339820Y899445D03*
X1343520D03*
X1347220Y893036D03*
X1336120Y886627D03*
X1343520D03*
X1332420Y912262D03*
X1334271Y915466D03*
X1339820Y912262D03*
X1337971Y909057D03*
X1343520Y912262D03*
X1345371Y909057D03*
X1337971Y902649D03*
X1345371D03*
X1336120Y905853D03*
X1343520D03*
X1339820D03*
X1347220D03*
X1332420Y931488D03*
X1339820D03*
X1332420Y918670D03*
X1337971Y928283D03*
X1343520Y931488D03*
X1345371Y928283D03*
X1337971Y921875D03*
X1339820Y918670D03*
X1345371Y921875D03*
X1343520Y918670D03*
X1336120Y925079D03*
X1343520D03*
X1339820D03*
X1347220D03*
X1332420Y937896D03*
X1334271Y934691D03*
X1337971Y941100D03*
X1339820Y937896D03*
X1345371Y941100D03*
X1343520Y937896D03*
X1337971Y947509D03*
X1345371D03*
X1343520Y944304D03*
X1336120D03*
X1347220D03*
X1339820D03*
X1332420Y950713D03*
Y957122D03*
X1334271Y953917D03*
X1337971Y966735D03*
X1345371D03*
X1336120Y963530D03*
X1339820Y950713D03*
X1343520D03*
X1337971Y960326D03*
X1339820Y957122D03*
X1345371Y960326D03*
X1343520Y957122D03*
X1347220Y963530D03*
X1336120Y982756D03*
X1343520D03*
X1339820D03*
X1347220D03*
X1345371Y979552D03*
X1343520Y976347D03*
X1337971Y979552D03*
X1339820Y976347D03*
X1332420D03*
Y969939D03*
X1334271Y973143D03*
X1339820Y969939D03*
X1343520D03*
X1334704Y1006093D03*
X1332853Y1002888D03*
Y1009297D03*
X1338404Y1012501D03*
X1345804D03*
X1340253Y1009297D03*
X1343953D03*
X1340253Y1002888D03*
X1338404Y999684D03*
X1347653Y1002888D03*
X1345804Y999684D03*
X1332853Y1028523D03*
Y1022114D03*
X1338404Y1031727D03*
X1340253Y1028523D03*
X1345804Y1031727D03*
X1343953Y1028523D03*
X1334704Y1025318D03*
X1336553Y1015705D03*
X1347653D03*
X1340253Y1022114D03*
X1338404Y1018910D03*
X1343953Y1022114D03*
X1345804Y1018910D03*
X1332853Y1047749D03*
Y1041340D03*
X1340253D03*
X1338404Y1038136D03*
X1343953Y1041340D03*
X1345804Y1038136D03*
X1336553Y1034931D03*
X1347653D03*
X1340253D03*
X1334704Y1044544D03*
X1343953Y1034931D03*
X1340253Y1047749D03*
X1343953D03*
X1332853Y1060565D03*
X1334704Y1063770D03*
X1340253Y1060565D03*
X1338404Y1057361D03*
X1343953Y1060565D03*
X1345804Y1057361D03*
X1338404Y1050952D03*
X1345804D03*
X1336553Y1054157D03*
X1347653D03*
X1340253D03*
X1343953D03*
X1332853Y1066974D03*
X1343953Y1079791D03*
X1345804Y1076587D03*
X1338404Y1070178D03*
X1340253Y1066974D03*
X1345804Y1070178D03*
X1343953Y1066974D03*
X1332853Y1079791D03*
X1340253D03*
X1338404Y1076587D03*
X1336553Y1073383D03*
X1347653D03*
X1340253D03*
X1343953D03*
X1332853Y1086200D03*
X1334704Y1082995D03*
X1338404Y1095813D03*
X1345804D03*
X1338404Y1089404D03*
X1340253Y1086200D03*
X1345804Y1089404D03*
X1343953Y1086200D03*
X1336553Y1092608D03*
X1343953D03*
X1340253D03*
X1347653D03*
X1340253Y1099017D03*
X1343953D03*
X1345803Y1108630D03*
X1340254Y1105426D03*
X1336554Y1111834D03*
X1334703Y1108630D03*
X1343954Y1111834D03*
X1342103Y1108630D03*
X1338403D03*
X1334703Y1121447D03*
X1336554Y1124651D03*
X1340253D03*
X1343953D03*
X1347653D03*
X1332854D03*
X1338404Y1127856D03*
X1342104Y1121447D03*
X1345804Y1127856D03*
X1342103Y1115039D03*
X1345803D03*
X1334703D03*
Y1134264D03*
X1338403Y1140973D03*
X1342104Y1134264D03*
X1345803Y1140973D03*
X1332854Y1137469D03*
X1336554D03*
X1340254D03*
X1343954D03*
X1347654D03*
X1352557Y168548D03*
X1355762Y166698D03*
X1352557Y172248D03*
X1349351Y177798D03*
Y170398D03*
Y174098D03*
X1352557Y175948D03*
X1349351Y181498D03*
X1355761Y185198D03*
X1349351D03*
X1355761Y174098D03*
Y181498D03*
X1352557Y183348D03*
X1352561Y198148D03*
X1355771Y196298D03*
X1355765Y199999D03*
Y203699D03*
X1363869Y844971D03*
X1352769D03*
X1356469D03*
X1360169D03*
X1362021Y841467D03*
X1349069Y844971D03*
X1350920Y848176D03*
X1354621Y841467D03*
X1358320Y848176D03*
X1354620Y867401D03*
X1362020D03*
X1349071Y857789D03*
X1354620Y854584D03*
X1356471Y857789D03*
X1360171D03*
X1363871D03*
X1350920Y860993D03*
X1352771Y857789D03*
X1358320Y860993D03*
X1362020Y854584D03*
X1363871Y870606D03*
X1349071D03*
X1356471D03*
X1350920Y873810D03*
X1352771Y870606D03*
X1358320Y873810D03*
X1360171Y870606D03*
X1349071Y883423D03*
X1354620Y880219D03*
X1356471Y883423D03*
X1362020Y880219D03*
X1363871Y883423D03*
X1352771D03*
X1360171D03*
X1350920Y899445D03*
X1358320D03*
Y893036D03*
X1350920D03*
X1362020D03*
X1349071Y896240D03*
X1356471D03*
X1352771D03*
X1360171D03*
X1350920Y886627D03*
X1358320D03*
X1352771Y902649D03*
X1356471D03*
X1350920Y912262D03*
X1352771Y909057D03*
X1358320Y912262D03*
X1356471Y909057D03*
X1363871D03*
Y902649D03*
X1349071Y915466D03*
X1362020Y905853D03*
X1356471Y915466D03*
X1352771D03*
X1360171D03*
X1350920Y931488D03*
X1352771Y928283D03*
X1358320Y931488D03*
X1356471Y928283D03*
X1363871Y921875D03*
X1352771D03*
X1350920Y918670D03*
X1356471Y921875D03*
X1358320Y918670D03*
X1363871Y928283D03*
X1362020Y925079D03*
X1356471Y941100D03*
X1358320Y937896D03*
X1352771Y947509D03*
X1356471D03*
X1352771Y941100D03*
X1350920Y937896D03*
X1349071Y934691D03*
X1356471D03*
X1352771D03*
X1360171D03*
X1363871Y947509D03*
Y941100D03*
X1362020Y944304D03*
X1352771Y960326D03*
X1350920Y957122D03*
X1356471Y960326D03*
X1358320Y957122D03*
X1350920Y950713D03*
X1358320D03*
X1349071Y953917D03*
X1356471D03*
X1352771D03*
X1360171D03*
X1363871Y960326D03*
Y966735D03*
X1356471D03*
X1352771D03*
X1362020Y963530D03*
Y982756D03*
X1363871Y979552D03*
X1352771D03*
X1356471D03*
X1350920Y976347D03*
X1358320D03*
X1349071Y973143D03*
X1350920Y969939D03*
X1358320D03*
X1360171Y973143D03*
X1349504Y1006093D03*
X1356904D03*
X1353204D03*
X1360604D03*
X1351353Y1002888D03*
X1353204Y999684D03*
X1358753Y1002888D03*
X1356904Y999684D03*
X1353204Y1012501D03*
X1351353Y1009297D03*
X1356904Y1012501D03*
X1358753Y1009297D03*
X1353204Y1031727D03*
X1351353Y1028523D03*
X1356904Y1031727D03*
X1358753Y1028523D03*
X1351353Y1022114D03*
X1353204Y1018910D03*
X1358753Y1022114D03*
X1356904Y1018910D03*
X1353204Y1025318D03*
X1360604D03*
X1349502D03*
X1356902D03*
X1362453Y1015705D03*
X1351353Y1047749D03*
X1358753D03*
X1351353Y1041340D03*
X1353204Y1038136D03*
X1358753Y1041340D03*
X1356904Y1038136D03*
X1349504Y1044544D03*
X1356904D03*
X1353204D03*
X1360604D03*
X1362453Y1034931D03*
X1351353Y1060565D03*
X1353204Y1057361D03*
X1358753Y1060565D03*
X1356904Y1057361D03*
X1353204Y1050952D03*
X1356904D03*
X1349504Y1063770D03*
X1360604D03*
X1353204D03*
X1356904D03*
X1362453Y1054157D03*
X1356904Y1070178D03*
X1358753Y1066974D03*
X1353204Y1070178D03*
X1351353Y1066974D03*
Y1079791D03*
X1353204Y1076587D03*
X1358753Y1079791D03*
X1356904Y1076587D03*
X1362453Y1073383D03*
X1353204Y1089404D03*
X1351353Y1086200D03*
X1356904Y1089404D03*
X1358753Y1086200D03*
X1349504Y1082995D03*
X1362453Y1092608D03*
X1360604Y1082995D03*
X1353204D03*
X1356904D03*
X1362453Y1111834D03*
Y1105426D03*
X1358753D03*
X1351353Y1111834D03*
Y1105426D03*
X1358753Y1111834D03*
X1360604Y1108630D03*
X1355053Y1111834D03*
X1356904Y1102221D03*
X1353204Y1108630D03*
X1355054Y1105426D03*
X1351353Y1124651D03*
X1355053D03*
X1358753D03*
X1362453D03*
X1349504Y1121447D03*
X1353204Y1127856D03*
X1356904Y1121447D03*
X1360604Y1127856D03*
X1356904Y1115039D03*
X1349504Y1134264D03*
X1353203Y1140973D03*
X1356904Y1134264D03*
X1360603Y1140973D03*
X1351354Y1137469D03*
X1355054D03*
X1358754D03*
X1362454D03*
X1367569Y844971D03*
X1369421Y841467D03*
X1373120Y848176D03*
X1376821Y841467D03*
X1365720Y848176D03*
X1371269Y844971D03*
X1374969D03*
X1378669D03*
X1376820Y867401D03*
X1369420D03*
X1365720Y860993D03*
X1367571Y857789D03*
X1373120Y860993D03*
X1374971Y857789D03*
X1369420Y854584D03*
X1371271Y857789D03*
X1376820Y854584D03*
X1378671Y857789D03*
X1367571Y870606D03*
X1371271D03*
X1378671D03*
X1365720Y873810D03*
X1373120D03*
X1374971Y870606D03*
X1369420Y880219D03*
X1371271Y883423D03*
X1376820Y880219D03*
X1378671Y883423D03*
X1367571D03*
X1374971D03*
X1365720Y899445D03*
X1369420D03*
X1373120Y886627D03*
X1365720D03*
Y912262D03*
X1369420D03*
X1371271Y909057D03*
Y902649D03*
X1369420Y905853D03*
X1365720D03*
X1373120D03*
X1369420Y931488D03*
X1371271Y928283D03*
X1365720Y918670D03*
X1371271Y921875D03*
X1369420Y918670D03*
X1365720Y931488D03*
X1369420Y925079D03*
X1365720D03*
X1373120D03*
X1371271Y947509D03*
X1365720Y937896D03*
X1371271Y941100D03*
X1369420Y937896D03*
Y944304D03*
X1365720D03*
X1373120D03*
X1365720Y957122D03*
X1371271Y960326D03*
X1369420Y957122D03*
X1371271Y966735D03*
X1365720Y950713D03*
X1369420D03*
X1373120Y963530D03*
X1369420D03*
X1365720D03*
X1374971Y973143D03*
X1376820Y976347D03*
X1378671Y979552D03*
Y973143D03*
X1369420Y982756D03*
X1365720D03*
X1373120D03*
X1369420Y976347D03*
X1371271Y979552D03*
X1365721Y976347D03*
X1365720Y969939D03*
X1369420D03*
X1366153Y1002888D03*
X1364304Y999684D03*
X1369853Y1002888D03*
X1371704Y999684D03*
X1364304Y1012501D03*
X1371704D03*
X1366153Y1009297D03*
X1369853D03*
X1373553Y1015705D03*
X1364304Y1031727D03*
X1366153Y1028523D03*
X1371704Y1031727D03*
X1369853Y1028523D03*
X1366153Y1022114D03*
X1364304Y1018910D03*
X1369853Y1022114D03*
X1371704Y1018910D03*
X1366153Y1041340D03*
X1364304Y1038136D03*
X1369853Y1041340D03*
X1371704Y1038136D03*
X1366153Y1047749D03*
X1369853D03*
Y1034931D03*
X1366153D03*
X1373553D03*
X1366153Y1060565D03*
X1364304Y1057361D03*
X1369853Y1060565D03*
X1371704Y1057361D03*
X1364304Y1050952D03*
X1371704D03*
X1369853Y1054157D03*
X1366153D03*
X1373553D03*
X1366153Y1079791D03*
X1364304Y1076587D03*
X1369853Y1079791D03*
X1371704Y1076587D03*
X1364304Y1070178D03*
X1366153Y1066974D03*
X1371704Y1070178D03*
X1369853Y1066974D03*
Y1073383D03*
X1366153D03*
X1373553D03*
X1371704Y1095813D03*
X1364304Y1089404D03*
X1366153Y1086200D03*
X1371704Y1089404D03*
X1369853Y1086200D03*
X1364304Y1095813D03*
X1369853Y1092608D03*
X1366153D03*
X1373553D03*
X1379104Y1082995D03*
X1379103Y1089404D03*
X1369853Y1099017D03*
X1366153D03*
X1369853Y1111834D03*
X1368004Y1108630D03*
X1377253Y1099017D03*
X1379104Y1108630D03*
X1373553Y1105426D03*
X1371704Y1108630D03*
X1379104Y1102221D03*
X1377253Y1111834D03*
X1375404Y1108630D03*
X1366153Y1124651D03*
X1371704Y1121447D03*
X1373553Y1124651D03*
X1377253D03*
X1368004Y1127856D03*
X1369853Y1124651D03*
X1375404Y1127856D03*
X1379104Y1121447D03*
X1364304D03*
X1375404Y1115039D03*
X1368004D03*
X1379104D03*
X1368003Y1140973D03*
X1371704Y1134264D03*
X1375403Y1140973D03*
X1379104Y1134264D03*
X1364304D03*
X1366154Y1137469D03*
X1369854D03*
X1373554D03*
X1377254D03*
X1380520Y848176D03*
X1386069Y844971D03*
X1389769D03*
X1393469D03*
X1382369D03*
X1384221Y841467D03*
X1387920Y848176D03*
X1391621Y841467D03*
X1395320Y848176D03*
X1384220Y867401D03*
X1391620D03*
X1380520Y860993D03*
X1382371Y857789D03*
X1387920Y860993D03*
X1389771Y857789D03*
X1395320Y860993D03*
X1384220Y854584D03*
X1386071Y857789D03*
X1391620Y854584D03*
X1393471Y857789D03*
X1380520Y873810D03*
X1382371Y870606D03*
X1384220Y880219D03*
X1386071Y883423D03*
X1382371D03*
X1395320Y873810D03*
X1393471Y870606D03*
X1387920Y873810D03*
X1389771Y870606D03*
X1393471Y883423D03*
X1391620Y880219D03*
X1389771Y883423D03*
X1386071Y896240D03*
X1389771D03*
X1393471D03*
X1387920Y899445D03*
X1391620Y893036D03*
X1395320Y899445D03*
X1380520Y886627D03*
X1387920D03*
X1395320D03*
X1384653Y1079791D03*
X1388353Y1086200D03*
X1386504Y1082995D03*
X1390204Y1089404D03*
X1382804D03*
X1390204Y1082995D03*
X1382804D03*
X1395753Y1086200D03*
Y1092608D03*
X1380953Y1086200D03*
X1386504Y1089404D03*
X1384653Y1092608D03*
X1380953Y1099017D03*
X1395753Y1105426D03*
X1393904Y1108630D03*
X1390204Y1102221D03*
X1392053Y1111834D03*
X1388353D03*
X1384653Y1105426D03*
Y1099017D03*
X1392053Y1105426D03*
X1395753Y1111834D03*
X1388353Y1105426D03*
X1384653Y1111834D03*
X1386504Y1108630D03*
X1380953Y1124651D03*
X1384653D03*
X1382804Y1127856D03*
X1386504Y1121447D03*
X1390204Y1115039D03*
X1382803Y1140973D03*
X1386504Y1134264D03*
X1380954Y1137469D03*
X1384654D03*
X1397169Y844971D03*
X1399021Y841467D03*
X1402720Y848176D03*
X1406420D03*
X1411969Y844971D03*
X1400869D03*
X1404569D03*
X1410120Y848176D03*
X1406420Y867401D03*
X1399020D03*
X1397171Y857789D03*
X1402720Y860993D03*
X1404571Y857789D03*
X1410121Y860993D03*
X1411971Y857789D03*
X1399020Y854584D03*
X1400871Y857789D03*
X1406420Y854584D03*
X1408271Y857789D03*
Y870606D03*
X1402720Y873810D03*
X1400871Y870606D03*
X1410121Y873810D03*
X1404571Y870606D03*
X1397171D03*
X1411971D03*
X1408271Y883423D03*
X1406420Y880219D03*
X1400871Y883423D03*
X1399020Y880219D03*
X1404571Y883423D03*
X1397171D03*
X1411971D03*
X1397171Y896240D03*
X1402720Y899445D03*
X1404571Y896240D03*
X1410120Y899445D03*
X1399020Y893036D03*
X1400871Y896240D03*
X1406420Y893036D03*
X1408271Y896240D03*
X1411971D03*
X1410120Y886627D03*
X1402720D03*
X1405003Y1076587D03*
X1406853Y1079791D03*
X1401304Y1082995D03*
X1405003Y1089404D03*
X1399453Y1086200D03*
X1406853Y1092608D03*
X1399453D03*
X1397604Y1089404D03*
X1403154Y1086200D03*
X1406852D03*
X1403153Y1092608D03*
X1401304Y1095813D03*
X1413820Y848176D03*
X1428620Y867401D03*
X1421220D03*
X1413820D03*
X1424921Y860993D03*
X1421220Y854584D03*
X1417520Y860993D03*
X1428620Y854584D03*
X1426771Y857789D03*
X1423071D03*
X1419371D03*
X1413821Y854584D03*
X1424921Y873810D03*
X1423071Y870606D03*
X1417520Y873810D03*
X1415671Y870606D03*
X1426771D03*
X1419371D03*
X1428621Y880219D03*
X1423071Y883423D03*
X1421220Y880219D03*
X1415671Y883423D03*
X1413820Y880219D03*
X1426771Y883423D03*
X1419371D03*
X1413820Y893036D03*
X1421220Y899445D03*
X1419371Y896240D03*
X1424920Y899445D03*
X1426772Y896240D03*
X1417520Y899445D03*
X1421220Y893036D03*
X1423071Y896240D03*
X1428621Y893036D03*
X1424920Y886627D03*
X1417520D03*
X1443420Y867401D03*
X1436020D03*
X1445271Y857789D03*
X1439720Y860993D03*
X1437871Y857789D03*
X1432320Y860993D03*
X1430471Y857789D03*
X1443420Y854584D03*
X1441571Y857789D03*
X1436020Y854584D03*
X1434171Y857789D03*
X1445271Y870606D03*
X1439720Y873810D03*
X1437871Y870606D03*
X1432320Y873810D03*
X1430471Y870606D03*
X1441571D03*
X1434171D03*
X1445271Y883423D03*
X1443420Y880219D03*
X1437871Y883423D03*
X1436020Y880219D03*
X1430471Y883423D03*
X1441571D03*
X1434171D03*
X1430471Y896240D03*
X1436020Y893036D03*
X1437871Y896240D03*
X1441571D03*
X1432320Y899445D03*
X1434171Y896240D03*
X1439720Y899445D03*
X1443420Y893036D03*
X1439720Y886627D03*
X1432320D03*
X1450820Y867401D03*
X1458220D03*
X1460071Y857789D03*
X1454520Y860993D03*
X1452671Y857789D03*
X1447120Y860993D03*
X1458220Y854584D03*
X1456371Y857789D03*
X1450820Y854584D03*
X1448971Y857789D03*
X1456371Y870606D03*
X1452671D03*
X1454520Y873810D03*
X1460071Y870606D03*
X1450820Y880219D03*
X1452671Y883423D03*
X1458220Y880219D03*
X1460071Y883423D03*
X1448971D03*
X1456371D03*
X1458220Y893036D03*
X1460071Y896240D03*
X1447120Y886627D03*
X1454520D03*
X1460071Y915466D03*
Y934691D03*
Y953917D03*
Y973143D03*
X1460504Y1006093D03*
Y1025318D03*
Y1044544D03*
Y1063770D03*
Y1082995D03*
Y1121447D03*
X1456804Y1127856D03*
X1453104Y1121447D03*
X1449404Y1127856D03*
X1445704Y1121447D03*
X1458653Y1124651D03*
X1454953D03*
X1451253D03*
X1447553D03*
X1460504Y1134264D03*
X1458654Y1137469D03*
X1453104Y1134264D03*
X1451254Y1137469D03*
X1456803Y1140973D03*
X1454954Y1137469D03*
X1449403Y1140973D03*
X1465620Y867401D03*
X1473020D03*
X1467471Y857789D03*
X1461920Y860993D03*
X1476720D03*
X1474871Y857789D03*
X1471171D03*
X1465620Y854584D03*
X1463771Y857789D03*
X1473020Y854584D03*
X1469320Y860993D03*
X1463771Y870606D03*
X1471171D03*
X1461920Y873810D03*
X1467471Y870606D03*
X1469320Y873810D03*
X1474871Y870606D03*
X1476720Y873810D03*
X1465620Y880219D03*
X1467471Y883423D03*
X1473020Y880219D03*
X1474871Y883423D03*
X1463771D03*
X1471171D03*
X1476720Y899445D03*
X1461920D03*
X1469320D03*
Y893036D03*
X1473020D03*
X1461920D03*
X1467471Y896240D03*
X1463771D03*
X1471171D03*
X1461920Y886627D03*
X1469320D03*
X1476720D03*
X1461920Y912262D03*
X1463771Y909057D03*
X1469320Y912262D03*
X1467471Y909057D03*
X1476720Y912262D03*
X1474871Y909057D03*
Y902649D03*
X1463771D03*
X1467471D03*
X1463771Y915466D03*
X1476720Y905853D03*
X1471171Y915466D03*
X1473020Y905853D03*
X1467471Y915466D03*
X1476720Y931488D03*
X1474871Y921875D03*
X1476720Y918670D03*
X1474871Y928283D03*
X1473020Y925079D03*
X1476720D03*
X1467471Y921875D03*
X1469320Y918670D03*
X1461920Y931488D03*
X1467471Y928283D03*
X1469320Y931488D03*
X1463771Y928283D03*
Y921875D03*
X1461920Y918670D03*
X1474871Y947509D03*
Y941100D03*
X1476720Y937896D03*
X1473020Y944304D03*
X1476720D03*
X1463771Y947509D03*
X1467471D03*
X1463771Y941100D03*
X1461920Y937896D03*
X1467471Y941100D03*
X1469320Y937896D03*
X1463771Y934691D03*
X1471171D03*
X1467471D03*
X1476720Y950713D03*
X1463771Y966735D03*
X1467471D03*
X1474871D03*
X1473020Y963530D03*
X1461920Y950713D03*
X1469320D03*
X1467471Y960326D03*
X1469320Y957122D03*
X1463771Y960326D03*
X1461920Y957122D03*
X1476720D03*
X1474871Y960326D03*
X1471171Y953917D03*
X1463771D03*
X1467471D03*
X1463771Y979552D03*
X1461920Y976347D03*
X1467471Y979552D03*
X1469320Y976347D03*
X1476720Y982756D03*
X1473020D03*
X1474871Y979552D03*
X1476720Y976347D03*
X1471171Y973143D03*
X1463771D03*
X1467471D03*
X1461920Y969939D03*
X1469320D03*
X1476720D03*
X1477153Y1002888D03*
X1475304Y999684D03*
Y1012501D03*
X1477153Y1009297D03*
X1471604Y1006093D03*
X1462353Y1002888D03*
X1469753D03*
X1464204Y999684D03*
X1467904D03*
X1467903Y1012501D03*
X1469753Y1009297D03*
X1464204Y1012501D03*
X1462353Y1009297D03*
X1473453Y1015705D03*
X1475304Y1031727D03*
X1477153Y1028523D03*
Y1022114D03*
X1475304Y1018910D03*
X1464204Y1031727D03*
X1462353Y1028523D03*
X1467904Y1031727D03*
X1469753Y1028523D03*
X1462353Y1022114D03*
X1464204Y1018910D03*
X1469753Y1022114D03*
X1467904Y1018910D03*
X1464204Y1025318D03*
X1471604D03*
X1467904D03*
X1477153Y1041340D03*
X1475304Y1038136D03*
X1477153Y1047749D03*
Y1034931D03*
X1473453D03*
X1462353Y1047749D03*
X1469753D03*
X1462353Y1041340D03*
X1464204Y1038136D03*
X1469753Y1041340D03*
X1467904Y1038136D03*
X1464204Y1044544D03*
X1471604D03*
X1467904D03*
X1477153Y1060565D03*
X1475304Y1057361D03*
Y1050952D03*
X1477153Y1054157D03*
X1473453D03*
X1462353Y1060565D03*
X1464204Y1057361D03*
X1469753Y1060565D03*
X1467904Y1057361D03*
X1464204Y1050952D03*
X1467904D03*
X1464204Y1063770D03*
X1471604D03*
X1467904D03*
X1475304Y1070178D03*
X1477153Y1066974D03*
Y1079791D03*
X1475304Y1076587D03*
X1473453Y1073383D03*
X1477153D03*
X1462353Y1079791D03*
X1464204Y1076587D03*
X1469753Y1079791D03*
X1467904Y1076587D03*
X1464204Y1070178D03*
X1462353Y1066974D03*
X1467904Y1070178D03*
X1469753Y1066974D03*
X1467904Y1089404D03*
X1469753Y1086200D03*
X1475304Y1089404D03*
X1477153Y1086200D03*
X1464204Y1089404D03*
X1462353Y1086200D03*
X1473453Y1092608D03*
X1471604Y1082995D03*
X1477153Y1092608D03*
X1464204Y1082995D03*
X1467904D03*
X1464204Y1127856D03*
X1475304Y1121447D03*
X1471604Y1127856D03*
X1467904Y1121447D03*
X1466053Y1124651D03*
X1462353D03*
X1477153D03*
X1473453D03*
X1469753D03*
X1469754Y1137469D03*
X1464203Y1140973D03*
X1477154Y1137469D03*
X1471603Y1140973D03*
X1467904Y1134264D03*
X1466054Y1137469D03*
X1462354D03*
X1475304Y1134264D03*
X1473454Y1137469D03*
X1487820Y867401D03*
X1480420D03*
X1491520Y860993D03*
X1489671Y857789D03*
X1484120Y860993D03*
X1482271Y857789D03*
X1493371D03*
X1487820Y854584D03*
X1485971Y857789D03*
X1480420Y854584D03*
X1478571Y857789D03*
X1493371Y870606D03*
X1478571D03*
X1485971D03*
X1489671D03*
X1491520Y873810D03*
X1482271Y870606D03*
X1484120Y873810D03*
X1487820Y880219D03*
X1489671Y883423D03*
X1480420Y880219D03*
X1482271Y883423D03*
X1485971D03*
X1493371D03*
X1478571D03*
X1487820Y899445D03*
Y893036D03*
X1484120D03*
X1485971Y896240D03*
X1493371D03*
X1489671D03*
X1480420Y899445D03*
X1491520Y886627D03*
X1484120D03*
X1489671Y902649D03*
X1493371D03*
X1487820Y912262D03*
X1489671Y909057D03*
X1493371D03*
X1489671Y915466D03*
X1485971D03*
X1493371D03*
X1480420Y912262D03*
X1482271Y909057D03*
Y902649D03*
X1484120Y905853D03*
X1480420D03*
X1487820Y931488D03*
X1489671Y928283D03*
X1493371D03*
X1482271D03*
Y921875D03*
X1480420Y918670D03*
X1489671Y921875D03*
X1487820Y918670D03*
X1493371Y921875D03*
X1480420Y931488D03*
Y925079D03*
X1484120D03*
X1489671Y941100D03*
X1487820Y937896D03*
X1493371Y941100D03*
X1489671Y934691D03*
X1485971D03*
X1493371D03*
X1489671Y947509D03*
X1493371D03*
X1482271D03*
Y941100D03*
X1480420Y937896D03*
X1484120Y944304D03*
X1480420D03*
X1487820Y950713D03*
X1489671Y960326D03*
X1487820Y957122D03*
X1493371Y960326D03*
Y966735D03*
X1489671D03*
X1480420Y950713D03*
X1489671Y953917D03*
X1493371D03*
X1485971D03*
X1482271Y966735D03*
X1480420Y957122D03*
X1482271Y960326D03*
X1484120Y963530D03*
Y982756D03*
X1480420D03*
Y976347D03*
X1482271Y979552D03*
X1489671D03*
X1493371D03*
X1487820Y976347D03*
X1485971Y973143D03*
X1487820Y969939D03*
X1480420D03*
X1493804Y1006093D03*
X1490104D03*
X1486404D03*
X1493804Y1012501D03*
X1480853Y1002888D03*
X1482703Y999684D03*
X1490104Y1012501D03*
X1488253Y1009297D03*
X1482704Y1012501D03*
X1480853Y1009297D03*
X1493803Y999684D03*
X1488253Y1002888D03*
X1490104Y999684D03*
Y1031727D03*
X1488253Y1028523D03*
X1493804Y1031727D03*
X1488253Y1022114D03*
X1490104Y1018910D03*
X1493804D03*
X1490104Y1025318D03*
X1486404D03*
X1493804D03*
X1484553Y1015705D03*
X1482704Y1031727D03*
X1480853Y1028523D03*
Y1022114D03*
X1482704Y1018910D03*
X1480853Y1041340D03*
X1482704Y1038136D03*
X1488253Y1047749D03*
Y1041340D03*
X1490104Y1038136D03*
X1493804D03*
X1480853Y1047749D03*
X1486404Y1044544D03*
X1484553Y1034931D03*
X1490104Y1044544D03*
X1493804D03*
X1480853Y1034931D03*
X1488253Y1060565D03*
X1490104Y1057361D03*
X1493804D03*
X1486404Y1063770D03*
X1490104D03*
X1493804D03*
X1490104Y1050952D03*
X1493804D03*
X1480853Y1060565D03*
X1482704Y1057361D03*
Y1050952D03*
X1484553Y1054157D03*
X1480853D03*
X1493804Y1070178D03*
X1490104D03*
X1488253Y1066974D03*
X1480853Y1079791D03*
X1482704Y1076587D03*
Y1070178D03*
X1480853Y1066974D03*
X1488253Y1079791D03*
X1490104Y1076587D03*
X1493804D03*
X1484553Y1073383D03*
X1480853D03*
X1490104Y1089404D03*
X1488253Y1086200D03*
X1493804Y1089404D03*
X1490104Y1082995D03*
X1486404D03*
X1493804D03*
X1486404Y1095813D03*
X1482703D03*
X1482704Y1089404D03*
X1480853Y1086200D03*
X1484553Y1092608D03*
X1480853D03*
X1493804Y1102221D03*
X1491953Y1099017D03*
X1493804Y1127856D03*
X1490104Y1121447D03*
X1486404Y1127856D03*
X1482704Y1121447D03*
X1479004Y1127856D03*
X1491953Y1124651D03*
X1488253D03*
X1484553D03*
X1480853D03*
X1493803Y1140973D03*
X1490104Y1134264D03*
X1488254Y1137469D03*
X1482704Y1134264D03*
X1480854Y1137469D03*
X1491954D03*
X1486403Y1140973D03*
X1484554Y1137469D03*
X1479003Y1140973D03*
X1508171Y864197D03*
X1510021Y854584D03*
X1495220Y867401D03*
X1502621D03*
X1504471Y857789D03*
X1498920Y860993D03*
X1497071Y857789D03*
X1502620Y854584D03*
X1500771Y857789D03*
X1495220Y854584D03*
X1500771Y870606D03*
X1508171D03*
X1497071D03*
X1498920Y873810D03*
X1504471Y870606D03*
X1506321Y873810D03*
X1495220Y880219D03*
X1497071Y883423D03*
X1502621Y880219D03*
X1504471Y883423D03*
X1500771D03*
X1502621Y899445D03*
X1506320D03*
X1495220D03*
Y893036D03*
X1498920D03*
X1497071Y896240D03*
X1498920Y886627D03*
X1506321D03*
Y912262D03*
X1508171Y909057D03*
X1500771Y902649D03*
X1508171D03*
X1502621Y912262D03*
X1500771Y909057D03*
X1502621Y905853D03*
X1510021D03*
X1498920D03*
X1506321D03*
X1495220Y912262D03*
X1497071Y915466D03*
X1502621Y931488D03*
X1500771Y928283D03*
X1506321Y931488D03*
X1508171Y928283D03*
X1500771Y921875D03*
X1502621Y918670D03*
X1508171Y921875D03*
X1506321Y918670D03*
X1502621Y925079D03*
X1510021D03*
X1498920D03*
X1506321D03*
X1495220Y931488D03*
Y918670D03*
X1500771Y941100D03*
X1502621Y937896D03*
X1508171Y941100D03*
X1506321Y937896D03*
X1500771Y947509D03*
X1508171D03*
X1495220Y937896D03*
X1510021Y944304D03*
X1497071Y934691D03*
X1502621Y944304D03*
X1506320D03*
X1498920D03*
X1500771Y966735D03*
X1508171D03*
X1498920Y963530D03*
X1502621Y950713D03*
X1506320D03*
X1508171Y960326D03*
X1506320Y957122D03*
X1500771Y960326D03*
X1502621Y957122D03*
X1510021Y963530D03*
X1495220Y950713D03*
Y957122D03*
X1497071Y953917D03*
X1502621Y969939D03*
X1506321D03*
X1495220Y976347D03*
Y969939D03*
X1497071Y973143D03*
X1497504Y1006093D03*
X1501204Y1012501D03*
X1508603D03*
X1503053Y1009297D03*
X1506753D03*
X1495653D03*
X1495655Y1002888D03*
X1506753D03*
X1508603Y999684D03*
X1503053Y1002888D03*
X1501204Y999684D03*
X1499353Y1015705D03*
X1510453D03*
X1501204Y1031727D03*
X1503053Y1028523D03*
X1508603Y1031727D03*
X1506753Y1028523D03*
Y1022114D03*
X1508603Y1018910D03*
X1503053Y1022114D03*
X1501204Y1018910D03*
X1495653Y1028523D03*
Y1022114D03*
X1497504Y1025318D03*
X1503053Y1041340D03*
X1501204Y1038136D03*
X1506753Y1041340D03*
X1508603Y1038136D03*
X1503053Y1047749D03*
X1506753D03*
X1503053Y1034931D03*
X1510453D03*
X1499353D03*
X1506753D03*
X1495653Y1047749D03*
Y1041340D03*
X1497504Y1044544D03*
X1495653Y1060565D03*
X1503053D03*
X1501204Y1057361D03*
X1506753Y1060565D03*
X1508604Y1057361D03*
X1501203Y1050952D03*
X1508604Y1050953D03*
X1499353Y1054157D03*
X1497504Y1063770D03*
X1510453Y1054157D03*
X1503053D03*
X1506753D03*
Y1079791D03*
X1508604Y1076587D03*
X1501204Y1070178D03*
X1503053Y1066974D03*
X1508604Y1070178D03*
X1506753Y1066974D03*
X1503053Y1079791D03*
X1501204Y1076587D03*
X1499353Y1073383D03*
X1510453D03*
X1503053D03*
X1506753D03*
X1495653Y1066974D03*
Y1079791D03*
X1497504Y1095813D03*
X1508603D03*
X1501204D03*
Y1089404D03*
X1503053Y1086200D03*
X1508604Y1089404D03*
X1506753Y1086200D03*
X1503053Y1092608D03*
X1510452D03*
X1499353D03*
X1506753D03*
X1495653Y1086200D03*
X1497504Y1082995D03*
X1506753Y1099017D03*
X1503053Y1124651D03*
X1497504Y1121447D03*
X1501204Y1127856D03*
X1499353Y1124651D03*
X1495653D03*
X1508604Y1134264D03*
X1501203Y1140973D03*
X1499354Y1137469D03*
X1510454D03*
X1503054D03*
X1497504Y1134264D03*
X1495654Y1137469D03*
X1519271Y851380D03*
X1515571D03*
X1511871Y864197D03*
X1519270D03*
X1522970D03*
X1511871Y857789D03*
X1519271D03*
X1515571D03*
X1517421Y860993D03*
Y854584D03*
X1515571Y883423D03*
X1513720Y880219D03*
X1519271Y883423D03*
X1521121Y880219D03*
X1513720Y873810D03*
X1515571Y870606D03*
X1521121Y873810D03*
X1519271Y870606D03*
X1515570Y877014D03*
X1522970D03*
X1511871D03*
X1519271D03*
X1596941Y883924D03*
Y890617D03*
Y897310D03*
Y900656D03*
Y914042D03*
Y907349D03*
Y960892D03*
Y957546D03*
Y1185105D03*
Y1178412D03*
Y1191798D03*
Y1208530D03*
Y1201837D03*
Y1195144D03*
X1613083Y880577D03*
Y887270D03*
Y897310D03*
Y893963D03*
Y910696D03*
Y904003D03*
Y1175066D03*
Y1181759D03*
Y1191798D03*
Y1188451D03*
Y1205184D03*
Y1198491D03*
X1626641Y960892D03*
Y957546D03*
X1656441Y780184D03*
Y773491D03*
Y786877D03*
Y803609D03*
Y796916D03*
Y790223D03*
Y816995D03*
Y810302D03*
Y833727D03*
Y823688D03*
Y827034D03*
Y847113D03*
Y840420D03*
Y853806D03*
Y860499D03*
Y863845D03*
Y883924D03*
Y877231D03*
Y870538D03*
Y890617D03*
Y897310D03*
Y900656D03*
Y914042D03*
Y907349D03*
Y927428D03*
Y920735D03*
Y934121D03*
Y944160D03*
Y937467D03*
Y960892D03*
Y950853D03*
Y957546D03*
Y980971D03*
Y974278D03*
Y967585D03*
Y994357D03*
Y987664D03*
X1656141Y1027822D03*
X1656441Y1021129D03*
X1656141Y1047900D03*
Y1041207D03*
Y1034514D03*
Y1054593D03*
X1656441Y1074672D03*
Y1067979D03*
Y1091404D03*
Y1081365D03*
Y1084711D03*
Y1098097D03*
Y1111483D03*
Y1104790D03*
Y1128215D03*
Y1118176D03*
Y1121522D03*
Y1141601D03*
Y1134908D03*
Y1148294D03*
Y1154987D03*
Y1158333D03*
Y1171719D03*
Y1165026D03*
Y1185105D03*
Y1178412D03*
Y1191798D03*
Y1208530D03*
Y1201837D03*
Y1195144D03*
Y1221916D03*
Y1215223D03*
Y1238648D03*
Y1228609D03*
Y1231955D03*
Y1245341D03*
X1672583Y770144D03*
Y776837D03*
Y786877D03*
Y783530D03*
Y800263D03*
Y793570D03*
Y813648D03*
Y806955D03*
Y820341D03*
Y830381D03*
Y823688D03*
Y850459D03*
Y843766D03*
Y837074D03*
Y867192D03*
Y860499D03*
Y857152D03*
Y873885D03*
Y880577D03*
Y887270D03*
Y897310D03*
Y893963D03*
Y917389D03*
Y910696D03*
Y904003D03*
Y924081D03*
Y934121D03*
Y930774D03*
Y947507D03*
Y940814D03*
Y964239D03*
Y977625D03*
Y970932D03*
Y991011D03*
Y984318D03*
Y1021129D03*
Y1024475D03*
Y1031168D03*
X1672283Y1044554D03*
Y1037861D03*
X1672583Y1051247D03*
Y1071325D03*
Y1064633D03*
Y1078018D03*
Y1094751D03*
Y1088058D03*
Y1081365D03*
Y1108136D03*
Y1101444D03*
Y1124869D03*
Y1118176D03*
Y1114829D03*
Y1144947D03*
Y1138255D03*
Y1131562D03*
Y1161680D03*
Y1154987D03*
Y1151640D03*
Y1175066D03*
Y1168373D03*
Y1181758D03*
Y1191798D03*
Y1188451D03*
Y1205184D03*
Y1198491D03*
Y1218569D03*
Y1211877D03*
Y1225262D03*
Y1241995D03*
Y1235302D03*
Y1228609D03*
X1686041Y960892D03*
Y957546D03*
X1686141Y967585D03*
Y1054593D03*
X1702283Y964239D03*
Y1021129D03*
Y1024475D03*
Y1051247D03*
X1715841Y780184D03*
Y773491D03*
Y786877D03*
Y803609D03*
Y796916D03*
Y790223D03*
Y816995D03*
Y810302D03*
Y833727D03*
Y823688D03*
Y827034D03*
Y847113D03*
Y840420D03*
Y853806D03*
Y860499D03*
Y863845D03*
Y883924D03*
Y877231D03*
Y870538D03*
Y890617D03*
Y897310D03*
Y900656D03*
Y914042D03*
Y907349D03*
Y927428D03*
Y920735D03*
Y934121D03*
Y944160D03*
Y937467D03*
Y960892D03*
Y950853D03*
Y957546D03*
Y980971D03*
Y974278D03*
Y967585D03*
Y994357D03*
Y987664D03*
Y1027822D03*
Y1021129D03*
Y1047900D03*
Y1041207D03*
Y1034514D03*
Y1054593D03*
Y1074672D03*
Y1067979D03*
Y1091404D03*
Y1081365D03*
Y1084711D03*
Y1098097D03*
Y1111483D03*
Y1104790D03*
Y1128215D03*
Y1118176D03*
Y1121522D03*
Y1141601D03*
Y1134908D03*
Y1148294D03*
Y1154987D03*
Y1158333D03*
Y1171719D03*
Y1165026D03*
Y1185105D03*
Y1178412D03*
Y1191798D03*
Y1208530D03*
Y1201837D03*
Y1195144D03*
Y1221916D03*
Y1215223D03*
Y1238648D03*
Y1228609D03*
Y1231955D03*
Y1245341D03*
X1731983Y770144D03*
Y776837D03*
Y786877D03*
Y783530D03*
Y800263D03*
Y793570D03*
Y813648D03*
Y806955D03*
Y820341D03*
Y830381D03*
Y823688D03*
Y850459D03*
Y843766D03*
Y837074D03*
Y867192D03*
Y860499D03*
Y857152D03*
Y873885D03*
Y880577D03*
Y887270D03*
Y897310D03*
Y893963D03*
Y917389D03*
Y910696D03*
Y904003D03*
Y924081D03*
Y934121D03*
Y930774D03*
Y947507D03*
Y940814D03*
Y964239D03*
Y977625D03*
X1731883Y970932D03*
X1731983Y991011D03*
Y984318D03*
Y1021129D03*
Y1024475D03*
Y1031168D03*
X1731683Y1044554D03*
Y1037861D03*
X1731983Y1051247D03*
X1731818Y1071326D03*
X1731883Y1064633D03*
X1731983Y1078018D03*
Y1094751D03*
Y1088058D03*
Y1081365D03*
X1731818Y1108137D03*
X1731983Y1101444D03*
Y1124869D03*
Y1118176D03*
Y1114829D03*
Y1144947D03*
Y1138255D03*
Y1131562D03*
Y1161680D03*
Y1154987D03*
Y1151640D03*
Y1175066D03*
Y1168373D03*
X1731818Y1181759D03*
X1731983Y1191798D03*
X1731818Y1188452D03*
X1731983Y1205184D03*
Y1198491D03*
Y1218569D03*
Y1211877D03*
Y1225262D03*
Y1241995D03*
Y1235302D03*
Y1228609D03*
X1745541Y960892D03*
Y957546D03*
Y967585D03*
Y1054593D03*
X1761683Y964239D03*
Y1021129D03*
Y1024475D03*
Y1051247D03*
X1775241Y780184D03*
Y773491D03*
Y786877D03*
Y803609D03*
Y796916D03*
Y790223D03*
Y816995D03*
Y810302D03*
Y833727D03*
Y823688D03*
Y827034D03*
Y847113D03*
Y840420D03*
Y853806D03*
Y860499D03*
Y863845D03*
Y883924D03*
Y877231D03*
Y870538D03*
Y890617D03*
Y897310D03*
Y900656D03*
Y914042D03*
Y907349D03*
Y927428D03*
Y920735D03*
Y934121D03*
Y944160D03*
Y937467D03*
Y960892D03*
Y950853D03*
Y957546D03*
Y980971D03*
Y974278D03*
Y967585D03*
Y994357D03*
Y987664D03*
Y1027822D03*
Y1021129D03*
Y1047900D03*
Y1041207D03*
Y1034515D03*
Y1054593D03*
Y1074672D03*
Y1067979D03*
Y1091404D03*
Y1081365D03*
Y1084711D03*
Y1098097D03*
Y1111483D03*
Y1104790D03*
Y1128215D03*
Y1118176D03*
Y1121522D03*
Y1141601D03*
Y1134908D03*
Y1148294D03*
Y1154987D03*
Y1158333D03*
Y1171719D03*
Y1165026D03*
Y1185105D03*
Y1178412D03*
Y1191798D03*
Y1208530D03*
Y1201837D03*
Y1195144D03*
Y1221916D03*
Y1215223D03*
Y1238648D03*
Y1228609D03*
Y1231955D03*
Y1245341D03*
X1791383Y770144D03*
Y776837D03*
Y786877D03*
Y783530D03*
Y800263D03*
Y793570D03*
Y813648D03*
Y806955D03*
Y820341D03*
Y830381D03*
Y823688D03*
Y850459D03*
Y843766D03*
Y837074D03*
Y867192D03*
Y860499D03*
Y857152D03*
Y873885D03*
Y880577D03*
Y887270D03*
Y897310D03*
Y893963D03*
Y917389D03*
Y910696D03*
Y904003D03*
Y924081D03*
Y934121D03*
Y930774D03*
Y947507D03*
Y940814D03*
Y964239D03*
Y977625D03*
Y970932D03*
Y991011D03*
Y984318D03*
Y1021129D03*
Y1024475D03*
Y1031168D03*
Y1044554D03*
Y1037861D03*
X1791083Y1051247D03*
X1791383Y1071325D03*
Y1064633D03*
Y1078018D03*
Y1094751D03*
Y1088058D03*
Y1081365D03*
Y1108136D03*
Y1101444D03*
Y1124869D03*
Y1118176D03*
Y1114829D03*
Y1144947D03*
Y1138255D03*
Y1131562D03*
Y1161680D03*
Y1154987D03*
Y1151640D03*
Y1175066D03*
Y1168373D03*
Y1181758D03*
Y1191798D03*
Y1188451D03*
Y1205184D03*
Y1198491D03*
Y1218570D03*
Y1211877D03*
Y1225263D03*
Y1241995D03*
Y1235302D03*
Y1228609D03*
X1804941Y960892D03*
Y957546D03*
Y967585D03*
Y1054593D03*
X1821083Y964239D03*
Y1021129D03*
Y1024475D03*
Y1051247D03*
G54D43*
X174685Y647210D03*
X174393Y678354D03*
X195316Y1430034D03*
X383224Y1354446D03*
X412990D03*
X443326D03*
X458600Y1379662D03*
X472700Y1353962D03*
X526478Y1449795D03*
X708795Y1429579D03*
X1168627Y1466363D03*
X1359365Y1353946D03*
X1389131D03*
X1419467D03*
X1434200Y1379362D03*
X1449233Y1353946D03*
X1502956Y1449373D03*
X1670101Y1463655D03*
X1682882Y628017D03*
Y678952D03*
X1769790Y204632D03*
X1799350D03*
X1826405Y269763D03*
Y299056D03*
G54D70*
X676508Y145866D03*
G54D34*
G01X170570Y1509250D02*
X172980Y1511660D01*
X186548D01*
X208000Y1533112D01*
X366365D01*
X367948Y1531529D01*
G01X775375Y1403561D02*
Y1413685D01*
X730998Y1458062D01*
X670599D01*
X665582Y1453045D01*
X663133D01*
X661100Y1451012D01*
G01X663410Y1553982D02*
X658600D01*
X655111Y1550493D01*
Y1538521D01*
X660380Y1533252D01*
X689076D01*
X780788Y1441540D01*
X796020D01*
X802550Y1435010D01*
X804100D01*
X70472Y173228D03*
Y236220D03*
G54D128*
G01X548401Y1068701D02*
X548859D01*
X549540Y1069382D01*
G54D119*
G01X-6350Y-464479D02*
Y-539479D01*
X493650D01*
Y-464479D01*
X-6350D01*
G01X5650Y-529479D02*
Y-534479D01*
G01X4193Y-529479D02*
X7107D01*
G01X12017Y-534479D02*
X9483D01*
Y-529479D01*
X12017D01*
G01X11003Y-531896D02*
X9483D01*
G01X14583Y-529479D02*
Y-534479D01*
X17117D01*
G01X20950Y-534646D02*
X20823Y-534562D01*
Y-534396D01*
X20950Y-534312D01*
X21077Y-534396D01*
Y-534562D01*
X20950Y-534646D01*
G01Y-532396D02*
X20823Y-532312D01*
Y-532146D01*
X20950Y-532062D01*
X21077Y-532146D01*
Y-532312D01*
X20950Y-532396D01*
G01X25733Y-536146D02*
X25100Y-535312D01*
X24783Y-534479D01*
Y-531146D01*
X25100Y-530312D01*
X25733Y-529479D01*
G01X31150D02*
X30643Y-529646D01*
X30263Y-530062D01*
X30010Y-530562D01*
X29820Y-531229D01*
X29757Y-531979D01*
X29820Y-532729D01*
X30010Y-533396D01*
X30263Y-533896D01*
X30643Y-534312D01*
X31150Y-534479D01*
X31657Y-534312D01*
X32037Y-533896D01*
X32290Y-533396D01*
X32480Y-532729D01*
X32543Y-531979D01*
X32480Y-531229D01*
X32290Y-530562D01*
X32037Y-530062D01*
X31657Y-529646D01*
X31150Y-529479D01*
G01X34857Y-533479D02*
X35237Y-534062D01*
X35743Y-534396D01*
X36313Y-534479D01*
X36820Y-534396D01*
X37327Y-533979D01*
X37643Y-533479D01*
X37707Y-532979D01*
X37580Y-532396D01*
X37137Y-531979D01*
X36693Y-531812D01*
X36123D01*
G01X36693D02*
X37073Y-531562D01*
X37390Y-531146D01*
X37517Y-530646D01*
X37390Y-530146D01*
X37073Y-529729D01*
X36503Y-529479D01*
X35933Y-529562D01*
X35363Y-529896D01*
G01X41667Y-536146D02*
X42300Y-535312D01*
X42617Y-534479D01*
Y-531146D01*
X42300Y-530312D01*
X41667Y-529479D01*
G01X45057Y-533479D02*
X45437Y-534062D01*
X45943Y-534396D01*
X46513Y-534479D01*
X47020Y-534396D01*
X47527Y-533979D01*
X47843Y-533479D01*
X47907Y-532979D01*
X47780Y-532396D01*
X47337Y-531979D01*
X46893Y-531812D01*
X46323D01*
G01X46893D02*
X47273Y-531562D01*
X47590Y-531146D01*
X47717Y-530646D01*
X47590Y-530146D01*
X47273Y-529729D01*
X46703Y-529479D01*
X46133Y-529562D01*
X45563Y-529896D01*
G01X50347Y-530312D02*
X50727Y-529812D01*
X51170Y-529562D01*
X51677Y-529479D01*
X52310Y-529646D01*
X52753Y-530062D01*
X52880Y-530562D01*
X52817Y-531062D01*
X52563Y-531479D01*
X51297Y-532312D01*
X50727Y-532896D01*
X50347Y-533729D01*
X50220Y-534479D01*
X52880D01*
G01X56523D02*
X56650Y-533396D01*
X56840Y-532479D01*
X57093Y-531646D01*
X57410Y-530729D01*
X57917Y-529479D01*
X55383D01*
G01X60927Y-532812D02*
X62573D01*
G01X65647Y-530312D02*
X66027Y-529812D01*
X66470Y-529562D01*
X66977Y-529479D01*
X67610Y-529646D01*
X68053Y-530062D01*
X68180Y-530562D01*
X68117Y-531062D01*
X67863Y-531479D01*
X66597Y-532312D01*
X66027Y-532896D01*
X65647Y-533729D01*
X65520Y-534479D01*
X68180D01*
G01X70557Y-533479D02*
X70937Y-534062D01*
X71443Y-534396D01*
X72013Y-534479D01*
X72520Y-534396D01*
X73027Y-533979D01*
X73343Y-533479D01*
X73407Y-532979D01*
X73280Y-532396D01*
X72837Y-531979D01*
X72393Y-531812D01*
X71823D01*
G01X72393D02*
X72773Y-531562D01*
X73090Y-531146D01*
X73217Y-530646D01*
X73090Y-530146D01*
X72773Y-529729D01*
X72203Y-529479D01*
X71633Y-529562D01*
X71063Y-529896D01*
G01X77810Y-534479D02*
Y-529479D01*
X75467Y-533062D01*
X78633D01*
G01X80757Y-533729D02*
X81137Y-534146D01*
X81580Y-534396D01*
X82150Y-534479D01*
X82720Y-534312D01*
X83163Y-533979D01*
X83480Y-533396D01*
X83543Y-532729D01*
X83417Y-532062D01*
X83100Y-531646D01*
X82657Y-531312D01*
X82213Y-531229D01*
X81770Y-531312D01*
X81200Y-531646D01*
X81390Y-529479D01*
X83100D01*
G01X91147Y-534479D02*
Y-529479D01*
X93553D01*
G01X92667Y-531896D02*
X91147D01*
G01X95867Y-534479D02*
X97450Y-529479D01*
X99033Y-534479D01*
G01X98463Y-532729D02*
X96437D01*
G01X101220Y-534479D02*
X103880Y-529479D01*
G01X101220D02*
X103880Y-534479D01*
G01X107650Y-534646D02*
X107523Y-534562D01*
Y-534396D01*
X107650Y-534312D01*
X107777Y-534396D01*
Y-534562D01*
X107650Y-534646D01*
G01Y-532396D02*
X107523Y-532312D01*
Y-532146D01*
X107650Y-532062D01*
X107777Y-532146D01*
Y-532312D01*
X107650Y-532396D01*
G01X112433Y-536146D02*
X111800Y-535312D01*
X111483Y-534479D01*
Y-531146D01*
X111800Y-530312D01*
X112433Y-529479D01*
G01X117850D02*
X117343Y-529646D01*
X116963Y-530062D01*
X116710Y-530562D01*
X116520Y-531229D01*
X116457Y-531979D01*
X116520Y-532729D01*
X116710Y-533396D01*
X116963Y-533896D01*
X117343Y-534312D01*
X117850Y-534479D01*
X118357Y-534312D01*
X118737Y-533896D01*
X118990Y-533396D01*
X119180Y-532729D01*
X119243Y-531979D01*
X119180Y-531229D01*
X118990Y-530562D01*
X118737Y-530062D01*
X118357Y-529646D01*
X117850Y-529479D01*
G01X121557Y-533479D02*
X121937Y-534062D01*
X122443Y-534396D01*
X123013Y-534479D01*
X123520Y-534396D01*
X124027Y-533979D01*
X124343Y-533479D01*
X124407Y-532979D01*
X124280Y-532396D01*
X123837Y-531979D01*
X123393Y-531812D01*
X122823D01*
G01X123393D02*
X123773Y-531562D01*
X124090Y-531146D01*
X124217Y-530646D01*
X124090Y-530146D01*
X123773Y-529729D01*
X123203Y-529479D01*
X122633Y-529562D01*
X122063Y-529896D01*
G01X128367Y-536146D02*
X129000Y-535312D01*
X129317Y-534479D01*
Y-531146D01*
X129000Y-530312D01*
X128367Y-529479D01*
G01X131757Y-533479D02*
X132137Y-534062D01*
X132643Y-534396D01*
X133213Y-534479D01*
X133720Y-534396D01*
X134227Y-533979D01*
X134543Y-533479D01*
X134607Y-532979D01*
X134480Y-532396D01*
X134037Y-531979D01*
X133593Y-531812D01*
X133023D01*
G01X133593D02*
X133973Y-531562D01*
X134290Y-531146D01*
X134417Y-530646D01*
X134290Y-530146D01*
X133973Y-529729D01*
X133403Y-529479D01*
X132833Y-529562D01*
X132263Y-529896D01*
G01X137173Y-533896D02*
X137617Y-534312D01*
X138123Y-534479D01*
X138630Y-534312D01*
X139073Y-533812D01*
X139390Y-533062D01*
X139517Y-532312D01*
Y-531396D01*
X139390Y-530646D01*
X139073Y-529979D01*
X138693Y-529646D01*
X138250Y-529479D01*
X137743Y-529646D01*
X137363Y-529979D01*
X137110Y-530479D01*
X136983Y-531146D01*
X137110Y-531729D01*
X137427Y-532312D01*
X137807Y-532646D01*
X138250Y-532729D01*
X138757Y-532562D01*
X139137Y-532146D01*
X139517Y-531396D01*
G01X143223Y-534479D02*
X143350Y-533396D01*
X143540Y-532479D01*
X143793Y-531646D01*
X144110Y-530729D01*
X144617Y-529479D01*
X142083D01*
G01X147627Y-532812D02*
X149273D01*
G01X152157Y-533479D02*
X152537Y-534062D01*
X153043Y-534396D01*
X153613Y-534479D01*
X154120Y-534396D01*
X154627Y-533979D01*
X154943Y-533479D01*
X155007Y-532979D01*
X154880Y-532396D01*
X154437Y-531979D01*
X153993Y-531812D01*
X153423D01*
G01X153993D02*
X154373Y-531562D01*
X154690Y-531146D01*
X154817Y-530646D01*
X154690Y-530146D01*
X154373Y-529729D01*
X153803Y-529479D01*
X153233Y-529562D01*
X152663Y-529896D01*
G01X157447Y-532396D02*
X157890Y-531812D01*
X158270Y-531479D01*
X158777Y-531312D01*
X159220Y-531479D01*
X159537Y-531812D01*
X159790Y-532312D01*
X159853Y-532896D01*
X159790Y-533396D01*
X159537Y-533896D01*
X159157Y-534312D01*
X158713Y-534479D01*
X158207Y-534312D01*
X157763Y-533812D01*
X157510Y-533062D01*
X157447Y-532229D01*
X157573Y-531146D01*
X157763Y-530562D01*
X158080Y-529979D01*
X158523Y-529562D01*
X158967Y-529479D01*
X159410Y-529646D01*
X159727Y-530062D01*
G01X163750Y-534479D02*
Y-529479D01*
X162990Y-530479D01*
G01Y-534479D02*
X164510D01*
G01X169610D02*
Y-529479D01*
X167267Y-533062D01*
X170433D01*
G01X188650Y-464479D02*
Y-539479D01*
G01Y-514479D02*
X291650D01*
Y-489479D01*
G01X188650D02*
X291650D01*
G01Y-464479D02*
Y-539479D01*
G01X293650Y-464479D02*
Y-539479D01*
G01X299157Y-524479D02*
Y-519479D01*
X300423D01*
X300930Y-519729D01*
X301310Y-520062D01*
X301627Y-520562D01*
X301880Y-521146D01*
X301943Y-521979D01*
X301880Y-522812D01*
X301627Y-523396D01*
X301310Y-523896D01*
X300930Y-524229D01*
X300423Y-524479D01*
X299157D01*
G01X304067D02*
X305650Y-519479D01*
X307233Y-524479D01*
G01X306663Y-522729D02*
X304637D01*
G01X310750Y-519479D02*
Y-524479D01*
G01X309293Y-519479D02*
X312207D01*
G01X317117Y-524479D02*
X314583D01*
Y-519479D01*
X317117D01*
G01X316103Y-521896D02*
X314583D01*
G01X320950Y-524646D02*
X320823Y-524562D01*
Y-524396D01*
X320950Y-524312D01*
X321077Y-524396D01*
Y-524562D01*
X320950Y-524646D01*
G01Y-522396D02*
X320823Y-522312D01*
Y-522146D01*
X320950Y-522062D01*
X321077Y-522146D01*
Y-522312D01*
X320950Y-522396D01*
G01X299283Y-499479D02*
Y-494479D01*
X300803D01*
X301310Y-494729D01*
X301690Y-495312D01*
X301817Y-495979D01*
X301690Y-496646D01*
X301373Y-497146D01*
X300803Y-497396D01*
X299283D01*
G01X304510Y-499646D02*
X306790Y-494479D01*
G01X309293Y-499479D02*
Y-494479D01*
X312207Y-499479D01*
Y-494479D01*
G01X315850Y-499646D02*
X315723Y-499562D01*
Y-499396D01*
X315850Y-499312D01*
X315977Y-499396D01*
Y-499562D01*
X315850Y-499646D01*
G01Y-497396D02*
X315723Y-497312D01*
Y-497146D01*
X315850Y-497062D01*
X315977Y-497146D01*
Y-497312D01*
X315850Y-497396D01*
G01X293650Y-514479D02*
X493650D01*
G01X293650Y-489479D02*
X493650D01*
G01X299283Y-474479D02*
Y-469479D01*
X300803D01*
X301310Y-469729D01*
X301690Y-470312D01*
X301817Y-470979D01*
X301690Y-471646D01*
X301373Y-472146D01*
X300803Y-472396D01*
X299283D01*
G01X304383Y-474479D02*
Y-469479D01*
X305967D01*
X306473Y-469729D01*
X306790Y-470062D01*
X306917Y-470729D01*
X306790Y-471396D01*
X306410Y-471812D01*
X305967Y-472062D01*
X304383D01*
G01X305967D02*
X306917Y-474479D01*
G01X310750D02*
X310243Y-474396D01*
X309800Y-474062D01*
X309420Y-473562D01*
X309167Y-472979D01*
X309040Y-472312D01*
Y-471646D01*
X309167Y-470979D01*
X309420Y-470396D01*
X309800Y-469896D01*
X310243Y-469562D01*
X310750Y-469479D01*
X311257Y-469562D01*
X311700Y-469896D01*
X312080Y-470396D01*
X312333Y-470979D01*
X312460Y-471646D01*
Y-472312D01*
X312333Y-472979D01*
X312080Y-473562D01*
X311700Y-474062D01*
X311257Y-474396D01*
X310750Y-474479D01*
G01X314583Y-473479D02*
X314900Y-473979D01*
X315280Y-474312D01*
X315723Y-474479D01*
X316230Y-474312D01*
X316610Y-473979D01*
X316990Y-473479D01*
X317117Y-472812D01*
Y-469479D01*
G01X322217Y-474479D02*
X319683D01*
Y-469479D01*
X322217D01*
G01X321203Y-471896D02*
X319683D01*
G01X327443Y-469896D02*
X327063Y-469646D01*
X326620Y-469479D01*
X326113D01*
X325543Y-469729D01*
X325100Y-470146D01*
X324783Y-470646D01*
X324530Y-471479D01*
X324467Y-472229D01*
X324593Y-472979D01*
X324783Y-473479D01*
X325163Y-473979D01*
X325607Y-474312D01*
X326050Y-474479D01*
X326493D01*
X326937Y-474312D01*
X327317Y-474062D01*
X327633Y-473729D01*
G01X331150Y-469479D02*
Y-474479D01*
G01X329693Y-469479D02*
X332607D01*
G01X336250Y-474646D02*
X336123Y-474562D01*
Y-474396D01*
X336250Y-474312D01*
X336377Y-474396D01*
Y-474562D01*
X336250Y-474646D01*
G01Y-472396D02*
X336123Y-472312D01*
Y-472146D01*
X336250Y-472062D01*
X336377Y-472146D01*
Y-472312D01*
X336250Y-472396D01*
G01X408650Y-514479D02*
Y-539479D01*
G01X411283Y-516979D02*
Y-521979D01*
X413817D01*
G01X416890Y-516979D02*
X418410D01*
G01X417650D02*
Y-521979D01*
G01X416890D02*
X418410D01*
G01X423257Y-519312D02*
X423510Y-519062D01*
X423700Y-518646D01*
X423827Y-518062D01*
X423700Y-517562D01*
X423447Y-517229D01*
X423003Y-516979D01*
X421293D01*
Y-521979D01*
X423383D01*
X423827Y-521646D01*
X424080Y-521146D01*
X424207Y-520562D01*
X424080Y-519979D01*
X423700Y-519479D01*
X423257Y-519312D01*
X421293D01*
G01X427850Y-522146D02*
X427723Y-522062D01*
Y-521896D01*
X427850Y-521812D01*
X427977Y-521896D01*
Y-522062D01*
X427850Y-522146D01*
G01Y-519896D02*
X427723Y-519812D01*
Y-519646D01*
X427850Y-519562D01*
X427977Y-519646D01*
Y-519812D01*
X427850Y-519896D01*
G01X451650Y-514479D02*
Y-539479D01*
G01Y-489479D02*
Y-514479D01*
G01X456663Y-541646D02*
X456770Y-541521D01*
X456850Y-541312D01*
X456903Y-541021D01*
X456850Y-540771D01*
X456743Y-540604D01*
X456557Y-540479D01*
X455837D01*
Y-542979D01*
X456717D01*
X456903Y-542812D01*
X457010Y-542562D01*
X457063Y-542271D01*
X457010Y-541979D01*
X456850Y-541729D01*
X456663Y-541646D01*
X455837D01*
G01X459130Y-542979D02*
Y-541312D01*
G01Y-541604D02*
X459023Y-541437D01*
X458863Y-541354D01*
X458677Y-541312D01*
X458490Y-541396D01*
X458330Y-541562D01*
X458223Y-541812D01*
X458170Y-542146D01*
X458223Y-542479D01*
X458330Y-542729D01*
X458490Y-542896D01*
X458677Y-542979D01*
X458863Y-542937D01*
X459023Y-542812D01*
X459130Y-542646D01*
G01X460450Y-542687D02*
X460583Y-542854D01*
X460770Y-542979D01*
X460930D01*
X461090Y-542896D01*
X461197Y-542771D01*
X461250Y-542604D01*
X461223Y-542354D01*
X461117Y-542229D01*
X460637Y-541979D01*
X460530Y-541687D01*
X460583Y-541479D01*
X460690Y-541354D01*
X460850Y-541312D01*
X461010Y-541354D01*
X461170Y-541479D01*
G01X462650Y-541854D02*
X463503D01*
X463423Y-541562D01*
X463290Y-541396D01*
X463103Y-541312D01*
X462917Y-541354D01*
X462757Y-541479D01*
X462650Y-541771D01*
X462597Y-542021D01*
Y-542271D01*
X462650Y-542521D01*
X462783Y-542771D01*
X462943Y-542937D01*
X463130Y-542979D01*
X463317Y-542896D01*
X463503Y-542646D01*
G01X464770Y-542979D02*
Y-540479D01*
G01Y-541729D02*
X464903Y-541479D01*
X465063Y-541354D01*
X465223Y-541312D01*
X465463Y-541396D01*
X465623Y-541562D01*
X465730Y-541854D01*
Y-542187D01*
X465677Y-542521D01*
X465570Y-542771D01*
X465383Y-542937D01*
X465223Y-542979D01*
X465063Y-542937D01*
X464903Y-542812D01*
X464770Y-542604D01*
G01X467450Y-542979D02*
X467290Y-542937D01*
X467130Y-542771D01*
X467023Y-542479D01*
X466970Y-542146D01*
X467023Y-541812D01*
X467130Y-541521D01*
X467290Y-541354D01*
X467450Y-541312D01*
X467610Y-541354D01*
X467770Y-541521D01*
X467877Y-541812D01*
X467903Y-542146D01*
X467877Y-542479D01*
X467770Y-542771D01*
X467610Y-542937D01*
X467450Y-542979D01*
G01X470130D02*
Y-541312D01*
G01Y-541604D02*
X470023Y-541437D01*
X469863Y-541354D01*
X469677Y-541312D01*
X469490Y-541396D01*
X469330Y-541562D01*
X469223Y-541812D01*
X469170Y-542146D01*
X469223Y-542479D01*
X469330Y-542729D01*
X469490Y-542896D01*
X469677Y-542979D01*
X469863Y-542937D01*
X470023Y-542812D01*
X470130Y-542646D01*
G01X471477Y-542979D02*
Y-541312D01*
G01Y-541646D02*
X471610Y-541479D01*
X471743Y-541354D01*
X471930Y-541312D01*
X472063Y-541354D01*
X472223Y-541479D01*
G01X474530Y-540479D02*
Y-542979D01*
G01Y-542604D02*
X474423Y-542812D01*
X474263Y-542937D01*
X474077Y-542979D01*
X473863Y-542896D01*
X473703Y-542687D01*
X473597Y-542437D01*
X473570Y-542146D01*
X473597Y-541854D01*
X473703Y-541604D01*
X473863Y-541396D01*
X474077Y-541312D01*
X474263Y-541354D01*
X474397Y-541437D01*
X474530Y-541604D01*
G01X477917Y-542979D02*
Y-540479D01*
X478583D01*
X478797Y-540604D01*
X478930Y-540771D01*
X478983Y-541104D01*
X478930Y-541437D01*
X478770Y-541646D01*
X478583Y-541771D01*
X477917D01*
G01X478583D02*
X478983Y-542979D01*
G01X480250Y-541854D02*
X481103D01*
X481023Y-541562D01*
X480890Y-541396D01*
X480703Y-541312D01*
X480517Y-541354D01*
X480357Y-541479D01*
X480250Y-541771D01*
X480197Y-542021D01*
Y-542271D01*
X480250Y-542521D01*
X480383Y-542771D01*
X480543Y-542937D01*
X480730Y-542979D01*
X480917Y-542896D01*
X481103Y-542646D01*
G01X482370Y-541312D02*
X482850Y-542979D01*
X483330Y-541312D01*
G01X485050Y-543062D02*
X484997Y-543021D01*
Y-542937D01*
X485050Y-542896D01*
X485103Y-542937D01*
Y-543021D01*
X485050Y-543062D01*
G01X487250Y-542979D02*
X487437Y-542937D01*
X487650Y-542812D01*
X487783Y-542604D01*
X487837Y-542312D01*
X487783Y-542021D01*
X487623Y-541771D01*
X487383Y-541646D01*
X487117D01*
X486957Y-541562D01*
X486823Y-541354D01*
X486770Y-541062D01*
X486850Y-540771D01*
X487037Y-540562D01*
X487250Y-540479D01*
X487463Y-540562D01*
X487650Y-540771D01*
X487730Y-541062D01*
X487677Y-541354D01*
X487543Y-541562D01*
X487383Y-541646D01*
X487117D01*
X486877Y-541771D01*
X486717Y-542021D01*
X486663Y-542312D01*
X486717Y-542604D01*
X486850Y-542812D01*
X487063Y-542937D01*
X487250Y-542979D01*
G01X489663Y-541646D02*
X489770Y-541521D01*
X489850Y-541312D01*
X489903Y-541021D01*
X489850Y-540771D01*
X489743Y-540604D01*
X489557Y-540479D01*
X488837D01*
Y-542979D01*
X489717D01*
X489903Y-542812D01*
X490010Y-542562D01*
X490063Y-542271D01*
X490010Y-541979D01*
X489850Y-541729D01*
X489663Y-541646D01*
X488837D01*
G01X455550Y-516979D02*
Y-521979D01*
G01X454093Y-516979D02*
X457007D01*
G01X460650Y-521979D02*
X460270Y-521896D01*
X459890Y-521562D01*
X459637Y-520979D01*
X459510Y-520312D01*
X459637Y-519646D01*
X459890Y-519062D01*
X460270Y-518729D01*
X460650Y-518646D01*
X461030Y-518729D01*
X461410Y-519062D01*
X461663Y-519646D01*
X461727Y-520312D01*
X461663Y-520979D01*
X461410Y-521562D01*
X461030Y-521896D01*
X460650Y-521979D01*
G01X465750D02*
X465370Y-521896D01*
X464990Y-521562D01*
X464737Y-520979D01*
X464610Y-520312D01*
X464737Y-519646D01*
X464990Y-519062D01*
X465370Y-518729D01*
X465750Y-518646D01*
X466130Y-518729D01*
X466510Y-519062D01*
X466763Y-519646D01*
X466827Y-520312D01*
X466763Y-520979D01*
X466510Y-521562D01*
X466130Y-521896D01*
X465750Y-521979D01*
G01X470850D02*
Y-516979D01*
G01X475950Y-522146D02*
X475823Y-522062D01*
Y-521896D01*
X475950Y-521812D01*
X476077Y-521896D01*
Y-522062D01*
X475950Y-522146D01*
G01Y-519896D02*
X475823Y-519812D01*
Y-519646D01*
X475950Y-519562D01*
X476077Y-519646D01*
Y-519812D01*
X475950Y-519896D01*
G01X454283Y-496979D02*
Y-491979D01*
X455867D01*
X456373Y-492229D01*
X456690Y-492562D01*
X456817Y-493229D01*
X456690Y-493896D01*
X456310Y-494312D01*
X455867Y-494562D01*
X454283D01*
G01X455867D02*
X456817Y-496979D01*
G01X461917D02*
X459383D01*
Y-491979D01*
X461917D01*
G01X460903Y-494396D02*
X459383D01*
G01X464167Y-491979D02*
X465750Y-496979D01*
X467333Y-491979D01*
G01X470850Y-497146D02*
X470723Y-497062D01*
Y-496896D01*
X470850Y-496812D01*
X470977Y-496896D01*
Y-497062D01*
X470850Y-497146D01*
G01Y-494896D02*
X470723Y-494812D01*
Y-494646D01*
X470850Y-494562D01*
X470977Y-494646D01*
Y-494812D01*
X470850Y-494896D01*
G01X-984580Y-698988D02*
Y4193602D01*
X5868320D01*
Y-698988D01*
X-984580D01*
G01X7723Y-521204D02*
X7253Y-520889D01*
X6705Y-520679D01*
X6078D01*
X5373Y-520994D01*
X4825Y-521519D01*
X4433Y-522149D01*
X4120Y-523199D01*
X4042Y-524144D01*
X4198Y-525089D01*
X4433Y-525719D01*
X4903Y-526349D01*
X5452Y-526769D01*
X6000Y-526979D01*
X6548D01*
X7097Y-526769D01*
X7567Y-526454D01*
X7958Y-526034D01*
G01X11360Y-520679D02*
X13240D01*
G01X12300D02*
Y-526979D01*
G01X11360D02*
X13240D01*
G01X18600Y-520679D02*
Y-526979D01*
G01X16798Y-520679D02*
X20402D01*
G01X24900Y-526979D02*
Y-524144D01*
X23333Y-520679D01*
G01X26467D02*
X24900Y-524144D01*
G01X35777Y-525719D02*
X36247Y-526454D01*
X36873Y-526874D01*
X37578Y-526979D01*
X38205Y-526874D01*
X38832Y-526349D01*
X39223Y-525719D01*
X39302Y-525089D01*
X39145Y-524354D01*
X38597Y-523829D01*
X38048Y-523619D01*
X37343D01*
G01X38048D02*
X38518Y-523304D01*
X38910Y-522779D01*
X39067Y-522149D01*
X38910Y-521519D01*
X38518Y-520994D01*
X37813Y-520679D01*
X37108Y-520784D01*
X36403Y-521204D01*
G01X42077Y-525719D02*
X42547Y-526454D01*
X43173Y-526874D01*
X43878Y-526979D01*
X44505Y-526874D01*
X45132Y-526349D01*
X45523Y-525719D01*
X45602Y-525089D01*
X45445Y-524354D01*
X44897Y-523829D01*
X44348Y-523619D01*
X43643D01*
G01X44348D02*
X44818Y-523304D01*
X45210Y-522779D01*
X45367Y-522149D01*
X45210Y-521519D01*
X44818Y-520994D01*
X44113Y-520679D01*
X43408Y-520784D01*
X42703Y-521204D01*
G01X48377Y-525719D02*
X48847Y-526454D01*
X49473Y-526874D01*
X50178Y-526979D01*
X50805Y-526874D01*
X51432Y-526349D01*
X51823Y-525719D01*
X51902Y-525089D01*
X51745Y-524354D01*
X51197Y-523829D01*
X50648Y-523619D01*
X49943D01*
G01X50648D02*
X51118Y-523304D01*
X51510Y-522779D01*
X51667Y-522149D01*
X51510Y-521519D01*
X51118Y-520994D01*
X50413Y-520679D01*
X49708Y-520784D01*
X49003Y-521204D01*
G01X56243Y-526979D02*
X56400Y-525614D01*
X56635Y-524459D01*
X56948Y-523409D01*
X57340Y-522254D01*
X57967Y-520679D01*
X54833D01*
G01X62543Y-526979D02*
X62700Y-525614D01*
X62935Y-524459D01*
X63248Y-523409D01*
X63640Y-522254D01*
X64267Y-520679D01*
X61133D01*
G01X68843Y-528134D02*
X69157Y-526769D01*
G01X75300Y-520679D02*
Y-526979D01*
G01X73498Y-520679D02*
X77102D01*
G01X79642Y-526979D02*
X81600Y-520679D01*
X83558Y-526979D01*
G01X82853Y-524774D02*
X80347D01*
G01X86960Y-520679D02*
X88840D01*
G01X87900D02*
Y-526979D01*
G01X86960D02*
X88840D01*
G01X91850Y-520679D02*
X92947Y-526979D01*
X94200Y-520679D01*
X95453Y-526979D01*
X96550Y-520679D01*
G01X98542Y-526979D02*
X100500Y-520679D01*
X102458Y-526979D01*
G01X101753Y-524774D02*
X99247D01*
G01X104998Y-526979D02*
Y-520679D01*
X108602Y-526979D01*
Y-520679D01*
G01X119008Y-529079D02*
X118225Y-528029D01*
X117833Y-526979D01*
Y-522779D01*
X118225Y-521729D01*
X119008Y-520679D01*
G01X130433Y-526979D02*
Y-520679D01*
X132392D01*
X133018Y-520994D01*
X133410Y-521414D01*
X133567Y-522254D01*
X133410Y-523094D01*
X132940Y-523619D01*
X132392Y-523934D01*
X130433D01*
G01X132392D02*
X133567Y-526979D01*
G01X138300Y-527189D02*
X138143Y-527084D01*
Y-526874D01*
X138300Y-526769D01*
X138457Y-526874D01*
Y-527084D01*
X138300Y-527189D01*
G01X144600Y-526979D02*
X143973Y-526874D01*
X143425Y-526454D01*
X142955Y-525824D01*
X142642Y-525089D01*
X142485Y-524249D01*
Y-523409D01*
X142642Y-522569D01*
X142955Y-521834D01*
X143425Y-521204D01*
X143973Y-520784D01*
X144600Y-520679D01*
X145227Y-520784D01*
X145775Y-521204D01*
X146245Y-521834D01*
X146558Y-522569D01*
X146715Y-523409D01*
Y-524249D01*
X146558Y-525089D01*
X146245Y-525824D01*
X145775Y-526454D01*
X145227Y-526874D01*
X144600Y-526979D01*
G01X150900Y-527189D02*
X150743Y-527084D01*
Y-526874D01*
X150900Y-526769D01*
X151057Y-526874D01*
Y-527084D01*
X150900Y-527189D01*
G01X158923Y-521204D02*
X158453Y-520889D01*
X157905Y-520679D01*
X157278D01*
X156573Y-520994D01*
X156025Y-521519D01*
X155633Y-522149D01*
X155320Y-523199D01*
X155242Y-524144D01*
X155398Y-525089D01*
X155633Y-525719D01*
X156103Y-526349D01*
X156652Y-526769D01*
X157200Y-526979D01*
X157748D01*
X158297Y-526769D01*
X158767Y-526454D01*
X159158Y-526034D01*
G01X163500Y-527189D02*
X163343Y-527084D01*
Y-526874D01*
X163500Y-526769D01*
X163657Y-526874D01*
Y-527084D01*
X163500Y-527189D01*
G01X170192Y-529079D02*
X170975Y-528029D01*
X171367Y-526979D01*
Y-522779D01*
X170975Y-521729D01*
X170192Y-520679D01*
G01X6470Y-513829D02*
X8037D01*
Y-515719D01*
X7567Y-516349D01*
X7018Y-516769D01*
X6235Y-516979D01*
X5452Y-516769D01*
X4903Y-516349D01*
X4433Y-515719D01*
X4120Y-514984D01*
X3963Y-514144D01*
Y-513409D01*
X4120Y-512779D01*
X4433Y-512044D01*
X4903Y-511414D01*
X5373Y-510994D01*
X6000Y-510679D01*
X6548D01*
X7175Y-510889D01*
X7645Y-511309D01*
G01X10577Y-510679D02*
Y-515194D01*
X10890Y-516139D01*
X11517Y-516769D01*
X12300Y-516979D01*
X13083Y-516769D01*
X13710Y-516139D01*
X14023Y-515194D01*
Y-510679D01*
G01X17660D02*
X19540D01*
G01X18600D02*
Y-516979D01*
G01X17660D02*
X19540D01*
G01X23255Y-516139D02*
X23882Y-516664D01*
X24587Y-516979D01*
X25213D01*
X25840Y-516664D01*
X26310Y-516139D01*
X26545Y-515404D01*
X26388Y-514669D01*
X25997Y-514039D01*
X25292Y-513619D01*
X24352Y-513409D01*
X23803Y-512989D01*
X23568Y-512254D01*
X23725Y-511519D01*
X24117Y-510994D01*
X24665Y-510679D01*
X25213D01*
X25762Y-510889D01*
X26232Y-511414D01*
G01X29555Y-516979D02*
Y-510679D01*
G01X32845D02*
Y-516979D01*
G01Y-513829D02*
X29555D01*
G01X35542Y-516979D02*
X37500Y-510679D01*
X39458Y-516979D01*
G01X38753Y-514774D02*
X36247D01*
G01X41998Y-516979D02*
Y-510679D01*
X45602Y-516979D01*
Y-510679D01*
G01X54677Y-516979D02*
Y-510679D01*
X56243D01*
X56870Y-510994D01*
X57340Y-511414D01*
X57732Y-512044D01*
X58045Y-512779D01*
X58123Y-513829D01*
X58045Y-514879D01*
X57732Y-515614D01*
X57340Y-516244D01*
X56870Y-516664D01*
X56243Y-516979D01*
X54677D01*
G01X61760Y-510679D02*
X63640D01*
G01X62700D02*
Y-516979D01*
G01X61760D02*
X63640D01*
G01X67355Y-516139D02*
X67982Y-516664D01*
X68687Y-516979D01*
X69313D01*
X69940Y-516664D01*
X70410Y-516139D01*
X70645Y-515404D01*
X70488Y-514669D01*
X70097Y-514039D01*
X69392Y-513619D01*
X68452Y-513409D01*
X67903Y-512989D01*
X67668Y-512254D01*
X67825Y-511519D01*
X68217Y-510994D01*
X68765Y-510679D01*
X69313D01*
X69862Y-510889D01*
X70332Y-511414D01*
G01X75300Y-510679D02*
Y-516979D01*
G01X73498Y-510679D02*
X77102D01*
G01X81600Y-517189D02*
X81443Y-517084D01*
Y-516874D01*
X81600Y-516769D01*
X81757Y-516874D01*
Y-517084D01*
X81600Y-517189D01*
G01X87743Y-518134D02*
X88057Y-516769D01*
G01X94200Y-510679D02*
Y-516979D01*
G01X92398Y-510679D02*
X96002D01*
G01X98542Y-516979D02*
X100500Y-510679D01*
X102458Y-516979D01*
G01X101753Y-514774D02*
X99247D01*
G01X106800Y-516979D02*
X106173Y-516874D01*
X105625Y-516454D01*
X105155Y-515824D01*
X104842Y-515089D01*
X104685Y-514249D01*
Y-513409D01*
X104842Y-512569D01*
X105155Y-511834D01*
X105625Y-511204D01*
X106173Y-510784D01*
X106800Y-510679D01*
X107427Y-510784D01*
X107975Y-511204D01*
X108445Y-511834D01*
X108758Y-512569D01*
X108915Y-513409D01*
Y-514249D01*
X108758Y-515089D01*
X108445Y-515824D01*
X107975Y-516454D01*
X107427Y-516874D01*
X106800Y-516979D01*
G01X113100D02*
Y-514144D01*
X111533Y-510679D01*
G01X114667D02*
X113100Y-514144D01*
G01X117677Y-510679D02*
Y-515194D01*
X117990Y-516139D01*
X118617Y-516769D01*
X119400Y-516979D01*
X120183Y-516769D01*
X120810Y-516139D01*
X121123Y-515194D01*
Y-510679D01*
G01X123742Y-516979D02*
X125700Y-510679D01*
X127658Y-516979D01*
G01X126953Y-514774D02*
X124447D01*
G01X130198Y-516979D02*
Y-510679D01*
X133802Y-516979D01*
Y-510679D01*
G01X4198Y-506979D02*
Y-500679D01*
X7802Y-506979D01*
Y-500679D01*
G01X12300Y-506979D02*
X11673Y-506874D01*
X11125Y-506454D01*
X10655Y-505824D01*
X10342Y-505089D01*
X10185Y-504249D01*
Y-503409D01*
X10342Y-502569D01*
X10655Y-501834D01*
X11125Y-501204D01*
X11673Y-500784D01*
X12300Y-500679D01*
X12927Y-500784D01*
X13475Y-501204D01*
X13945Y-501834D01*
X14258Y-502569D01*
X14415Y-503409D01*
Y-504249D01*
X14258Y-505089D01*
X13945Y-505824D01*
X13475Y-506454D01*
X12927Y-506874D01*
X12300Y-506979D01*
G01X18600Y-507189D02*
X18443Y-507084D01*
Y-506874D01*
X18600Y-506769D01*
X18757Y-506874D01*
Y-507084D01*
X18600Y-507189D01*
G01X23412Y-501729D02*
X23882Y-501099D01*
X24430Y-500784D01*
X25057Y-500679D01*
X25840Y-500889D01*
X26388Y-501414D01*
X26545Y-502044D01*
X26467Y-502674D01*
X26153Y-503199D01*
X24587Y-504249D01*
X23882Y-504984D01*
X23412Y-506034D01*
X23255Y-506979D01*
X26545D01*
G01X31200D02*
Y-500679D01*
X30260Y-501939D01*
G01Y-506979D02*
X32140D01*
G01X37500D02*
Y-500679D01*
X36560Y-501939D01*
G01Y-506979D02*
X38440D01*
G01X43643Y-508134D02*
X43957Y-506769D01*
G01X47750Y-500679D02*
X48847Y-506979D01*
X50100Y-500679D01*
X51353Y-506979D01*
X52450Y-500679D01*
G01X57967Y-506979D02*
X54833D01*
Y-500679D01*
X57967D01*
G01X56713Y-503724D02*
X54833D01*
G01X60898Y-506979D02*
Y-500679D01*
X64502Y-506979D01*
Y-500679D01*
G01X67355Y-506979D02*
Y-500679D01*
G01X70645D02*
Y-506979D01*
G01Y-503829D02*
X67355D01*
G01X73577Y-500679D02*
Y-505194D01*
X73890Y-506139D01*
X74517Y-506769D01*
X75300Y-506979D01*
X76083Y-506769D01*
X76710Y-506139D01*
X77023Y-505194D01*
Y-500679D01*
G01X79642Y-506979D02*
X81600Y-500679D01*
X83558Y-506979D01*
G01X82853Y-504774D02*
X80347D01*
G01X92712Y-501729D02*
X93182Y-501099D01*
X93730Y-500784D01*
X94357Y-500679D01*
X95140Y-500889D01*
X95688Y-501414D01*
X95845Y-502044D01*
X95767Y-502674D01*
X95453Y-503199D01*
X93887Y-504249D01*
X93182Y-504984D01*
X92712Y-506034D01*
X92555Y-506979D01*
X95845D01*
G01X98698D02*
Y-500679D01*
X102302Y-506979D01*
Y-500679D01*
G01X105077Y-506979D02*
Y-500679D01*
X106643D01*
X107270Y-500994D01*
X107740Y-501414D01*
X108132Y-502044D01*
X108445Y-502779D01*
X108523Y-503829D01*
X108445Y-504879D01*
X108132Y-505614D01*
X107740Y-506244D01*
X107270Y-506664D01*
X106643Y-506979D01*
X105077D01*
G01X117833D02*
Y-500679D01*
X119792D01*
X120418Y-500994D01*
X120810Y-501414D01*
X120967Y-502254D01*
X120810Y-503094D01*
X120340Y-503619D01*
X119792Y-503934D01*
X117833D01*
G01X119792D02*
X120967Y-506979D01*
G01X123977D02*
Y-500679D01*
X125543D01*
X126170Y-500994D01*
X126640Y-501414D01*
X127032Y-502044D01*
X127345Y-502779D01*
X127423Y-503829D01*
X127345Y-504879D01*
X127032Y-505614D01*
X126640Y-506244D01*
X126170Y-506664D01*
X125543Y-506979D01*
X123977D01*
G01X132000Y-507189D02*
X131843Y-507084D01*
Y-506874D01*
X132000Y-506769D01*
X132157Y-506874D01*
Y-507084D01*
X132000Y-507189D01*
G01X28300Y-494279D02*
X25780Y-493862D01*
X23575Y-492196D01*
X21685Y-489696D01*
X20425Y-486779D01*
X19795Y-483446D01*
Y-480112D01*
X20425Y-476779D01*
X21685Y-473862D01*
X23575Y-471363D01*
X25780Y-469696D01*
X28300Y-469279D01*
X30820Y-469696D01*
X33025Y-471363D01*
X34915Y-473862D01*
X36175Y-476779D01*
X36805Y-480112D01*
Y-483446D01*
X36175Y-486779D01*
X34915Y-489696D01*
X33025Y-492196D01*
X30820Y-493862D01*
X28300Y-494279D01*
G01X30820Y-487612D02*
X34600Y-494279D01*
G01X48145Y-477613D02*
Y-489279D01*
X49405Y-492196D01*
X51295Y-493862D01*
X53500Y-494279D01*
X55705Y-493862D01*
X57595Y-492196D01*
X58855Y-489279D01*
G01Y-494279D02*
Y-477613D01*
G01X84370Y-494279D02*
Y-477613D01*
G01Y-480529D02*
X83110Y-478863D01*
X81220Y-478029D01*
X79015Y-477613D01*
X76810Y-478446D01*
X74920Y-480112D01*
X73660Y-482613D01*
X73030Y-485946D01*
X73660Y-489279D01*
X74920Y-491780D01*
X76810Y-493446D01*
X79015Y-494279D01*
X81220Y-493862D01*
X83110Y-492613D01*
X84370Y-490946D01*
G01X98545Y-494279D02*
Y-477613D01*
G01Y-481779D02*
X99805Y-479696D01*
X101695Y-478029D01*
X104215Y-477613D01*
X106420Y-478029D01*
X108310Y-479696D01*
X109255Y-482613D01*
Y-494279D01*
G01X129100Y-469279D02*
Y-494279D01*
G01X124690Y-477613D02*
X133510D01*
G01X159970Y-494279D02*
Y-477613D01*
G01Y-480529D02*
X158710Y-478863D01*
X156820Y-478029D01*
X154615Y-477613D01*
X152410Y-478446D01*
X150520Y-480112D01*
X149260Y-482613D01*
X148630Y-485946D01*
X149260Y-489279D01*
X150520Y-491780D01*
X152410Y-493446D01*
X154615Y-494279D01*
X156820Y-493862D01*
X158710Y-492613D01*
X159970Y-490946D01*
G01X199650Y-473979D02*
Y-481979D01*
X203650D01*
G01X211450D02*
Y-476646D01*
G01Y-477579D02*
X211050Y-477046D01*
X210450Y-476779D01*
X209750Y-476646D01*
X209050Y-476912D01*
X208450Y-477446D01*
X208050Y-478246D01*
X207850Y-479312D01*
X208050Y-480379D01*
X208450Y-481179D01*
X209050Y-481712D01*
X209750Y-481979D01*
X210450Y-481846D01*
X211050Y-481446D01*
X211450Y-480913D01*
G01X215550Y-484379D02*
X216150Y-484646D01*
X216950Y-484379D01*
X217450Y-483846D01*
X217850Y-483179D01*
X218450Y-481046D01*
X219750Y-476646D01*
G01X216550D02*
X218450Y-481046D01*
G01X224150Y-478379D02*
X227350D01*
X227050Y-477446D01*
X226550Y-476912D01*
X225850Y-476646D01*
X225150Y-476779D01*
X224550Y-477179D01*
X224150Y-478112D01*
X223950Y-478913D01*
Y-479712D01*
X224150Y-480512D01*
X224650Y-481312D01*
X225250Y-481846D01*
X225950Y-481979D01*
X226650Y-481712D01*
X227350Y-480913D01*
G01X232250Y-481979D02*
Y-476646D01*
G01Y-477712D02*
X232750Y-477179D01*
X233250Y-476779D01*
X233950Y-476646D01*
X234450Y-476779D01*
X235050Y-477179D01*
G01X223350Y-531979D02*
Y-523979D01*
X227950Y-531979D01*
Y-523979D01*
G01X233650Y-526646D02*
Y-531979D01*
G01Y-524512D02*
X233450Y-524379D01*
Y-524112D01*
X233650Y-523979D01*
X233850Y-524112D01*
Y-524379D01*
X233650Y-524512D01*
G01X239950Y-531979D02*
Y-526646D01*
G01Y-527979D02*
X240350Y-527312D01*
X240950Y-526779D01*
X241750Y-526646D01*
X242450Y-526779D01*
X243050Y-527312D01*
X243350Y-528246D01*
Y-531979D01*
G01X251450D02*
Y-526646D01*
G01Y-527579D02*
X251050Y-527046D01*
X250450Y-526779D01*
X249750Y-526646D01*
X249050Y-526912D01*
X248450Y-527446D01*
X248050Y-528246D01*
X247850Y-529312D01*
X248050Y-530379D01*
X248450Y-531179D01*
X249050Y-531712D01*
X249750Y-531979D01*
X250450Y-531846D01*
X251050Y-531446D01*
X251450Y-530913D01*
G01X217479Y-504169D02*
X217879Y-503769D01*
X218179Y-503103D01*
X218379Y-502169D01*
X218179Y-501369D01*
X217779Y-500836D01*
X217079Y-500436D01*
X214379D01*
Y-508436D01*
X217679D01*
X218379Y-507903D01*
X218779Y-507103D01*
X218979Y-506169D01*
X218779Y-505236D01*
X218179Y-504436D01*
X217479Y-504169D01*
X214379D01*
G01X224679Y-508436D02*
X223879Y-508303D01*
X223179Y-507769D01*
X222579Y-506969D01*
X222179Y-506036D01*
X221979Y-504969D01*
Y-503903D01*
X222179Y-502836D01*
X222579Y-501903D01*
X223179Y-501103D01*
X223879Y-500569D01*
X224679Y-500436D01*
X225479Y-500569D01*
X226179Y-501103D01*
X226779Y-501903D01*
X227179Y-502836D01*
X227379Y-503903D01*
Y-504969D01*
X227179Y-506036D01*
X226779Y-506969D01*
X226179Y-507769D01*
X225479Y-508303D01*
X224679Y-508436D01*
G01X232679Y-500436D02*
Y-508436D01*
G01X230379Y-500436D02*
X234979D01*
G01X240679D02*
Y-508436D01*
G01X238379Y-500436D02*
X242979D01*
G01X248679Y-508436D02*
X247879Y-508303D01*
X247179Y-507769D01*
X246579Y-506969D01*
X246179Y-506036D01*
X245979Y-504969D01*
Y-503903D01*
X246179Y-502836D01*
X246579Y-501903D01*
X247179Y-501103D01*
X247879Y-500569D01*
X248679Y-500436D01*
X249479Y-500569D01*
X250179Y-501103D01*
X250779Y-501903D01*
X251179Y-502836D01*
X251379Y-503903D01*
Y-504969D01*
X251179Y-506036D01*
X250779Y-506969D01*
X250179Y-507769D01*
X249479Y-508303D01*
X248679Y-508436D01*
G01X254079D02*
Y-500436D01*
X256679Y-507103D01*
X259279Y-500436D01*
Y-508436D01*
G01X241679Y-483436D02*
Y-475436D01*
X240479Y-477036D01*
G01Y-483436D02*
X242879D01*
G01X249679D02*
X250379Y-483303D01*
X251179Y-482903D01*
X251679Y-482236D01*
X251879Y-481303D01*
X251679Y-480370D01*
X251079Y-479569D01*
X250179Y-479169D01*
X249179D01*
X248579Y-478903D01*
X248079Y-478236D01*
X247879Y-477303D01*
X248179Y-476369D01*
X248879Y-475703D01*
X249679Y-475436D01*
X250479Y-475703D01*
X251179Y-476369D01*
X251479Y-477303D01*
X251279Y-478236D01*
X250779Y-478903D01*
X250179Y-479169D01*
X249179D01*
X248279Y-479569D01*
X247679Y-480370D01*
X247479Y-481303D01*
X247679Y-482236D01*
X248179Y-482903D01*
X248979Y-483303D01*
X249679Y-483436D01*
G01X326250Y-525312D02*
X326850Y-524512D01*
X327550Y-524112D01*
X328350Y-523979D01*
X329350Y-524246D01*
X330050Y-524912D01*
X330250Y-525712D01*
X330150Y-526513D01*
X329750Y-527179D01*
X327750Y-528512D01*
X326850Y-529446D01*
X326250Y-530779D01*
X326050Y-531979D01*
X330250D01*
G01X336150Y-523979D02*
X335350Y-524246D01*
X334750Y-524912D01*
X334350Y-525712D01*
X334050Y-526779D01*
X333950Y-527979D01*
X334050Y-529179D01*
X334350Y-530246D01*
X334750Y-531046D01*
X335350Y-531712D01*
X336150Y-531979D01*
X336950Y-531712D01*
X337550Y-531046D01*
X337950Y-530246D01*
X338250Y-529179D01*
X338350Y-527979D01*
X338250Y-526779D01*
X337950Y-525712D01*
X337550Y-524912D01*
X336950Y-524246D01*
X336150Y-523979D01*
G01X342250Y-525312D02*
X342850Y-524512D01*
X343550Y-524112D01*
X344350Y-523979D01*
X345350Y-524246D01*
X346050Y-524912D01*
X346250Y-525712D01*
X346150Y-526513D01*
X345750Y-527179D01*
X343750Y-528512D01*
X342850Y-529446D01*
X342250Y-530779D01*
X342050Y-531979D01*
X346250D01*
G01X349950Y-530379D02*
X350550Y-531312D01*
X351350Y-531846D01*
X352250Y-531979D01*
X353050Y-531846D01*
X353850Y-531179D01*
X354350Y-530379D01*
X354450Y-529579D01*
X354250Y-528646D01*
X353550Y-527979D01*
X352850Y-527712D01*
X351950D01*
G01X352850D02*
X353450Y-527312D01*
X353950Y-526646D01*
X354150Y-525846D01*
X353950Y-525046D01*
X353450Y-524379D01*
X352550Y-523979D01*
X351650Y-524112D01*
X350750Y-524646D01*
G01X358350Y-532246D02*
X361950Y-523979D01*
G01X368150D02*
X367350Y-524246D01*
X366750Y-524912D01*
X366350Y-525712D01*
X366050Y-526779D01*
X365950Y-527979D01*
X366050Y-529179D01*
X366350Y-530246D01*
X366750Y-531046D01*
X367350Y-531712D01*
X368150Y-531979D01*
X368950Y-531712D01*
X369550Y-531046D01*
X369950Y-530246D01*
X370250Y-529179D01*
X370350Y-527979D01*
X370250Y-526779D01*
X369950Y-525712D01*
X369550Y-524912D01*
X368950Y-524246D01*
X368150Y-523979D01*
G01X373950Y-530379D02*
X374550Y-531312D01*
X375350Y-531846D01*
X376250Y-531979D01*
X377050Y-531846D01*
X377850Y-531179D01*
X378350Y-530379D01*
X378450Y-529579D01*
X378250Y-528646D01*
X377550Y-527979D01*
X376850Y-527712D01*
X375950D01*
G01X376850D02*
X377450Y-527312D01*
X377950Y-526646D01*
X378150Y-525846D01*
X377950Y-525046D01*
X377450Y-524379D01*
X376550Y-523979D01*
X375650Y-524112D01*
X374750Y-524646D01*
G01X382350Y-532246D02*
X385950Y-523979D01*
G01X390250Y-525312D02*
X390850Y-524512D01*
X391550Y-524112D01*
X392350Y-523979D01*
X393350Y-524246D01*
X394050Y-524912D01*
X394250Y-525712D01*
X394150Y-526513D01*
X393750Y-527179D01*
X391750Y-528512D01*
X390850Y-529446D01*
X390250Y-530779D01*
X390050Y-531979D01*
X394250D01*
G01X401350D02*
Y-523979D01*
X397650Y-529712D01*
X402650D01*
G01X325950Y-506979D02*
Y-498979D01*
X327950D01*
X328750Y-499379D01*
X329350Y-499912D01*
X329850Y-500712D01*
X330250Y-501646D01*
X330350Y-502979D01*
X330250Y-504312D01*
X329850Y-505246D01*
X329350Y-506046D01*
X328750Y-506579D01*
X327950Y-506979D01*
X325950D01*
G01X333650D02*
X336150Y-498979D01*
X338650Y-506979D01*
G01X337750Y-504179D02*
X334550D01*
G01X344150Y-498979D02*
X343350Y-499246D01*
X342750Y-499912D01*
X342350Y-500712D01*
X342050Y-501779D01*
X341950Y-502979D01*
X342050Y-504179D01*
X342350Y-505246D01*
X342750Y-506046D01*
X343350Y-506712D01*
X344150Y-506979D01*
X344950Y-506712D01*
X345550Y-506046D01*
X345950Y-505246D01*
X346250Y-504179D01*
X346350Y-502979D01*
X346250Y-501779D01*
X345950Y-500712D01*
X345550Y-499912D01*
X344950Y-499246D01*
X344150Y-498979D01*
G01X350250Y-506979D02*
Y-498979D01*
X354050D01*
G01X352650Y-502846D02*
X350250D01*
G01X360150Y-498979D02*
X359350Y-499246D01*
X358750Y-499912D01*
X358350Y-500712D01*
X358050Y-501779D01*
X357950Y-502979D01*
X358050Y-504179D01*
X358350Y-505246D01*
X358750Y-506046D01*
X359350Y-506712D01*
X360150Y-506979D01*
X360950Y-506712D01*
X361550Y-506046D01*
X361950Y-505246D01*
X362250Y-504179D01*
X362350Y-502979D01*
X362250Y-501779D01*
X361950Y-500712D01*
X361550Y-499912D01*
X360950Y-499246D01*
X360150Y-498979D01*
G01X368150D02*
Y-506979D01*
G01X365850Y-498979D02*
X370450D01*
G01X373550Y-506979D02*
Y-498979D01*
X376150Y-505646D01*
X378750Y-498979D01*
Y-506979D01*
G01X384950Y-502712D02*
X385350Y-502312D01*
X385650Y-501646D01*
X385850Y-500712D01*
X385650Y-499912D01*
X385250Y-499379D01*
X384550Y-498979D01*
X381850D01*
Y-506979D01*
X385150D01*
X385850Y-506446D01*
X386250Y-505646D01*
X386450Y-504712D01*
X386250Y-503779D01*
X385650Y-502979D01*
X384950Y-502712D01*
X381850D01*
G01X390950Y-498979D02*
X393350D01*
G01X392150D02*
Y-506979D01*
G01X390950D02*
X393350D01*
G01X398150Y-505379D02*
X398650Y-506179D01*
X399250Y-506712D01*
X399950Y-506979D01*
X400750Y-506712D01*
X401350Y-506179D01*
X401950Y-505379D01*
X402150Y-504312D01*
Y-498979D01*
G01X408150D02*
X407350Y-499246D01*
X406750Y-499912D01*
X406350Y-500712D01*
X406050Y-501779D01*
X405950Y-502979D01*
X406050Y-504179D01*
X406350Y-505246D01*
X406750Y-506046D01*
X407350Y-506712D01*
X408150Y-506979D01*
X408950Y-506712D01*
X409550Y-506046D01*
X409950Y-505246D01*
X410250Y-504179D01*
X410350Y-502979D01*
X410250Y-501779D01*
X409950Y-500712D01*
X409550Y-499912D01*
X408950Y-499246D01*
X408150Y-498979D01*
G01X343750Y-481979D02*
Y-473979D01*
X347550D01*
G01X346150Y-477846D02*
X343750D01*
G01X353650Y-473979D02*
X352850Y-474246D01*
X352250Y-474912D01*
X351850Y-475712D01*
X351550Y-476779D01*
X351450Y-477979D01*
X351550Y-479179D01*
X351850Y-480246D01*
X352250Y-481046D01*
X352850Y-481712D01*
X353650Y-481979D01*
X354450Y-481712D01*
X355050Y-481046D01*
X355450Y-480246D01*
X355750Y-479179D01*
X355850Y-477979D01*
X355750Y-476779D01*
X355450Y-475712D01*
X355050Y-474912D01*
X354450Y-474246D01*
X353650Y-473979D01*
G01X361650D02*
Y-481979D01*
G01X359350Y-473979D02*
X363950D01*
G01X366650Y-484646D02*
X372650D01*
G01X375050Y-481979D02*
Y-473979D01*
X377650Y-480646D01*
X380250Y-473979D01*
Y-481979D01*
G01X386450Y-477712D02*
X386850Y-477312D01*
X387150Y-476646D01*
X387350Y-475712D01*
X387150Y-474912D01*
X386750Y-474379D01*
X386050Y-473979D01*
X383350D01*
Y-481979D01*
X386650D01*
X387350Y-481446D01*
X387750Y-480646D01*
X387950Y-479712D01*
X387750Y-478779D01*
X387150Y-477979D01*
X386450Y-477712D01*
X383350D01*
G01X390650Y-484646D02*
X396650D01*
G01X403650Y-481979D02*
X399650D01*
Y-473979D01*
X403650D01*
G01X402050Y-477846D02*
X399650D01*
G01X407050Y-481979D02*
Y-473979D01*
X409650Y-480646D01*
X412250Y-473979D01*
Y-481979D01*
G01X417650D02*
X418350Y-481846D01*
X419150Y-481446D01*
X419650Y-480779D01*
X419850Y-479846D01*
X419650Y-478913D01*
X419050Y-478112D01*
X418150Y-477712D01*
X417150D01*
X416550Y-477446D01*
X416050Y-476779D01*
X415850Y-475846D01*
X416150Y-474912D01*
X416850Y-474246D01*
X417650Y-473979D01*
X418450Y-474246D01*
X419150Y-474912D01*
X419450Y-475846D01*
X419250Y-476779D01*
X418750Y-477446D01*
X418150Y-477712D01*
X417150D01*
X416250Y-478112D01*
X415650Y-478913D01*
X415450Y-479846D01*
X415650Y-480779D01*
X416150Y-481446D01*
X416950Y-481846D01*
X417650Y-481979D01*
G01X423950Y-481046D02*
X424650Y-481712D01*
X425450Y-481979D01*
X426250Y-481712D01*
X426950Y-480913D01*
X427450Y-479712D01*
X427650Y-478512D01*
Y-477046D01*
X427450Y-475846D01*
X426950Y-474779D01*
X426350Y-474246D01*
X425650Y-473979D01*
X424850Y-474246D01*
X424250Y-474779D01*
X423850Y-475579D01*
X423650Y-476646D01*
X423850Y-477579D01*
X424350Y-478512D01*
X424950Y-479046D01*
X425650Y-479179D01*
X426450Y-478913D01*
X427050Y-478246D01*
X427650Y-477046D01*
G01X433650Y-473979D02*
X432850Y-474246D01*
X432250Y-474912D01*
X431850Y-475712D01*
X431550Y-476779D01*
X431450Y-477979D01*
X431550Y-479179D01*
X431850Y-480246D01*
X432250Y-481046D01*
X432850Y-481712D01*
X433650Y-481979D01*
X434450Y-481712D01*
X435050Y-481046D01*
X435450Y-480246D01*
X435750Y-479179D01*
X435850Y-477979D01*
X435750Y-476779D01*
X435450Y-475712D01*
X435050Y-474912D01*
X434450Y-474246D01*
X433650Y-473979D01*
G01X439450Y-481979D02*
Y-473979D01*
G01X443250D02*
X439450Y-478913D01*
G01X443850Y-481979D02*
X441150Y-476646D01*
G01X414650Y-534979D02*
Y-526979D01*
X413450Y-528579D01*
G01Y-534979D02*
X415850D01*
G01X420750Y-531646D02*
X421450Y-530712D01*
X422050Y-530179D01*
X422850Y-529912D01*
X423550Y-530179D01*
X424050Y-530712D01*
X424450Y-531512D01*
X424550Y-532446D01*
X424450Y-533246D01*
X424050Y-534046D01*
X423450Y-534712D01*
X422750Y-534979D01*
X421950Y-534712D01*
X421250Y-533913D01*
X420850Y-532712D01*
X420750Y-531379D01*
X420950Y-529646D01*
X421250Y-528712D01*
X421750Y-527779D01*
X422450Y-527112D01*
X423150Y-526979D01*
X423850Y-527246D01*
X424350Y-527912D01*
G01X430650Y-535246D02*
X430450Y-535112D01*
Y-534846D01*
X430650Y-534712D01*
X430850Y-534846D01*
Y-535112D01*
X430650Y-535246D01*
G01X436750Y-531646D02*
X437450Y-530712D01*
X438050Y-530179D01*
X438850Y-529912D01*
X439550Y-530179D01*
X440050Y-530712D01*
X440450Y-531512D01*
X440550Y-532446D01*
X440450Y-533246D01*
X440050Y-534046D01*
X439450Y-534712D01*
X438750Y-534979D01*
X437950Y-534712D01*
X437250Y-533913D01*
X436850Y-532712D01*
X436750Y-531379D01*
X436950Y-529646D01*
X437250Y-528712D01*
X437750Y-527779D01*
X438450Y-527112D01*
X439150Y-526979D01*
X439850Y-527246D01*
X440350Y-527912D01*
G01X459650Y-534979D02*
Y-526979D01*
X458450Y-528579D01*
G01Y-534979D02*
X460850D01*
G01X467450D02*
X467650Y-533246D01*
X467950Y-531779D01*
X468350Y-530446D01*
X468850Y-528979D01*
X469650Y-526979D01*
X465650D01*
G01X475650Y-535246D02*
X475450Y-535112D01*
Y-534846D01*
X475650Y-534712D01*
X475850Y-534846D01*
Y-535112D01*
X475650Y-535246D01*
G01X481750Y-528312D02*
X482350Y-527512D01*
X483050Y-527112D01*
X483850Y-526979D01*
X484850Y-527246D01*
X485550Y-527912D01*
X485750Y-528712D01*
X485650Y-529513D01*
X485250Y-530179D01*
X483250Y-531512D01*
X482350Y-532446D01*
X481750Y-533779D01*
X481550Y-534979D01*
X485750D01*
G01X479650Y-508379D02*
X480150Y-509179D01*
X480750Y-509712D01*
X481450Y-509979D01*
X482250Y-509712D01*
X482850Y-509179D01*
X483450Y-508379D01*
X483650Y-507312D01*
Y-501979D01*
G01X712222Y1570703D02*
X711582D01*
X710962Y1570083D01*
Y1566978D01*
X707717Y1563733D01*
G01X713052Y1579683D02*
X708612D01*
X704567Y1575638D01*
Y1563733D01*
G01X726677Y1569493D02*
X722727D01*
G01D02*
Y1572908D01*
X723942Y1574123D01*
G01X724392Y1604188D02*
X727382D01*
X729052Y1602518D01*
G01X757687Y1577203D02*
X758132D01*
X760112Y1579183D01*
G54D26*
X33583Y1256964D03*
Y1252965D03*
X48742Y393408D03*
X48575Y386993D03*
X49583Y1256964D03*
X65412Y443677D03*
X71374Y763164D03*
X63283Y1256964D03*
X87762Y659641D03*
Y663141D03*
X90024Y667952D03*
X91992Y673881D03*
Y677881D03*
X88962Y725640D03*
X92983Y1256964D03*
X79283D03*
X107934Y505374D03*
Y509374D03*
Y517925D03*
X99427Y649839D03*
X99497Y642149D03*
X99467Y646009D03*
X108983Y1256964D03*
X120208Y501638D03*
X120238Y507877D03*
Y512983D03*
X127084Y646822D03*
X125092Y667700D03*
X122683Y1256964D03*
Y1250499D03*
X143724Y1257952D03*
X157102Y511095D03*
X146982Y522771D03*
X146332Y694970D03*
X146232Y703270D03*
X152383Y1256964D03*
X152746Y1546009D03*
X145140Y1598155D03*
Y1602666D03*
X168383Y1256964D03*
X182083D03*
X198083D03*
X211783D03*
X241351Y1257456D03*
X227583Y1257520D03*
X257351Y1255756D03*
Y1251564D03*
X261750Y958053D03*
X330709Y205049D03*
X396393Y1412991D03*
Y1416491D03*
X414031Y929165D03*
X419915Y1415275D03*
X406388Y1418492D03*
X408004Y1413662D03*
X435809Y1626419D03*
X451984Y341362D03*
X449454Y1427968D03*
X461484Y341362D03*
X453033Y1411678D03*
X480907Y1402364D03*
X478384Y1408172D03*
X570449Y114132D03*
X570389Y109622D03*
X588490Y747887D03*
X611845Y145473D03*
X612012Y151888D03*
X613122Y774712D03*
X608614Y891364D03*
Y895384D03*
X619734Y34652D03*
X626774Y61272D03*
X619704Y442862D03*
Y457862D03*
Y452862D03*
Y447862D03*
Y462862D03*
X634704Y421362D03*
X649704Y416362D03*
Y431362D03*
Y457862D03*
Y452862D03*
Y447862D03*
Y462862D03*
X656213Y973428D03*
X656547Y989241D03*
Y985321D03*
X656483Y1256964D03*
X669464Y202362D03*
Y206362D03*
Y210362D03*
X673869Y1255932D03*
X687166Y35057D03*
X686183Y1256964D03*
X702747Y412255D03*
X702509Y417500D03*
X702469Y421540D03*
X711204Y484862D03*
Y488862D03*
X707996Y1595623D03*
X708203Y1641851D03*
X718984Y82562D03*
X717531Y412269D03*
X715883Y1256964D03*
X713704Y1301162D03*
Y1297162D03*
X725736Y1593913D03*
X741204Y408362D03*
Y404362D03*
X731944Y411382D03*
X745735Y1257681D03*
X732016Y1249625D03*
X750504Y74562D03*
X757596Y1581783D03*
Y1577203D03*
X763704Y413212D03*
Y408212D03*
Y423212D03*
Y418212D03*
X762824Y469862D03*
Y464862D03*
X777792Y484802D03*
X777824Y488862D03*
X762829Y501662D03*
X762841Y497658D03*
X770171Y753179D03*
X775283Y1256964D03*
X763301Y1257572D03*
X778797Y432665D03*
X791491Y432555D03*
X802004Y139262D03*
Y144262D03*
X800874Y308062D03*
X804983Y1256964D03*
X813148Y276820D03*
X813202Y284311D03*
X834683Y1256964D03*
X852715Y301542D03*
X852874Y308852D03*
X863049Y269220D03*
X895465Y506875D03*
X906058Y507348D03*
X906564Y500117D03*
Y503631D03*
X912068Y493611D03*
X922384Y986242D03*
X931409Y197612D03*
X937852Y505977D03*
X937847Y501925D03*
X937878Y498083D03*
X969273Y386189D03*
X958181Y403656D03*
Y399401D03*
X969284Y402017D03*
X969340Y398138D03*
X960090Y1559276D03*
X960130Y1563256D03*
X1003484Y380862D03*
X994484Y387362D03*
Y383362D03*
Y391362D03*
X994565Y400607D03*
X1004730Y422682D03*
X1015814Y194609D03*
X1018747Y420548D03*
X1009719Y1257810D03*
Y1253869D03*
X1022644Y194609D03*
X1025725Y1256944D03*
X1031939Y1251503D03*
X1039425Y1256944D03*
X1069125D03*
Y1251277D03*
X1098825Y1256944D03*
X1095456Y1251409D03*
X1119891Y1253449D03*
X1128525Y1256944D03*
X1134945Y1251483D03*
X1158225Y1256944D03*
X1174484Y1020362D03*
X1191642Y220362D03*
X1196257Y588714D03*
X1187925Y1256944D03*
X1204371Y599133D03*
X1204731Y605605D03*
X1230577Y116962D03*
X1231577Y134262D03*
X1220217Y126942D03*
X1220184Y134600D03*
X1220214Y130810D03*
X1232107Y156672D03*
X1233494Y192482D03*
X1242204Y193362D03*
X1242077Y217462D03*
X1242104Y221562D03*
X1253069Y120107D03*
X1253070Y124107D03*
X1255637Y752449D03*
X1272848Y196622D03*
X1273077Y229462D03*
Y225462D03*
X1316191Y731375D03*
X1326267Y737747D03*
X1345075Y120618D03*
X1337093Y179062D03*
Y183068D03*
X1343570Y195530D03*
X1337219Y187059D03*
X1337181Y191009D03*
X1343521Y199534D03*
X1342118Y212239D03*
X1333784Y204900D03*
X1359046Y128285D03*
X1352076Y124718D03*
X1365646Y124123D03*
Y128285D03*
X1373450Y1402334D03*
X1372534Y1416491D03*
Y1412791D03*
X1390371Y928806D03*
X1396056Y1415275D03*
X1384429Y1413792D03*
Y1417304D03*
X1425465Y1427948D03*
X1429584Y721944D03*
X1429581Y717865D03*
X1434744Y732212D03*
X1429160Y1412108D03*
X1456204Y149362D03*
Y153362D03*
Y161862D03*
Y165862D03*
Y157862D03*
Y173862D03*
Y177862D03*
Y181862D03*
Y169862D03*
X1454457Y1408139D03*
X1467704Y145362D03*
X1463191Y746305D03*
X1484533Y309257D03*
X1592082Y215568D03*
X1592062Y207567D03*
X1592046Y235982D03*
X1607404Y725062D03*
X1613004Y583362D03*
X1632625Y1256944D03*
X1643203Y647963D03*
X1649282Y653741D03*
X1643203Y681963D03*
X1649282Y687742D03*
X1649400Y721761D03*
X1643203Y715963D03*
X1648710Y1257492D03*
X1670017Y539680D03*
X1669531Y534524D03*
X1657713Y536071D03*
Y532071D03*
X1669987Y528335D03*
X1657713Y544622D03*
X1662325Y1256944D03*
X1682162Y479078D03*
Y482590D03*
X1697654Y198330D03*
X1697634Y202470D03*
X1696706Y475583D03*
X1696670Y486806D03*
X1697444Y481422D03*
X1696760Y537507D03*
X1692025Y1256944D03*
X1716247Y39654D03*
Y43654D03*
Y47654D03*
Y51654D03*
X1707054Y199720D03*
X1721725Y1256944D03*
X1751425D03*
X1761096Y716448D03*
X1761196Y724648D03*
X1781125Y1256944D03*
X1796773Y1253019D03*
Y1256819D03*
X1812806Y1510437D03*
G54D80*
X769895Y281705D03*
Y279146D03*
Y276587D03*
Y274028D03*
Y271469D03*
Y286823D03*
Y284264D03*
X764977Y298790D03*
Y296231D03*
Y311585D03*
Y309026D03*
Y306467D03*
Y303908D03*
Y301349D03*
X792895Y271469D03*
Y274028D03*
Y276587D03*
Y279146D03*
Y281705D03*
Y284264D03*
Y286823D03*
X787977Y296231D03*
Y298790D03*
Y301349D03*
Y303908D03*
Y306467D03*
Y309026D03*
Y311585D03*
X812499Y299070D03*
Y296511D03*
Y311865D03*
Y309306D03*
Y306747D03*
Y304188D03*
Y301629D03*
X822500Y281507D03*
Y278948D03*
Y276389D03*
Y273830D03*
Y271271D03*
Y286625D03*
Y284066D03*
X835499Y296511D03*
Y299070D03*
Y301629D03*
Y304188D03*
Y306747D03*
Y309306D03*
Y311865D03*
X845500Y271271D03*
Y273830D03*
Y276389D03*
Y278948D03*
Y281507D03*
Y284066D03*
Y286625D03*
G54D53*
X306772Y991220D03*
X350099Y811121D03*
X356063Y1171318D03*
X531240Y811121D03*
X525276Y1171318D03*
X574567Y991220D03*
X1282914D03*
X1326240Y811121D03*
X1332205Y1171318D03*
X1507382Y811121D03*
X1501418Y1171318D03*
X1550709Y991220D03*
G54D44*
X177043Y1409115D03*
X184043D03*
X205538Y698226D03*
X219563Y586471D03*
X212563D03*
X219563Y594877D03*
X212563D03*
X219563Y620471D03*
X212563D03*
X219563Y628877D03*
X212563D03*
X219563Y654471D03*
X212563D03*
X219563Y662877D03*
X212563D03*
X212538Y698226D03*
X225113Y1409935D03*
X218113D03*
X240518Y671881D03*
X238478Y699357D03*
X255965Y70636D03*
X255669Y78930D03*
X244518Y568690D03*
X251518D03*
X244518Y602690D03*
X251518D03*
X244518Y595420D03*
X251518D03*
X244518Y636690D03*
X251518D03*
X244518Y629420D03*
X251518D03*
X247518Y671881D03*
X243218Y663720D03*
X250218D03*
X245478Y699357D03*
X262965Y70636D03*
X262669Y78930D03*
X400026Y1157520D03*
Y1165570D03*
X421252Y834842D03*
Y827536D03*
X407772D03*
X414772D03*
X407772Y834842D03*
X414772D03*
X412232Y1032870D03*
X419232D03*
X407026Y1157520D03*
X412526D03*
X419526D03*
X407026Y1165570D03*
X412526D03*
X419526D03*
X428252Y834842D03*
Y827536D03*
X434732D03*
X434729Y834842D03*
X437526Y1157520D03*
X432026D03*
X425026D03*
X432026Y1165570D03*
X425026D03*
X437526D03*
X448212Y827536D03*
X448209Y834842D03*
X441732Y827536D03*
X441729Y834842D03*
X444526Y1157520D03*
X450026D03*
X444526Y1165570D03*
X450026D03*
X461689Y834842D03*
X468689D03*
X461692Y827536D03*
X468692D03*
X455212D03*
X455209Y834842D03*
X468451Y1032870D03*
X461451D03*
X457026Y1157520D03*
X462526D03*
X469526D03*
X457026Y1165570D03*
X462526D03*
X469526D03*
X482169Y834842D03*
X475169D03*
X482172Y827536D03*
X475172D03*
X482026Y1157520D03*
X475026D03*
X482026Y1165570D03*
X475026D03*
X562617Y1321370D03*
Y1330170D03*
X569617Y1321370D03*
Y1330170D03*
X685420Y97062D03*
X692420D03*
X697662Y1409840D03*
X690662D03*
X739880Y1409905D03*
X732880D03*
X940761Y975162D03*
X933761D03*
X1069118Y269600D03*
X1068799Y280874D03*
X1076118Y269600D03*
X1075799Y280874D03*
X1150254Y1445544D03*
X1167444Y182685D03*
X1157254Y1445544D03*
X1174444Y182685D03*
X1193073Y200486D03*
X1186073D03*
X1193069Y193180D03*
X1186069D03*
X1200192Y1437872D03*
X1193192D03*
X1376167Y1157519D03*
Y1165569D03*
X1397393Y827535D03*
Y834841D03*
X1383913D03*
X1390913D03*
X1383913Y827535D03*
X1390913D03*
X1388373Y1032869D03*
X1395373D03*
X1383167Y1157519D03*
X1388667D03*
X1395667D03*
X1383167Y1165569D03*
X1388667D03*
X1395667D03*
X1410873Y827535D03*
X1410870Y834841D03*
X1404393Y827535D03*
Y834841D03*
X1408167Y1157519D03*
X1401167D03*
X1413667D03*
X1408167Y1165569D03*
X1401167D03*
X1413667D03*
X1424353Y827535D03*
X1424350Y834841D03*
X1417873Y827535D03*
X1417870Y834841D03*
X1420667Y1157519D03*
X1426167D03*
X1420667Y1165569D03*
X1426167D03*
X1437833Y827535D03*
X1444833D03*
X1437830Y834841D03*
X1444830D03*
X1431353Y827535D03*
X1431350Y834841D03*
X1444592Y1032869D03*
X1437592D03*
X1433167Y1157519D03*
X1438667D03*
X1445667D03*
X1433167Y1165569D03*
X1438667D03*
X1445667D03*
X1458310Y834841D03*
X1451310D03*
X1458313Y827535D03*
X1451313D03*
X1458167Y1157519D03*
X1451167D03*
X1458167Y1165569D03*
X1451167D03*
X1478658Y293756D03*
X1478758Y285556D03*
X1478658Y301956D03*
X1485658Y293756D03*
X1485758Y285556D03*
X1485858Y316356D03*
X1478858D03*
X1485658Y301956D03*
X1537508Y1330120D03*
Y1338920D03*
X1544508Y1330120D03*
Y1338920D03*
X1607955Y589185D03*
Y616701D03*
X1602455Y624862D03*
Y658862D03*
Y651592D03*
Y685592D03*
Y692862D03*
Y719592D03*
X1614955Y589185D03*
Y616701D03*
X1609455Y624862D03*
Y658862D03*
Y651592D03*
Y685592D03*
Y692862D03*
Y719592D03*
X1634410Y625705D03*
X1641410D03*
X1634410Y634111D03*
X1641410D03*
X1634410Y668111D03*
X1641410D03*
X1634410Y659705D03*
X1641410D03*
X1634410Y693705D03*
X1641410D03*
X1634410Y702111D03*
X1641410D03*
X1644435Y590356D03*
X1651435D03*
X1651828Y1442736D03*
X1658828D03*
X1701327Y1443735D03*
X1694327D03*
X1729326Y71930D03*
X1736326D03*
X1729130Y80364D03*
X1736130D03*
X1755271Y708121D03*
X1762477Y699940D03*
X1755477D03*
X1762271Y708121D03*
G54D35*
X109087Y522620D03*
X144640Y510230D03*
X338667Y772452D03*
X341527Y778362D03*
X358902Y773352D03*
X372117Y778576D03*
X381010Y734732D03*
X402700Y234167D03*
X420865Y215067D03*
X433695Y209862D03*
X426490Y244262D03*
X452071Y254862D03*
X461900Y215244D03*
X466300Y217803D03*
X461900Y222921D03*
X466300Y225480D03*
X461736Y301098D03*
X463198Y311587D03*
X470780Y1406980D03*
X486800Y259162D03*
X478500Y258862D03*
X474736Y302098D03*
X479736Y303598D03*
Y308598D03*
X472960Y602152D03*
X498700Y212685D03*
Y220362D03*
X503100Y215244D03*
Y222921D03*
X496028Y258590D03*
X495136Y300398D03*
X495036Y310398D03*
X508500Y232862D03*
X508502Y298813D03*
X508500Y303362D03*
X508136Y309398D03*
X536420Y309422D03*
X563482Y40826D03*
X558058Y46352D03*
X567865Y92656D03*
X570150Y102862D03*
X607630Y39662D03*
X606880Y44682D03*
X638281Y1254922D03*
X831705Y593877D03*
X859888Y593970D03*
X911340Y502872D03*
X912828Y498251D03*
X933012Y516711D03*
X970207Y1562731D03*
X1045760Y596272D03*
X1051680Y614772D03*
X1144810Y613762D03*
X1291306Y863361D03*
X1287674Y856290D03*
X1305288Y858104D03*
X1328187Y774757D03*
X1347640Y101950D03*
X1413900Y225212D03*
X1415340Y231812D03*
X1431430Y256383D03*
Y264060D03*
X1457361Y205982D03*
X1459961Y210432D03*
X1456150Y214382D03*
X1456770Y342942D03*
X1462790Y359042D03*
X1462870Y355012D03*
X1455920Y373941D03*
X1455642Y409646D03*
X1456777Y418596D03*
Y426546D03*
X1467761Y205982D03*
X1471308Y230640D03*
X1471690Y259862D03*
X1467700Y370953D03*
X1472758Y370817D03*
X1465836Y408668D03*
X1470942Y409718D03*
X1475250Y401812D03*
X1481766Y372288D03*
X1489443D03*
X1481766Y406238D03*
X1490384Y407292D03*
X1486880Y416863D03*
X1508959Y215802D03*
X1499922Y211240D03*
X1504484Y234562D03*
X1508410Y230842D03*
X1510017Y225516D03*
X1501840Y225502D03*
X1510810Y249742D03*
X1509040Y243362D03*
X1504890Y249862D03*
X1506600Y239092D03*
X1498184Y361723D03*
Y369798D03*
X1524539Y215551D03*
X1522009Y210825D03*
X1518110Y215551D03*
X1526998Y209645D03*
X1527732Y219488D03*
X1526152Y225114D03*
X1533385Y193108D03*
X1533148Y211614D03*
X1531824Y207677D03*
X1534194Y217519D03*
X1535561Y225393D03*
X1531110Y264862D03*
X1539150Y267132D03*
X1551160Y189342D03*
X1557900Y220362D03*
X1557760Y214792D03*
X1550353Y217352D03*
X1559400Y229832D03*
X1573560Y245078D03*
X1574760Y251032D03*
X1604240Y238242D03*
X1658450Y549550D03*
X1689093Y474538D03*
G54D71*
X676508Y224606D03*
G54D62*
X450000Y278543D03*
X460000D03*
X470000D03*
X483500Y246362D03*
X480000Y278543D03*
X493500Y246362D03*
X490000Y278543D03*
X500000D03*
X510000D03*
X518563Y607067D03*
X508563D03*
X559236Y1441207D03*
X569236D03*
X688500Y1601900D03*
Y1611900D03*
X1041435Y143357D03*
Y153357D03*
X1056225Y143131D03*
Y153131D03*
X1099970Y1702570D03*
Y1712570D03*
X1689646Y115669D03*
X1679646D03*
X1689646Y125669D03*
Y135669D03*
X1679646Y125669D03*
Y135669D03*
X1689646Y145669D03*
Y155669D03*
X1679646Y145669D03*
Y155669D03*
X1689646Y165669D03*
X1679646D03*
X1689646Y175669D03*
X1771457Y1634646D03*
Y1644646D03*
G54D17*
X44396Y444564D03*
Y442989D03*
Y441415D03*
Y439840D03*
X50696D03*
Y441415D03*
Y442989D03*
Y444564D03*
X550700Y114289D03*
Y112714D03*
Y111140D03*
Y109565D03*
X557000D03*
Y111140D03*
Y112714D03*
Y114289D03*
G54D129*
G01X402962Y1006093D02*
X402950Y1006049D01*
X400251Y1004490D01*
G02X398336I-958J1659D01*
G01X398233Y1004549D01*
G03X396590I-822J-1419D01*
G01X396449Y1004468D01*
G02X394636Y1004490I-887J1625D01*
G03X392786I-925J-1602D01*
G02X390936I-925J1603D01*
G01X390898Y1004512D01*
G03X389087Y1004490I-886J-1624D01*
G01X389049Y1004468D01*
G02X388486Y1004235I-563J563D01*
G01X387947D01*
G02X387449Y1004368I-1J995D01*
G01X387237Y1004491D01*
G03X385440Y1004522I-926J-1603D01*
G01X385387Y1004491D01*
G02X383537I-925J1602D01*
G03X381724Y1004513I-926J-1603D01*
G01X381686Y1004491D01*
G02X379875Y1004469I-925J1602D01*
G01X379837Y1004491D01*
G03X377987I-925J-1603D01*
G02X376137I-925J1602D01*
G03X374324Y1004513I-926J-1603D01*
G01X374183Y1004432D01*
G02X372540I-822J1419D01*
G01X372437Y1004491D01*
G03X370522I-958J-1659D01*
G01X367823Y1002932D01*
X367811Y1002888D01*
G01X502862Y1006093D02*
X502850Y1006049D01*
X500151Y1004490D01*
G02X498236I-957J1659D01*
G01X498133Y1004549D01*
G03X496490I-821J-1419D01*
G01X496349Y1004468D01*
G02X494536Y1004490I-887J1625D01*
G03X492686I-925J-1602D01*
G02X490836I-925J1603D01*
G01X490798Y1004512D01*
G03X488987Y1004490I-886J-1624D01*
G01X488949Y1004468D01*
G02X487136Y1004490I-887J1625D01*
G03X485286I-925J-1602D01*
G01X485233Y1004459D01*
G02X483436Y1004490I-871J1634D01*
G03X481586I-925J-1602D01*
G01X481545Y1004466D01*
X480120Y1004282D01*
G03X479700Y1004041I81J-628D01*
G01X478811Y1002888D01*
G01X1379104Y1006093D02*
X1379092Y1006049D01*
X1376393Y1004490D01*
G02X1374478I-957J1659D01*
G01X1374375Y1004549D01*
G03X1372732I-821J-1419D01*
G01X1372591Y1004468D01*
G02X1370778Y1004490I-887J1625D01*
G03X1368928I-925J-1602D01*
G02X1367078I-925J1603D01*
G01X1367040Y1004512D01*
G03X1365229Y1004490I-886J-1624D01*
G01X1365191Y1004468D01*
G02X1364628Y1004235I-563J563D01*
G01X1364089D01*
G02X1363591Y1004368I-1J995D01*
G01X1363379Y1004491D01*
G03X1361582Y1004522I-926J-1603D01*
G01X1361529Y1004491D01*
G02X1359679I-925J1602D01*
G03X1357866Y1004513I-926J-1603D01*
G01X1357828Y1004491D01*
G02X1356017Y1004469I-925J1602D01*
G01X1355979Y1004491D01*
G03X1354129I-925J-1603D01*
G02X1352279I-925J1602D01*
G03X1350466Y1004513I-926J-1603D01*
G01X1350325Y1004432D01*
G02X1348682I-821J1419D01*
G01X1348579Y1004491D01*
G03X1346664I-958J-1659D01*
G01X1343965Y1002932D01*
X1343953Y1002888D01*
G01X1479004Y1006093D02*
X1478992Y1006049D01*
X1476293Y1004490D01*
G02X1474378I-958J1659D01*
G01X1474275Y1004549D01*
G03X1472632I-821J-1419D01*
G01X1472491Y1004468D01*
G02X1470678Y1004490I-887J1625D01*
G03X1468828I-925J-1602D01*
G02X1466978I-925J1603D01*
G01X1466940Y1004512D01*
G03X1465129Y1004490I-886J-1624D01*
G01X1465091Y1004468D01*
G02X1463278Y1004490I-887J1625D01*
G03X1461428I-925J-1602D01*
G01X1461375Y1004459D01*
G02X1459578Y1004490I-871J1634D01*
G03X1457728I-925J-1602D01*
G01X1457687Y1004466D01*
X1456262Y1004282D01*
G03X1455842Y1004041I81J-628D01*
G01X1454953Y1002888D01*
G01X1924695Y1670036D02*
Y1375398D01*
X1925677Y1374416D01*
X1933653D01*
X1934695Y1375458D01*
Y1670036D01*
G54D36*
X150927Y1237271D03*
Y1246719D03*
X268597Y1255061D03*
Y1264509D03*
X833207Y1239961D03*
Y1249409D03*
X1127069Y1237271D03*
Y1246719D03*
X1216149Y1239961D03*
Y1249409D03*
X1780500Y314299D03*
Y323747D03*
X1809349Y1236461D03*
Y1245909D03*
G54D81*
X771724Y763455D03*
Y758337D03*
X778724D03*
Y760896D03*
Y763455D03*
G54D27*
X32099Y1269464D03*
Y1262464D03*
X48099Y1269464D03*
Y1262464D03*
X61799Y1269464D03*
Y1262464D03*
X77799Y1269464D03*
Y1262464D03*
X91499Y1269464D03*
Y1262464D03*
X86520Y1531262D03*
Y1538262D03*
X107499Y1269464D03*
Y1262464D03*
X121199Y1269464D03*
Y1262464D03*
X137199Y1269464D03*
Y1262464D03*
X133914Y1562234D03*
Y1555234D03*
X150899Y1269464D03*
Y1262464D03*
X149669Y1354514D03*
Y1361514D03*
X166899Y1269464D03*
Y1262464D03*
X177239Y1354514D03*
Y1361514D03*
X168058Y1388498D03*
X176464D03*
X168058Y1395498D03*
X176464D03*
X180599Y1269464D03*
Y1262464D03*
X188215Y1354514D03*
Y1361514D03*
X210299Y1269464D03*
Y1262464D03*
X196599Y1269464D03*
Y1262464D03*
X206201Y1388498D03*
Y1395498D03*
X226448Y1011928D03*
Y1018928D03*
X226299Y1269464D03*
Y1262464D03*
X219980Y1353391D03*
Y1360391D03*
X214607Y1388498D03*
Y1395498D03*
X240072Y983774D03*
Y990774D03*
X239658Y1014086D03*
Y1021086D03*
X239999Y1269464D03*
Y1262464D03*
X256172Y983874D03*
Y990874D03*
X255528Y1014109D03*
X248102Y1014079D03*
X255528Y1021109D03*
X248102Y1021079D03*
X255999Y1269464D03*
Y1262464D03*
X321581Y1308970D03*
Y1301970D03*
X314318Y1308998D03*
Y1301998D03*
X322041Y1346644D03*
Y1353644D03*
X323544Y1368887D03*
Y1361887D03*
X335988Y1289012D03*
Y1296012D03*
X330447Y1346644D03*
Y1353644D03*
X354169Y1323846D03*
X355672Y1339089D03*
X354169Y1330846D03*
X355672Y1346089D03*
X363518Y1289012D03*
Y1296012D03*
X362575Y1323846D03*
Y1330846D03*
X376437Y1275059D03*
X384837D03*
X376437Y1282059D03*
X384837D03*
X387800Y1325663D03*
X386033Y1310043D03*
Y1317043D03*
X387800Y1332663D03*
X397518Y1275059D03*
Y1282059D03*
X394469Y1310043D03*
Y1317043D03*
X409367Y946135D03*
X416247Y946085D03*
X409061Y967360D03*
Y960360D03*
X416061Y967360D03*
Y960360D03*
X409367Y953135D03*
X416247Y953085D03*
X416061Y981840D03*
Y974840D03*
X409061Y981840D03*
Y974840D03*
Y996320D03*
Y989320D03*
X416061Y996320D03*
Y989320D03*
Y1010800D03*
Y1003800D03*
X409061D03*
Y1010800D03*
Y1025284D03*
Y1018284D03*
X416061Y1018280D03*
Y1025280D03*
X419928Y1325663D03*
X418425Y1310043D03*
Y1317043D03*
X419928Y1332663D03*
X423061Y933680D03*
Y946180D03*
Y940680D03*
Y967360D03*
Y960360D03*
Y953180D03*
Y981840D03*
Y974840D03*
Y996320D03*
Y989320D03*
Y1010800D03*
Y1003800D03*
Y1018280D03*
Y1025280D03*
X433274Y1275209D03*
X425274D03*
X433274Y1282209D03*
X425274D03*
X426831Y1310043D03*
Y1317043D03*
X450553Y1310420D03*
Y1317420D03*
X452056Y1325663D03*
Y1332663D03*
X458280Y932398D03*
X465107Y945885D03*
X458280Y945880D03*
Y939398D03*
X465280Y967360D03*
Y960360D03*
X458280Y967360D03*
Y960360D03*
X465107Y952885D03*
X458280Y952880D03*
Y981840D03*
Y974840D03*
X465280Y981840D03*
Y974840D03*
X458280Y996320D03*
Y989320D03*
X465280Y996320D03*
Y989320D03*
Y1010800D03*
Y1003800D03*
X458280Y1010800D03*
Y1003800D03*
X465280Y1018280D03*
Y1025280D03*
X458280Y1018280D03*
Y1025280D03*
X462713Y1275209D03*
Y1282209D03*
X458959Y1310420D03*
Y1317420D03*
X471917Y945805D03*
X472280Y967360D03*
Y960360D03*
X471917Y952805D03*
X472280Y981840D03*
Y974840D03*
Y996320D03*
Y989320D03*
Y1010800D03*
Y1003800D03*
Y1018280D03*
Y1025280D03*
X475821Y1275209D03*
X484221D03*
X475821Y1282209D03*
X484221D03*
X482681Y1310420D03*
Y1317420D03*
X483442Y1325423D03*
Y1332423D03*
X486773Y1440292D03*
Y1447292D03*
X496228Y1289012D03*
Y1296012D03*
X491087Y1310420D03*
Y1317420D03*
X495173Y1440292D03*
Y1447292D03*
X514809Y1323846D03*
X515199Y1339878D03*
X514809Y1330846D03*
X515199Y1346878D03*
X503573Y1440292D03*
Y1447292D03*
X523897Y1289012D03*
Y1296012D03*
X523215Y1323846D03*
Y1330846D03*
X537077Y1316970D03*
Y1309970D03*
X543907Y1316950D03*
Y1309950D03*
X546937Y1346644D03*
Y1353644D03*
X547327Y1369676D03*
Y1362676D03*
X555343Y1346644D03*
Y1353644D03*
X625355Y983045D03*
Y990045D03*
X625340Y1011835D03*
Y1018835D03*
X625299Y1269464D03*
Y1262464D03*
X641560Y981934D03*
Y988934D03*
X641044Y1013821D03*
X648527Y1013299D03*
Y1006299D03*
X633435Y1013821D03*
X641044Y1020821D03*
X633435D03*
X641299Y1269464D03*
Y1262464D03*
X654999Y1269464D03*
Y1262464D03*
X663288Y1354539D03*
Y1361539D03*
X670999Y1269464D03*
Y1262464D03*
X681677Y1388623D03*
Y1395623D03*
X684699Y1269464D03*
Y1262464D03*
X690826Y1354539D03*
Y1361539D03*
X690083Y1389123D03*
Y1396123D03*
X700699Y1269464D03*
Y1262464D03*
X714399Y1269464D03*
Y1262464D03*
X702239Y1354539D03*
Y1361539D03*
X730399Y1269464D03*
Y1262464D03*
X719820Y1388523D03*
X728226D03*
X719820Y1395523D03*
X728226D03*
X744099Y1269464D03*
Y1262464D03*
X733588Y1353416D03*
Y1360416D03*
X760099Y1269464D03*
Y1262464D03*
X773799Y1269464D03*
Y1262464D03*
X789799Y1269464D03*
Y1262464D03*
X803499Y1269464D03*
Y1262464D03*
X819499Y1269464D03*
Y1262464D03*
X833199Y1269464D03*
Y1262464D03*
X840246Y1269464D03*
Y1262464D03*
X968580Y211799D03*
Y204799D03*
X1015841Y1269344D03*
Y1262344D03*
X1024241Y1269444D03*
Y1262444D03*
X1037941Y1269444D03*
Y1262444D03*
X1053941Y1269444D03*
Y1262444D03*
X1067641Y1269444D03*
Y1262444D03*
X1083641Y1269444D03*
Y1262444D03*
X1097341Y1269444D03*
Y1262444D03*
X1113341Y1269444D03*
Y1262444D03*
X1127041Y1269444D03*
Y1262444D03*
X1122980Y1397844D03*
Y1390844D03*
X1143041Y1269444D03*
Y1262444D03*
X1150518Y1397844D03*
Y1390844D03*
X1149775Y1424827D03*
Y1431827D03*
X1141369Y1424827D03*
Y1431827D03*
X1156741Y1269444D03*
Y1262444D03*
X1161931Y1397844D03*
Y1390844D03*
X1186441Y1269444D03*
Y1262444D03*
X1172741Y1269444D03*
Y1262444D03*
X1179512Y1424827D03*
Y1431827D03*
X1202641Y1013744D03*
Y1020744D03*
X1202441Y1269444D03*
Y1262444D03*
X1193280Y1389721D03*
Y1396721D03*
X1187918Y1424827D03*
Y1431827D03*
X1216152Y983844D03*
Y990844D03*
X1215841Y1013744D03*
Y1020744D03*
X1216141Y1269444D03*
Y1262444D03*
X1232241Y983844D03*
Y990844D03*
X1232341Y1013744D03*
X1224241D03*
X1232341Y1020744D03*
X1224241D03*
X1232141Y1269444D03*
Y1262444D03*
X1263333Y267106D03*
Y260106D03*
X1270404Y267032D03*
Y260032D03*
X1289459Y1316998D03*
Y1309998D03*
X1296722Y1316970D03*
Y1309970D03*
X1298182Y1346644D03*
Y1353644D03*
X1299685Y1368887D03*
Y1361887D03*
X1312529Y1289012D03*
Y1296012D03*
X1306588Y1346644D03*
Y1353644D03*
X1330310Y1323846D03*
Y1330846D03*
X1331813Y1339089D03*
Y1346089D03*
X1340059Y1289012D03*
Y1296012D03*
X1338716Y1323846D03*
Y1330846D03*
X1352458Y1275529D03*
X1360858D03*
X1352458Y1282529D03*
X1360858D03*
X1362174Y1310043D03*
Y1317043D03*
X1363941Y1325496D03*
Y1332496D03*
X1379212Y210814D03*
Y217814D03*
X1373739Y1275529D03*
Y1282529D03*
X1370610Y1310043D03*
Y1317043D03*
X1386212Y210814D03*
Y217814D03*
X1392357Y945865D03*
X1385547Y946105D03*
X1392202Y967359D03*
Y960359D03*
X1392357Y952865D03*
X1385202Y967359D03*
Y960359D03*
X1385547Y953105D03*
X1392202Y981839D03*
Y974839D03*
X1385202Y981839D03*
Y974839D03*
X1392202Y996319D03*
Y989319D03*
X1385202Y996319D03*
Y989319D03*
X1392202Y1010799D03*
Y1003799D03*
X1385202D03*
Y1010799D03*
X1392202Y1018279D03*
Y1025279D03*
X1385202Y1025283D03*
Y1018283D03*
X1394566Y1310043D03*
Y1317043D03*
X1396069Y1325496D03*
Y1332496D03*
X1399202Y933379D03*
Y945879D03*
Y940379D03*
Y967359D03*
Y960359D03*
Y952879D03*
Y981839D03*
Y974839D03*
Y996319D03*
Y989319D03*
Y1010799D03*
Y1003799D03*
Y1018279D03*
Y1025279D03*
X1409295Y1275679D03*
X1401235D03*
X1409295Y1282679D03*
X1401235D03*
X1402972Y1310043D03*
Y1317043D03*
X1426694Y1310420D03*
Y1317420D03*
X1428197Y1325496D03*
Y1332496D03*
X1434421Y932397D03*
X1441287Y945975D03*
X1434421Y945879D03*
Y939397D03*
X1441421Y967359D03*
Y960359D03*
X1441287Y952975D03*
X1434421Y967359D03*
Y960359D03*
Y952879D03*
X1441421Y981839D03*
Y974839D03*
X1434421Y981839D03*
Y974839D03*
X1441421Y996319D03*
Y989319D03*
X1434421Y996319D03*
Y989319D03*
X1441421Y1010799D03*
Y1003799D03*
X1434421Y1010799D03*
Y1003799D03*
X1441421Y1018279D03*
Y1025279D03*
X1434421Y1018279D03*
Y1025279D03*
X1438734Y1275679D03*
Y1282679D03*
X1435100Y1310420D03*
Y1317420D03*
X1448127Y945775D03*
X1448421Y967359D03*
Y960359D03*
X1448127Y952775D03*
X1448421Y981839D03*
Y974839D03*
Y996319D03*
Y989319D03*
Y1010799D03*
Y1003799D03*
Y1018279D03*
Y1025279D03*
X1451842Y1275679D03*
X1460242D03*
X1451842Y1282679D03*
X1460242D03*
X1458822Y1310420D03*
Y1317420D03*
X1459583Y1325423D03*
Y1332423D03*
X1472449Y1289012D03*
Y1296012D03*
X1467228Y1310420D03*
Y1317420D03*
X1463294Y1440419D03*
Y1447419D03*
X1471694Y1440419D03*
Y1447419D03*
X1490950Y1323846D03*
Y1330846D03*
X1491340Y1339878D03*
Y1346878D03*
X1480094Y1440419D03*
Y1447419D03*
X1499912Y1290405D03*
Y1297405D03*
X1499247Y1323906D03*
Y1330906D03*
X1513718Y1308970D03*
Y1301970D03*
X1520528Y1309020D03*
Y1302020D03*
X1523078Y1346644D03*
Y1353644D03*
X1523468Y1368876D03*
Y1361876D03*
X1531456Y1346644D03*
Y1353644D03*
X1601397Y983725D03*
Y990725D03*
X1609477Y1013501D03*
X1601482Y1011815D03*
X1609477Y1020501D03*
X1601482Y1018815D03*
X1601441Y1269444D03*
Y1262444D03*
X1617526Y983867D03*
Y990867D03*
X1624206Y1013879D03*
Y1006879D03*
X1617386Y1013066D03*
Y1020066D03*
X1617441Y1269444D03*
Y1262444D03*
X1624454Y1387285D03*
Y1394285D03*
X1631141Y1269444D03*
Y1262444D03*
X1647141Y1269444D03*
Y1262444D03*
X1651992Y1387285D03*
Y1394285D03*
X1651249Y1422119D03*
X1642843D03*
X1651249Y1429119D03*
X1642843D03*
X1660841Y1269444D03*
Y1262444D03*
X1663405Y1387285D03*
Y1394285D03*
X1690541Y1269444D03*
Y1262444D03*
X1676841Y1269444D03*
Y1262444D03*
X1680986Y1422119D03*
X1689392D03*
X1680986Y1429119D03*
X1689392D03*
X1706541Y1269444D03*
Y1262444D03*
X1694954Y1386162D03*
Y1393162D03*
X1720241Y1269444D03*
Y1262444D03*
X1736241Y1269444D03*
Y1262444D03*
X1749941Y1269444D03*
Y1262444D03*
X1770898Y233128D03*
Y226128D03*
X1762878Y233128D03*
Y226128D03*
X1765941Y1269444D03*
Y1262444D03*
X1779378Y233128D03*
Y226128D03*
X1784810Y276992D03*
Y283992D03*
X1779641Y1269444D03*
Y1262444D03*
X1791850Y277002D03*
Y284002D03*
X1790320Y298032D03*
Y305032D03*
X1795641Y1269444D03*
Y1262444D03*
X1809341Y1269444D03*
Y1262444D03*
X1816714Y1269444D03*
Y1262444D03*
G54D18*
X30771Y441130D03*
Y445519D03*
X40084Y722374D03*
Y726874D03*
X37861Y1254400D03*
X62327Y393079D03*
X62329Y388462D03*
X48384Y722374D03*
Y726874D03*
X68300Y754726D03*
Y759246D03*
X67793Y1254593D03*
X104966Y493474D03*
Y513374D03*
X97228Y1254464D03*
X117516Y642762D03*
X114963Y657550D03*
X114999Y646327D03*
X114963Y651734D03*
X126694Y1254528D03*
X135707Y652919D03*
Y656431D03*
X132389Y1242353D03*
X144063Y493640D03*
Y501640D03*
Y497640D03*
Y505550D03*
X144013Y518810D03*
Y514980D03*
X154505Y1253412D03*
X147915Y1252964D03*
X148506Y1407778D03*
X192036Y681062D03*
X186270Y1255943D03*
X203056Y565982D03*
X204652Y600801D03*
X204562Y634882D03*
X208935Y1244936D03*
X210770Y572619D03*
Y606619D03*
Y640619D03*
X216154Y1255944D03*
X241393Y704825D03*
X226396Y1242283D03*
X258997Y64455D03*
X258949Y60345D03*
X258952Y56160D03*
X302227Y177279D03*
Y181279D03*
X320361Y205049D03*
X351513Y705965D03*
X393425Y1404085D03*
Y1407605D03*
X417563Y929166D03*
X435000Y1415275D03*
X434990Y1407789D03*
X437516Y380862D03*
X437970Y1420659D03*
X448790Y1407229D03*
X437455Y1411504D03*
X446486Y1424269D03*
X447876Y1626352D03*
X453896Y1401282D03*
X477973Y1398402D03*
X479452Y1394447D03*
X536341Y112592D03*
X593238Y740955D03*
X586228Y740985D03*
X614973Y400149D03*
Y404179D03*
X611874Y939877D03*
X616736Y38702D03*
X625599Y146942D03*
X625597Y151559D03*
X631736Y431062D03*
Y457862D03*
Y477862D03*
Y472862D03*
Y467862D03*
Y462862D03*
X616736Y467862D03*
X631736Y487862D03*
Y482862D03*
X623308Y1257336D03*
Y1253293D03*
X646736Y421362D03*
Y438862D03*
Y472862D03*
Y477862D03*
Y467862D03*
Y482862D03*
X663236Y408362D03*
Y404362D03*
X656304Y1252895D03*
X677044Y35067D03*
X679811Y408362D03*
Y404362D03*
X688568Y779977D03*
X691316Y1257062D03*
X699736Y408362D03*
Y404362D03*
X701736Y1301162D03*
Y1297162D03*
X704658Y1563733D03*
X704628Y1587683D03*
Y1591683D03*
X706228Y1601983D03*
X708612Y1663842D03*
X708625Y1667841D03*
X717736Y408362D03*
Y404362D03*
X719035Y1253356D03*
X719668Y1569493D03*
X726768D03*
X740506Y412692D03*
X754393Y273399D03*
X757555Y286632D03*
X759856Y474862D03*
X750676Y1256762D03*
X775736Y423212D03*
Y418212D03*
X774856Y474862D03*
X762923Y761555D03*
X793640Y763996D03*
X786043Y759655D03*
X793643Y758455D03*
X786043Y763855D03*
X778384Y1253277D03*
X798015Y295488D03*
X801185Y312773D03*
X797915Y303188D03*
X802193Y763915D03*
Y759665D03*
X807849Y1253512D03*
X824383Y760215D03*
X824480Y764316D03*
X842736Y220362D03*
X840413Y770025D03*
X839386Y1252392D03*
X849636Y216362D03*
X849736Y209362D03*
X930111Y189386D03*
X930311Y193386D03*
X928441Y201612D03*
X934905Y493701D03*
X930681Y512098D03*
X933186Y521348D03*
X931156Y980462D03*
X931294Y986143D03*
X970366Y380952D03*
X966372Y390302D03*
Y394178D03*
X987275Y341799D03*
X987395Y421961D03*
X999575Y341829D03*
X1001762Y419162D03*
X1018016Y380862D03*
Y385862D03*
Y394362D03*
Y398362D03*
X1015779Y416974D03*
X1013921Y1254263D03*
X1043423Y1254713D03*
X1073120Y1254504D03*
X1116923Y1257449D03*
X1133064Y1259862D03*
X1146493Y606082D03*
X1146503Y599122D03*
X1171516Y1016362D03*
X1192017Y1256140D03*
X1208609Y120962D03*
X1216051Y121002D03*
X1201624Y588714D03*
X1217024Y1256789D03*
X1228609Y129962D03*
Y140962D03*
Y144962D03*
X1229139Y152612D03*
X1226236Y205862D03*
Y217862D03*
Y209862D03*
Y213862D03*
X1239109Y201462D03*
Y205462D03*
Y209462D03*
Y213462D03*
X1239793Y907485D03*
X1256923Y741785D03*
X1270174Y235206D03*
X1282789Y190387D03*
X1284909Y276407D03*
X1302036Y99262D03*
X1312638Y177016D03*
X1321966Y167472D03*
X1322036Y171277D03*
X1315951Y198088D03*
X1315826Y193002D03*
X1315951Y202141D03*
X1323299Y741707D03*
X1342107Y124718D03*
X1349108Y120618D03*
X1356078Y124123D03*
X1377094Y1330133D03*
X1390453Y223754D03*
X1387021Y235188D03*
X1393975Y928806D03*
X1409257Y1330159D03*
X1411141Y1415275D03*
X1411131Y1407789D03*
X1428816Y1401948D03*
X1425931Y1408229D03*
X1413596Y1411504D03*
X1414111Y1420659D03*
X1422497Y1424249D03*
X1437213Y712575D03*
X1441234Y1330312D03*
X1438776Y1570772D03*
X1453236Y145362D03*
X1446463Y746305D03*
X1464736Y169862D03*
X1502492Y741315D03*
X1499358Y745240D03*
X1514816Y312712D03*
X1589094Y211526D03*
X1589078Y231490D03*
X1609530Y1254944D03*
X1636630Y1254844D03*
X1654809Y522176D03*
X1654745Y540071D03*
X1661966Y607332D03*
X1666430Y1255044D03*
X1686193Y466950D03*
X1681454Y488288D03*
X1685185Y502279D03*
X1693792Y521507D03*
Y525507D03*
Y541507D03*
Y529507D03*
Y533507D03*
Y545507D03*
X1696030Y1254244D03*
X1718877Y475752D03*
Y472252D03*
Y479252D03*
X1732310Y61639D03*
X1732358Y65749D03*
X1725630Y1254344D03*
X1755130D03*
X1771891Y173903D03*
Y178303D03*
X1785330Y1254744D03*
X1792486Y1505652D03*
X1803336Y1256426D03*
G54D72*
X673054Y432187D03*
X669904D03*
X673054Y460533D03*
X669904D03*
X695101Y441636D03*
Y444785D03*
Y451084D03*
Y447935D03*
X698251Y441636D03*
Y444785D03*
Y451084D03*
Y447935D03*
X704550Y466832D03*
X701400D03*
X717148Y438486D03*
X713998D03*
X717148Y444785D03*
X713998D03*
X717148Y441636D03*
X713998D03*
X717148Y447935D03*
X713998D03*
X717148Y451084D03*
X713998D03*
X717148Y454234D03*
X713998D03*
G54D63*
X473500Y246362D03*
X498563Y607067D03*
X520000Y278543D03*
X549236Y1441207D03*
X688500Y1621900D03*
X1041435Y163357D03*
X1056225Y163131D03*
X1099970Y1722570D03*
X1679646Y175669D03*
X1771457Y1624646D03*
G54D45*
X186697Y1578182D03*
Y1590094D03*
X191997Y1602380D03*
Y1614292D03*
X194497Y1578182D03*
X206557D03*
X198757D03*
X194497Y1590094D03*
X206557D03*
X198757D03*
X199797Y1614292D03*
Y1602380D03*
X204057Y1614292D03*
Y1602380D03*
X218617Y1578182D03*
X210817D03*
X222877D03*
X218617Y1590094D03*
X210817D03*
X222877D03*
X211857Y1614292D03*
Y1602380D03*
X223917Y1614292D03*
X216117D03*
X223917Y1602380D03*
X216117D03*
X230677Y1578182D03*
X234937D03*
X230677Y1590094D03*
X234937D03*
X228177Y1614292D03*
X235977D03*
X228177Y1602380D03*
X235977D03*
X240237D03*
Y1614292D03*
X242737Y1578182D03*
X246997D03*
X254797D03*
X242737Y1590094D03*
X246997D03*
X254797D03*
X248037Y1602380D03*
Y1614292D03*
X252297Y1602380D03*
Y1614292D03*
X266857Y1578182D03*
X259057D03*
X271117D03*
X266857Y1590094D03*
X259057D03*
X271117D03*
X260097Y1602380D03*
Y1614292D03*
X272157Y1602380D03*
Y1614292D03*
X264357D03*
Y1602380D03*
X278917Y1578182D03*
X283177D03*
X278917Y1590094D03*
X283177D03*
X284217Y1602380D03*
Y1614292D03*
X276417D03*
Y1602380D03*
X288477Y1614292D03*
Y1602380D03*
X290977Y1578182D03*
X295237D03*
X303037D03*
X290977Y1590094D03*
X295237D03*
X303037D03*
X296277Y1614292D03*
Y1602380D03*
X300537D03*
Y1614292D03*
X315097Y1578182D03*
X307297D03*
X319357D03*
X315097Y1590094D03*
X307297D03*
X319357D03*
X308337Y1602380D03*
Y1614292D03*
X320397D03*
X312597D03*
X320397Y1602380D03*
X312597D03*
X327157Y1578182D03*
X331417D03*
X327157Y1590094D03*
X331417D03*
X324657Y1602380D03*
X332457D03*
X324657Y1614292D03*
X332457D03*
X336717Y1602380D03*
Y1614292D03*
X339217Y1578182D03*
X343477D03*
X351277D03*
X339217Y1590094D03*
X343477D03*
X351277D03*
X344517Y1602380D03*
Y1614292D03*
X348777Y1602380D03*
Y1614292D03*
X363337Y1578088D03*
X355537Y1578182D03*
X367597D03*
X363337Y1590094D03*
X355537D03*
X367597D03*
X356577Y1602380D03*
Y1614292D03*
X368637D03*
X360837D03*
X368637Y1602286D03*
X360837Y1602380D03*
X375397Y1578182D03*
Y1590094D03*
X372897Y1602380D03*
X380697D03*
X372897Y1614292D03*
X380697D03*
X482911Y1578182D03*
X478651D03*
X470851D03*
X482911Y1590094D03*
X478651D03*
X470851D03*
X483951Y1614292D03*
Y1602380D03*
X476151D03*
Y1614292D03*
X494971Y1578182D03*
X490711D03*
X494971Y1590094D03*
X490711D03*
X500271Y1614292D03*
Y1602380D03*
X488211Y1614292D03*
Y1602380D03*
X496011D03*
Y1614292D03*
X507031Y1578182D03*
X514831D03*
X502771D03*
X507031Y1590094D03*
X514831D03*
X502771D03*
X512331Y1614292D03*
Y1602380D03*
X508071Y1614292D03*
Y1602380D03*
X531151Y1578182D03*
X519091D03*
X526891D03*
X531151Y1590094D03*
X519091D03*
X526891D03*
X532191Y1614292D03*
Y1602380D03*
X524391Y1614292D03*
Y1602380D03*
X520131D03*
Y1614292D03*
X543211Y1578182D03*
X538951D03*
X543211Y1590094D03*
X538951D03*
X548511Y1614292D03*
Y1602380D03*
X536451D03*
Y1614292D03*
X544251Y1602380D03*
Y1614292D03*
X555271Y1578182D03*
X563071D03*
X551011D03*
X555271Y1590094D03*
X563071D03*
X551011D03*
X560571Y1614292D03*
Y1602380D03*
X556311Y1614292D03*
Y1602380D03*
X579391Y1578182D03*
X567331D03*
X575131D03*
X579391Y1590094D03*
X567331D03*
X575131D03*
X580431Y1614292D03*
X572631D03*
X580431Y1602380D03*
X572631D03*
X568371D03*
Y1614292D03*
X599251Y1578182D03*
X591451D03*
X587191D03*
X599251Y1590094D03*
X591451D03*
X587191D03*
X596751Y1614292D03*
Y1602380D03*
X584691D03*
Y1614292D03*
X592491Y1602380D03*
Y1614292D03*
X615571Y1578182D03*
X603511D03*
X611311D03*
X615571Y1590094D03*
X603511D03*
X611311D03*
X608811Y1602380D03*
Y1614292D03*
X604551Y1602380D03*
Y1614292D03*
X627631Y1578182D03*
X623371D03*
X627631Y1590094D03*
X623371D03*
X628671Y1602380D03*
Y1614292D03*
X620871D03*
Y1602380D03*
X616611Y1614292D03*
Y1602380D03*
X647491Y1578088D03*
X639691Y1578182D03*
X635431D03*
X647491Y1590094D03*
X639691D03*
X635431D03*
X644991Y1614292D03*
Y1602380D03*
X632931D03*
Y1614292D03*
X640731D03*
Y1602380D03*
X651751Y1578182D03*
X659551D03*
X651751Y1590094D03*
X659551D03*
X657051Y1602380D03*
Y1614292D03*
X652791Y1602286D03*
Y1614292D03*
X664851Y1602380D03*
Y1614292D03*
X1194572Y1578182D03*
Y1590094D03*
X1199872Y1614292D03*
Y1602380D03*
X1202372Y1578182D03*
X1214432D03*
X1206632D03*
X1202372Y1590094D03*
X1214432D03*
X1206632D03*
X1207672Y1602380D03*
Y1614292D03*
X1211932D03*
Y1602380D03*
X1218692Y1578182D03*
X1226492D03*
X1230752D03*
X1218692Y1590094D03*
X1226492D03*
X1230752D03*
X1219732Y1614292D03*
Y1602380D03*
X1231792Y1614292D03*
Y1602380D03*
X1223992D03*
Y1614292D03*
X1238552Y1578182D03*
X1242812D03*
X1238552Y1590094D03*
X1242812D03*
X1236052Y1602380D03*
Y1614292D03*
X1243852D03*
Y1602380D03*
X1248112D03*
Y1614292D03*
X1250612Y1578182D03*
X1262672D03*
X1254872D03*
X1250612Y1590094D03*
X1262672D03*
X1254872D03*
X1255912Y1614292D03*
Y1602380D03*
X1260172D03*
Y1614292D03*
X1266932Y1578182D03*
X1274732D03*
X1278992D03*
X1266932Y1590094D03*
X1274732D03*
X1278992D03*
X1267972Y1614292D03*
Y1602380D03*
X1272232D03*
Y1614292D03*
X1280032D03*
Y1602380D03*
X1286792Y1578182D03*
X1298852D03*
X1291052D03*
X1286792Y1590094D03*
X1298852D03*
X1291052D03*
X1284292Y1602380D03*
Y1614292D03*
X1292092D03*
Y1602380D03*
X1296352D03*
Y1614292D03*
X1303112Y1578182D03*
X1310912D03*
X1315172D03*
X1303112Y1590094D03*
X1310912D03*
X1315172D03*
X1304152Y1602380D03*
Y1614292D03*
X1308412Y1602380D03*
Y1614292D03*
X1322972Y1578182D03*
X1327232D03*
X1322972Y1590094D03*
X1327232D03*
X1316212Y1614292D03*
Y1602380D03*
X1328272D03*
Y1614292D03*
X1320472Y1602380D03*
Y1614292D03*
X1335032Y1578182D03*
X1347092D03*
X1339292D03*
X1335032Y1590094D03*
X1347092D03*
X1339292D03*
X1340332Y1602380D03*
Y1614292D03*
X1332532Y1602380D03*
Y1614292D03*
X1344592Y1602380D03*
Y1614292D03*
X1351352Y1578182D03*
X1359152D03*
X1363412D03*
X1351352Y1590094D03*
X1359152D03*
X1363412D03*
X1352392Y1602380D03*
Y1614292D03*
X1356652Y1602380D03*
Y1614292D03*
X1371212Y1578088D03*
X1375472Y1578182D03*
X1371212Y1590094D03*
X1375472D03*
X1364452Y1602380D03*
Y1614292D03*
X1376512Y1602286D03*
Y1614292D03*
X1368712Y1602380D03*
Y1614292D03*
X1383272Y1578182D03*
Y1590094D03*
X1380772Y1602380D03*
Y1614292D03*
X1388572D03*
Y1602380D03*
X1460095Y1578182D03*
Y1590094D03*
X1472155Y1578182D03*
X1467895D03*
X1472155Y1590094D03*
X1467895D03*
X1477455Y1602380D03*
Y1614292D03*
X1473195D03*
Y1602380D03*
X1465395D03*
Y1614292D03*
X1492015Y1578182D03*
X1484215D03*
X1479955D03*
X1492015Y1590094D03*
X1484215D03*
X1479955D03*
X1489515Y1614292D03*
Y1602380D03*
X1485255D03*
Y1614292D03*
X1508335Y1578182D03*
X1496275D03*
X1504075D03*
X1508335Y1590094D03*
X1496275D03*
X1504075D03*
X1501575Y1614292D03*
Y1602380D03*
X1509375D03*
Y1614292D03*
X1497315Y1602380D03*
Y1614292D03*
X1520395Y1578182D03*
X1516135D03*
X1520395Y1590094D03*
X1516135D03*
X1525695Y1614292D03*
Y1602380D03*
X1521435D03*
Y1614292D03*
X1513635D03*
Y1602380D03*
X1540255Y1578182D03*
X1532455D03*
X1528195D03*
X1540255Y1590094D03*
X1532455D03*
X1528195D03*
X1537755Y1614292D03*
Y1602380D03*
X1533495D03*
Y1614292D03*
X1556575Y1578182D03*
X1544515D03*
X1552315D03*
X1556575Y1590094D03*
X1544515D03*
X1552315D03*
X1549815Y1614292D03*
Y1602380D03*
X1557615D03*
Y1614292D03*
X1545555Y1602380D03*
Y1614292D03*
X1568635Y1578182D03*
X1564375D03*
X1568635Y1590094D03*
X1564375D03*
X1573935Y1614292D03*
Y1602380D03*
X1569675Y1614292D03*
Y1602380D03*
X1561875Y1614292D03*
Y1602380D03*
X1588495Y1578182D03*
X1580695D03*
X1576435D03*
X1588495Y1590094D03*
X1580695D03*
X1576435D03*
X1585995Y1614292D03*
Y1602380D03*
X1581735D03*
Y1614292D03*
X1604815Y1578182D03*
X1592755D03*
X1600555D03*
X1604815Y1590094D03*
X1592755D03*
X1600555D03*
X1598055Y1614292D03*
Y1602380D03*
X1605855Y1614292D03*
Y1602380D03*
X1593795Y1614292D03*
Y1602380D03*
X1616875Y1578182D03*
X1612615D03*
X1616875Y1590094D03*
X1612615D03*
X1622175Y1614292D03*
Y1602380D03*
X1617915Y1614292D03*
Y1602380D03*
X1610115Y1614292D03*
Y1602380D03*
X1636735Y1578088D03*
X1628935Y1578182D03*
X1624675D03*
X1636735Y1590094D03*
X1628935D03*
X1624675D03*
X1634235Y1614292D03*
Y1602380D03*
X1629975Y1614292D03*
Y1602380D03*
X1640995Y1578182D03*
X1648795D03*
X1640995Y1590094D03*
X1648795D03*
X1646295Y1614292D03*
Y1602380D03*
X1654095Y1614292D03*
Y1602380D03*
X1642035Y1614292D03*
Y1602286D03*
G54D90*
X922441Y154311D03*
Y243799D03*
G54D54*
X320561Y168009D03*
Y192509D03*
X366037Y1385515D03*
Y1410015D03*
X1338727Y1385105D03*
Y1409605D03*
G36*
G01X791285Y1719440D02*
G02X791280Y1690339I-5J-14550D01*
G02X791275Y1719440I0J14551D01*
G01Y1712890D01*
G03X791280Y1696889I5J-8000D01*
G03X791285Y1712890I0J8001D01*
G01Y1719440D01*
G37*
G36*
G01X1066285D02*
G02X1066280Y1690339I-5J-14550D01*
G02X1066275Y1719440I0J14551D01*
G01Y1712890D01*
G03X1066280Y1696889I5J-8000D01*
G03X1066285Y1712890I0J8001D01*
G01Y1719440D01*
G37*
G54D91*
X928739Y321653D03*
G54D73*
X676203Y444785D03*
Y447935D03*
X685652Y413289D03*
Y416439D03*
X695101Y457384D03*
Y454234D03*
X701400Y444785D03*
Y441635D03*
X704550Y444785D03*
Y441635D03*
X707699Y457384D03*
Y454234D03*
X704550Y457384D03*
Y454234D03*
X701400Y457384D03*
Y454234D03*
X698251Y457384D03*
Y454234D03*
X710849Y457384D03*
Y454234D03*
X723447Y413289D03*
Y416439D03*
G54D19*
X33738Y441130D03*
Y445519D03*
X43051Y722374D03*
Y726874D03*
X40828Y1254400D03*
X51351Y722374D03*
Y726874D03*
X65294Y393079D03*
X65296Y388462D03*
X71267Y754726D03*
Y759246D03*
X70760Y1254593D03*
X107933Y493474D03*
Y513374D03*
X100195Y1254464D03*
X120483Y642762D03*
X117930Y657550D03*
X117966Y646327D03*
X117930Y651734D03*
X138674Y652919D03*
Y656431D03*
X135356Y1242353D03*
X129661Y1254528D03*
X147030Y493640D03*
Y501640D03*
Y497640D03*
Y505550D03*
X146980Y518810D03*
Y514980D03*
X157472Y1253412D03*
X150882Y1252964D03*
X151473Y1407778D03*
X189237Y1255943D03*
X206023Y565982D03*
X207619Y600801D03*
X207529Y634882D03*
X195003Y681062D03*
X213737Y572619D03*
Y606619D03*
Y640619D03*
X219121Y1255944D03*
X211902Y1244936D03*
X229363Y1242283D03*
X244360Y704825D03*
X261964Y64455D03*
X261916Y60345D03*
X261919Y56160D03*
X305194Y177279D03*
Y181279D03*
X323328Y205049D03*
X354480Y705965D03*
X396392Y1404085D03*
Y1407605D03*
X420530Y929166D03*
X440483Y380862D03*
X440937Y1420659D03*
X451757Y1407229D03*
X440422Y1411504D03*
X437967Y1415275D03*
X437957Y1407789D03*
X449453Y1424269D03*
X450843Y1626352D03*
X456863Y1401282D03*
X480940Y1398402D03*
X482419Y1394447D03*
X539308Y112592D03*
X596205Y740955D03*
X589195Y740985D03*
X614841Y939877D03*
X619703Y38702D03*
X628566Y146942D03*
X628564Y151559D03*
X617940Y400149D03*
Y404179D03*
X619703Y467862D03*
X626275Y1257336D03*
Y1253293D03*
X634703Y431062D03*
Y457862D03*
Y477862D03*
Y472862D03*
Y467862D03*
Y462862D03*
Y487862D03*
Y482862D03*
X649703Y421362D03*
Y438862D03*
Y472862D03*
Y477862D03*
Y467862D03*
Y482862D03*
X659271Y1252895D03*
X680011Y35067D03*
X666203Y408362D03*
Y404362D03*
X682778Y408362D03*
Y404362D03*
X691535Y779977D03*
X694283Y1257062D03*
X702703Y408362D03*
Y404362D03*
X704703Y1301162D03*
Y1297162D03*
X707625Y1563733D03*
X707595Y1587683D03*
Y1591683D03*
X709195Y1601983D03*
X711579Y1663842D03*
X711592Y1667841D03*
X720703Y408362D03*
Y404362D03*
X722002Y1253356D03*
X722635Y1569493D03*
X743473Y412692D03*
X729735Y1569493D03*
X757360Y273399D03*
X760522Y286632D03*
X753643Y1256762D03*
X762823Y474862D03*
X777823D03*
X765890Y761555D03*
X778703Y423212D03*
Y418212D03*
X789010Y759655D03*
Y763855D03*
X781351Y1253277D03*
X800982Y295488D03*
X804152Y312773D03*
X800882Y303188D03*
X805160Y763915D03*
Y759665D03*
X796607Y763996D03*
X796610Y758455D03*
X810816Y1253512D03*
X827350Y760215D03*
X827447Y764316D03*
X843380Y770025D03*
X842353Y1252392D03*
X852603Y216362D03*
X852703Y209362D03*
X845703Y220362D03*
X933078Y189386D03*
X933278Y193386D03*
X931408Y201612D03*
X937872Y493701D03*
X933648Y512098D03*
X936153Y521348D03*
X934123Y980462D03*
X934261Y986143D03*
X973333Y380952D03*
X969339Y390302D03*
Y394178D03*
X1002542Y341829D03*
X990242Y341799D03*
X990362Y421961D03*
X1004729Y419162D03*
X1020983Y380862D03*
Y385862D03*
Y394362D03*
Y398362D03*
X1018746Y416974D03*
X1016888Y1254263D03*
X1046390Y1254713D03*
X1076087Y1254504D03*
X1119890Y1257449D03*
X1136031Y1259862D03*
X1149460Y606082D03*
X1149470Y599122D03*
X1174483Y1016362D03*
X1194984Y1256140D03*
X1211576Y120962D03*
X1204591Y588714D03*
X1231576Y129962D03*
X1219018Y121002D03*
X1231576Y140962D03*
Y144962D03*
X1232106Y152612D03*
X1229203Y205862D03*
Y217862D03*
Y209862D03*
Y213862D03*
X1219991Y1256789D03*
X1242076Y201462D03*
Y205462D03*
Y209462D03*
Y213462D03*
X1242760Y907485D03*
X1259890Y741785D03*
X1273141Y235206D03*
X1285756Y190387D03*
X1287876Y276407D03*
X1305003Y99262D03*
X1324933Y167472D03*
X1315605Y177016D03*
X1325003Y171277D03*
X1318918Y198088D03*
X1318793Y193002D03*
X1318918Y202141D03*
X1326266Y741707D03*
X1345074Y124718D03*
X1352075Y120618D03*
X1359045Y124123D03*
X1380061Y1330133D03*
X1393420Y223754D03*
X1389988Y235188D03*
X1396942Y928806D03*
X1412224Y1330159D03*
X1414108Y1415275D03*
X1414098Y1407789D03*
X1428898Y1408229D03*
X1416563Y1411504D03*
X1417078Y1420659D03*
X1425464Y1424249D03*
X1440180Y712575D03*
X1444201Y1330312D03*
X1431783Y1401948D03*
X1441743Y1570772D03*
X1456203Y145362D03*
X1449430Y746305D03*
X1467703Y169862D03*
X1505459Y741315D03*
X1502325Y745240D03*
X1517783Y312712D03*
X1592061Y211526D03*
X1592045Y231490D03*
X1612497Y1254944D03*
X1639597Y1254844D03*
X1657776Y522176D03*
X1657712Y540071D03*
X1664933Y607332D03*
X1669397Y1255044D03*
X1689160Y466950D03*
X1684421Y488288D03*
X1688152Y502279D03*
X1696759Y521507D03*
Y525507D03*
Y541507D03*
Y529507D03*
Y533507D03*
Y545507D03*
X1698997Y1254244D03*
X1721844Y475752D03*
Y472252D03*
Y479252D03*
X1735277Y61639D03*
X1735325Y65749D03*
X1728597Y1254344D03*
X1758097D03*
X1774858Y173903D03*
Y178303D03*
X1788297Y1254744D03*
X1795453Y1505652D03*
X1806303Y1256426D03*
G54D28*
X57646Y12480D03*
X137272D03*
X186622D03*
X266858D03*
X315598D03*
X502528Y33268D03*
X582154D03*
X631504D03*
X711740D03*
X760480D03*
X1532055Y12480D03*
X1611681D03*
X1661031D03*
X1741267D03*
X1790007D03*
G54D37*
X159474Y1320753D03*
X183847Y1320778D03*
X208247D03*
X275289Y575702D03*
Y599861D03*
Y624015D03*
Y648169D03*
X278126Y676260D03*
Y700414D03*
X395771Y1242785D03*
X420171D03*
X444493D03*
X468893D03*
X493293D03*
X673093Y1320778D03*
X697466Y1320803D03*
X721866D03*
X1100800Y251488D03*
X1100700Y275788D03*
X1131100Y1357088D03*
X1155500D03*
X1179900D03*
X1371912Y1242785D03*
X1396312D03*
X1420634D03*
X1445034D03*
X1469434D03*
X1577000Y591888D03*
Y616388D03*
Y640888D03*
Y665288D03*
Y689788D03*
Y714288D03*
X1634259Y1354374D03*
X1658632Y1354399D03*
X1683032D03*
G54D55*
X338211Y1022114D03*
Y1041340D03*
Y1060565D03*
Y1105426D03*
X341479Y867401D03*
Y873810D03*
Y912262D03*
X341478Y905853D03*
Y925079D03*
X341479Y931488D03*
X341478Y944304D03*
X343328Y960326D03*
X343329Y966735D03*
X341479Y950713D03*
X341911Y1009297D03*
Y1002888D03*
Y1022114D03*
X343761Y1018910D03*
X345611Y1015705D03*
X343761Y1031727D03*
X341911Y1041340D03*
X343761Y1038136D03*
Y1057361D03*
Y1050952D03*
Y1076587D03*
Y1070178D03*
X341911Y1079791D03*
X340060Y1082995D03*
X340061Y1095813D03*
X367811Y1002888D03*
X502862Y1006093D03*
X537579Y893036D03*
Y899445D03*
Y912262D03*
X539429Y909057D03*
X543129D03*
Y928283D03*
X539429D03*
X537579Y918670D03*
X537578Y931488D03*
X537579Y937896D03*
X539429Y947509D03*
X537579Y957122D03*
Y950713D03*
X539429Y979552D03*
X535729Y973143D03*
X539862Y1006092D03*
X539861Y999684D03*
X536161Y1006093D03*
X543563Y1006092D03*
X536161Y1025318D03*
X539861Y1018910D03*
X539862Y1044544D03*
X539861Y1038136D03*
X538011Y1060565D03*
Y1066974D03*
X541711Y1073383D03*
X539861Y1076587D03*
X536162Y1082996D03*
X1314353Y1022114D03*
Y1041340D03*
Y1060565D03*
Y1105426D03*
X1317621Y867401D03*
Y873810D03*
Y912262D03*
X1317620Y905853D03*
Y925079D03*
X1317621Y931488D03*
X1317620Y944304D03*
X1319471Y966735D03*
X1319470Y960326D03*
X1317621Y950713D03*
X1318053Y1009297D03*
Y1002888D03*
Y1022114D03*
X1319903Y1018910D03*
X1321753Y1015705D03*
X1319903Y1031727D03*
X1318053Y1041340D03*
X1319903Y1038136D03*
Y1057361D03*
Y1050952D03*
Y1076587D03*
Y1070178D03*
X1318053Y1079791D03*
X1316202Y1082995D03*
X1316203Y1095813D03*
X1343953Y1002888D03*
X1479004Y1006093D03*
X1513721Y893036D03*
Y899445D03*
Y912262D03*
X1515571Y909057D03*
X1519271D03*
Y928283D03*
X1515571D03*
X1513721Y918670D03*
X1513720Y931488D03*
X1513721Y937896D03*
X1519271Y947509D03*
X1515571D03*
X1513721Y957122D03*
Y950713D03*
X1515571Y979552D03*
X1511871Y973143D03*
X1516004Y1006092D03*
X1516003Y999684D03*
X1512303Y1006093D03*
X1519705Y1006092D03*
X1512303Y1025318D03*
X1516003Y1018910D03*
X1516004Y1044544D03*
X1516003Y1038136D03*
X1514153Y1060565D03*
Y1066974D03*
X1517853Y1073383D03*
X1516003Y1076587D03*
X1512304Y1082996D03*
G54D64*
X474246Y1414884D03*
X479646D03*
X1450387Y1414844D03*
X1455787D03*
G54D46*
X223948Y685639D03*
X230017Y582055D03*
Y616055D03*
Y650055D03*
X255213Y582055D03*
Y616055D03*
Y650055D03*
X249144Y685639D03*
X1047163Y253671D03*
X1072359D03*
X1605129Y602943D03*
X1598760Y638527D03*
Y672527D03*
Y706527D03*
X1623956Y638527D03*
Y672527D03*
Y706527D03*
X1630325Y602943D03*
G54D74*
X688802Y438486D03*
X691952D03*
X688802Y441636D03*
X691952D03*
X688802Y444785D03*
X691952D03*
X688802Y454234D03*
X691952D03*
X688802Y447935D03*
X691952D03*
X688802Y451084D03*
X691952D03*
X707699Y444785D03*
X710849D03*
X707699Y441636D03*
X710849D03*
X707699Y447935D03*
X710849D03*
X707699Y451084D03*
X710849D03*
X729747Y432187D03*
X732897D03*
X729747Y460533D03*
X732897D03*
G36*
G01X253476Y197836D02*
G02Y172636I0J-12600D01*
G01X250331D01*
Y176926D01*
X253476D01*
G03Y193546I0J8310D01*
G01X247176D01*
G03Y176926I0J-8310D01*
G01X250321D01*
Y172636D01*
X247176D01*
G02Y197836I0J12600D01*
G01X253476D01*
G37*
G36*
G01X371587D02*
G02Y172636I0J-12600D01*
G01X368442D01*
Y176926D01*
X371587D01*
G03Y193546I0J8310D01*
G01X365287D01*
G03Y176926I0J-8310D01*
G01X368432D01*
Y172636D01*
X365287D01*
G02Y197836I0J12600D01*
G01X371587D01*
G37*
G54D56*
X349187Y710632D03*
X351746D03*
X354305D03*
Y718112D03*
X351746D03*
X349187D03*
X1434597Y717132D03*
X1437156D03*
X1439715D03*
Y724612D03*
X1437156D03*
X1434597D03*
X1709521Y185170D03*
X1712080D03*
X1714639D03*
Y192650D03*
X1712080D03*
X1709521D03*
G54D65*
X493384Y101473D03*
X491284D03*
X493384Y98373D03*
X491284D03*
X485480Y107972D03*
X487580D03*
X485480Y111282D03*
X487580D03*
X520480Y98012D03*
X518380D03*
X520480Y94882D03*
X518380D03*
X564888Y1316279D03*
X566988D03*
X1375626Y256280D03*
X1377726D03*
X1375626Y252680D03*
X1377726D03*
X1539927Y1324555D03*
X1542027D03*
G54D92*
X938780Y1714890D03*
G54D38*
X159474Y1328627D03*
X183847Y1328652D03*
X208247D03*
X275289Y583576D03*
Y607735D03*
Y631889D03*
Y656043D03*
X270252Y676260D03*
Y700414D03*
X387897Y1242785D03*
X412297D03*
X436619D03*
X461019D03*
X485419D03*
X673093Y1328652D03*
X697466Y1328677D03*
X721866D03*
X1100800Y259362D03*
X1100700Y283662D03*
X1131100Y1364962D03*
X1155500D03*
X1179900D03*
X1364038Y1242785D03*
X1388438D03*
X1412760D03*
X1437160D03*
X1461560D03*
X1577000Y599762D03*
Y624262D03*
Y648762D03*
Y673162D03*
Y697662D03*
Y722162D03*
X1634259Y1362248D03*
X1658632Y1362273D03*
X1683032D03*
G54D29*
X60303Y20354D03*
X312921Y24291D03*
X505185Y41142D03*
X757803Y45079D03*
X922441Y237697D03*
X929331Y160413D03*
X1534712Y20354D03*
X1787330Y24291D03*
G54D83*
X793879Y194881D03*
X789942Y204724D03*
X793879Y214567D03*
X805690Y188976D03*
Y220472D03*
X817501Y194881D03*
Y214567D03*
X821438Y204724D03*
X916545Y309459D03*
X911494Y321653D03*
X916545Y333847D03*
X940933Y309459D03*
X928739Y304408D03*
Y338898D03*
X940933Y333847D03*
X945984Y321653D03*
X1045847Y194881D03*
X1041910Y204724D03*
X1045847Y214567D03*
X1069469Y194881D03*
X1057658Y188976D03*
X1069469Y214567D03*
X1057658Y220472D03*
X1073406Y204724D03*
X1131715Y1532913D03*
X1175215D03*
G54D75*
X695101Y435336D03*
Y438486D03*
X685652Y476281D03*
Y479431D03*
X708300Y418750D03*
Y421900D03*
X701400Y435336D03*
Y438486D03*
X704550Y435336D03*
Y438486D03*
X698251Y435336D03*
Y438486D03*
X707699Y435336D03*
Y438486D03*
X710849Y435336D03*
Y438486D03*
X704550Y447935D03*
Y451085D03*
X701400Y447935D03*
Y451085D03*
X726597Y444785D03*
Y447935D03*
X723447Y476281D03*
Y479431D03*
G54D84*
X805690Y204724D03*
X1057658D03*
G54D93*
X948474Y1645870D03*
X985286D03*
G54D57*
X396332Y828421D03*
X402132D03*
X396332Y834842D03*
X402132D03*
X423955Y1646993D03*
X429755D03*
X423965Y1642006D03*
X429765D03*
X451395Y1636501D03*
X445595D03*
X661820Y399862D03*
X666870Y197272D03*
X672670D03*
X667620Y399862D03*
X678395D03*
X684195D03*
X698320D03*
X704120D03*
X710120Y493362D03*
X704320D03*
X716320Y399862D03*
X722120D03*
X742620D03*
X736820D03*
X919269Y475794D03*
X925069D03*
X932094Y477311D03*
X937894D03*
X990600Y396117D03*
X996400D03*
X1027241Y397305D03*
X1033041D03*
X1026139Y412728D03*
X1031939D03*
X1168462Y190588D03*
X1168140Y197742D03*
Y205842D03*
X1174262Y190588D03*
X1173940Y197742D03*
Y205842D03*
X1187460Y185582D03*
X1193260D03*
X1186938Y214133D03*
X1192738D03*
X1186938Y208733D03*
X1192738D03*
X1250101Y256098D03*
X1255901D03*
X1285189Y294768D03*
Y289368D03*
X1372473Y834841D03*
X1378273D03*
X1372473Y828420D03*
X1378273D03*
X1371226Y1406454D03*
X1377026D03*
X1392750Y230152D03*
X1386950D03*
G54D48*
X238780Y1648385D03*
X230906Y1644448D03*
X238780Y1662558D03*
X230906Y1658621D03*
X238780Y1676732D03*
X230906Y1672795D03*
X238780Y1690905D03*
X230906Y1686968D03*
X238780Y1705078D03*
X230906Y1701141D03*
Y1715314D03*
X238780Y1719251D03*
X230906Y1729488D03*
X238780Y1733425D03*
X254528Y1648385D03*
X246654Y1644448D03*
X254528Y1662558D03*
X246654Y1658621D03*
X254528Y1676732D03*
X246654Y1672795D03*
X254528Y1690905D03*
X246654Y1686968D03*
X254528Y1705078D03*
X246654Y1701141D03*
Y1715314D03*
X254528Y1719251D03*
X246654Y1729488D03*
X254528Y1733425D03*
X270276Y1648385D03*
X262402Y1644448D03*
X270276Y1662558D03*
X262402Y1658621D03*
X270276Y1676732D03*
X262402Y1672795D03*
X270276Y1690905D03*
X262402Y1686968D03*
X270276Y1705078D03*
X262402Y1701141D03*
Y1715314D03*
X270276Y1719251D03*
X262402Y1729488D03*
X270276Y1733425D03*
X286024Y1648385D03*
X278150Y1644448D03*
X286024Y1662558D03*
X278150Y1658621D03*
X286024Y1676732D03*
X278150Y1672795D03*
X286024Y1690905D03*
X278150Y1686968D03*
X286024Y1705078D03*
X278150Y1701141D03*
Y1715314D03*
X286024Y1719251D03*
X278150Y1729488D03*
X286024Y1733425D03*
X297835Y1672795D03*
X305709Y1676732D03*
X297835Y1686968D03*
X305709Y1690905D03*
X297835Y1701141D03*
X305709Y1705078D03*
X297835Y1715314D03*
X305709Y1719251D03*
X297835Y1729488D03*
X305709Y1733425D03*
X313583Y1672795D03*
X321457Y1676732D03*
X313583Y1686968D03*
X321457Y1690905D03*
X313583Y1701141D03*
X321457Y1705078D03*
X313583Y1715314D03*
X321457Y1719251D03*
X313583Y1729488D03*
X321457Y1733425D03*
X329331Y1672795D03*
X337205Y1676732D03*
X329331Y1686968D03*
X337205Y1690905D03*
X329331Y1701141D03*
X337205Y1705078D03*
X329331Y1715314D03*
X337205Y1719251D03*
X329331Y1729488D03*
X337205Y1733425D03*
X345079Y1672795D03*
X352953Y1676732D03*
X345079Y1686968D03*
X352953Y1690905D03*
X345079Y1701141D03*
X352953Y1705078D03*
X345079Y1715314D03*
X352953Y1719251D03*
X345079Y1729488D03*
X352953Y1733425D03*
X495079Y1672795D03*
Y1686968D03*
Y1701141D03*
Y1715314D03*
Y1729488D03*
X510827Y1672795D03*
X502953Y1676732D03*
X518701D03*
X510827Y1686968D03*
X502953Y1690905D03*
X518701D03*
X510827Y1701141D03*
X502953Y1705078D03*
X518701D03*
X510827Y1715314D03*
X502953Y1719251D03*
X518701D03*
X510827Y1729488D03*
X502953Y1733425D03*
X518701D03*
X526575Y1672795D03*
X534449Y1676732D03*
X526575Y1686968D03*
X534449Y1690905D03*
X526575Y1701141D03*
X534449Y1705078D03*
X526575Y1715314D03*
X534449Y1719251D03*
X526575Y1729488D03*
X534449Y1733425D03*
X542323Y1672795D03*
X550197Y1676732D03*
X542323Y1686968D03*
X550197Y1690905D03*
X542323Y1701141D03*
X550197Y1705078D03*
X542323Y1715314D03*
X550197Y1719251D03*
X542323Y1729488D03*
X550197Y1733425D03*
X562008Y1672795D03*
Y1686968D03*
Y1701141D03*
Y1715314D03*
Y1729488D03*
X577756Y1672795D03*
X569882Y1676732D03*
X577756Y1686968D03*
X569882Y1690905D03*
X577756Y1701141D03*
X569882Y1705078D03*
X577756Y1715314D03*
X569882Y1719251D03*
X577756Y1729488D03*
X569882Y1733425D03*
X593504Y1672795D03*
X585630Y1676732D03*
X593504Y1686968D03*
X585630Y1690905D03*
X593504Y1701141D03*
X585630Y1705078D03*
X593504Y1715314D03*
X585630Y1719251D03*
X593504Y1729488D03*
X585630Y1733425D03*
X609252Y1672795D03*
X601378Y1676732D03*
X609252Y1686968D03*
X601378Y1690905D03*
X609252Y1701141D03*
X601378Y1705078D03*
X609252Y1715314D03*
X601378Y1719251D03*
X609252Y1729488D03*
X601378Y1733425D03*
X617126Y1676732D03*
Y1690905D03*
Y1705078D03*
Y1719251D03*
Y1733425D03*
X1238780Y1672795D03*
X1246654Y1676732D03*
X1238780Y1686968D03*
X1246654Y1690905D03*
X1238780Y1701141D03*
X1246654Y1705078D03*
X1238780Y1715314D03*
X1246654Y1719251D03*
X1238780Y1729488D03*
X1246654Y1733425D03*
X1254528Y1672795D03*
X1262402Y1676732D03*
X1254528Y1686968D03*
X1262402Y1690905D03*
X1254528Y1701141D03*
X1262402Y1705078D03*
X1254528Y1715314D03*
X1262402Y1719251D03*
X1254528Y1729488D03*
X1262402Y1733425D03*
X1270276Y1672795D03*
X1278150Y1676732D03*
X1270276Y1686968D03*
X1278150Y1690905D03*
X1270276Y1701141D03*
X1278150Y1705078D03*
X1270276Y1715314D03*
X1278150Y1719251D03*
X1270276Y1729488D03*
X1278150Y1733425D03*
X1286024Y1672795D03*
X1293898Y1676732D03*
X1286024Y1686968D03*
X1293898Y1690905D03*
X1286024Y1701141D03*
X1293898Y1705078D03*
X1286024Y1715314D03*
X1293898Y1719251D03*
X1286024Y1729488D03*
X1293898Y1733425D03*
X1305709Y1672795D03*
X1313583Y1676732D03*
X1305709Y1686968D03*
X1313583Y1690905D03*
X1305709Y1701141D03*
X1313583Y1705078D03*
X1305709Y1715314D03*
X1313583Y1719251D03*
X1305709Y1729488D03*
X1313583Y1733425D03*
X1321457Y1672795D03*
X1329331Y1676732D03*
X1321457Y1686968D03*
X1329331Y1690905D03*
X1321457Y1701141D03*
X1329331Y1705078D03*
X1321457Y1715314D03*
X1329331Y1719251D03*
X1321457Y1729488D03*
X1329331Y1733425D03*
X1337205Y1672795D03*
X1345079Y1676732D03*
X1337205Y1686968D03*
X1345079Y1690905D03*
X1337205Y1701141D03*
X1345079Y1705078D03*
X1337205Y1715314D03*
X1345079Y1719251D03*
X1337205Y1729488D03*
X1345079Y1733425D03*
X1352953Y1672795D03*
X1360827Y1676732D03*
X1352953Y1686968D03*
X1360827Y1690905D03*
X1352953Y1701141D03*
X1360827Y1705078D03*
X1352953Y1715314D03*
X1360827Y1719251D03*
X1352953Y1729488D03*
X1360827Y1733425D03*
X1502953Y1672795D03*
X1510827Y1676732D03*
X1502953Y1686968D03*
X1510827Y1690905D03*
X1502953Y1701141D03*
X1510827Y1705078D03*
X1502953Y1715314D03*
X1510827Y1719251D03*
X1502953Y1729488D03*
X1510827Y1733425D03*
X1518701Y1672795D03*
X1526575Y1676732D03*
X1518701Y1686968D03*
X1526575Y1690905D03*
X1518701Y1701141D03*
X1526575Y1705078D03*
X1518701Y1715314D03*
X1526575Y1719251D03*
X1518701Y1729488D03*
X1526575Y1733425D03*
X1534449Y1672795D03*
X1542323Y1676732D03*
X1534449Y1686968D03*
X1542323Y1690905D03*
X1534449Y1701141D03*
X1542323Y1705078D03*
X1534449Y1715314D03*
X1542323Y1719251D03*
X1534449Y1729488D03*
X1542323Y1733425D03*
X1550197Y1672795D03*
X1558071Y1676732D03*
X1550197Y1686968D03*
X1558071Y1690905D03*
X1550197Y1701141D03*
X1558071Y1705078D03*
X1550197Y1715314D03*
X1558071Y1719251D03*
X1550197Y1729488D03*
X1558071Y1733425D03*
X1569882Y1672795D03*
Y1686968D03*
Y1701141D03*
Y1715314D03*
Y1729488D03*
X1585630Y1672795D03*
X1577756Y1676732D03*
X1585630Y1686968D03*
X1577756Y1690905D03*
X1585630Y1701141D03*
X1577756Y1705078D03*
X1585630Y1715314D03*
X1577756Y1719251D03*
X1585630Y1729488D03*
X1577756Y1733425D03*
X1601378Y1672795D03*
X1593504Y1676732D03*
X1601378Y1686968D03*
X1593504Y1690905D03*
X1601378Y1701141D03*
X1593504Y1705078D03*
X1601378Y1715314D03*
X1593504Y1719251D03*
X1601378Y1729488D03*
X1593504Y1733425D03*
X1617126Y1672795D03*
X1609252Y1676732D03*
X1625000D03*
X1617126Y1686968D03*
X1609252Y1690905D03*
X1625000D03*
X1617126Y1701141D03*
X1609252Y1705078D03*
X1625000D03*
X1617126Y1715314D03*
X1609252Y1719251D03*
X1625000D03*
X1617126Y1729488D03*
X1609252Y1733425D03*
X1625000D03*
G54D39*
X163527Y1351890D03*
Y1377086D03*
X201927Y1351890D03*
Y1377086D03*
X349753Y1286498D03*
Y1311694D03*
X411380Y1274780D03*
Y1299976D03*
X447551Y1274792D03*
Y1299988D03*
X510022Y1286306D03*
Y1311502D03*
X677107Y1351915D03*
Y1377111D03*
X716004Y1351915D03*
Y1377111D03*
X1136799Y1389120D03*
Y1414316D03*
X1175696Y1389120D03*
Y1414316D03*
X1326294Y1287458D03*
Y1312654D03*
X1387521Y1274280D03*
Y1299476D03*
X1423692Y1274292D03*
Y1299488D03*
X1486163Y1286306D03*
Y1311502D03*
X1638273Y1384661D03*
Y1409857D03*
X1677170Y1384661D03*
Y1409857D03*
G54D66*
X498487Y103452D03*
Y102074D03*
Y100696D03*
Y99318D03*
Y107586D03*
Y106208D03*
Y104830D03*
X508133Y99318D03*
Y100696D03*
Y102074D03*
Y103452D03*
Y104830D03*
Y106208D03*
Y107586D03*
G54D94*
X986830Y-21500D03*
Y8500D03*
X1296222Y-31511D03*
Y-11511D03*
Y8489D03*
X1488581Y-31511D03*
Y-11511D03*
Y8489D03*
G54D85*
X810850Y763874D03*
Y761315D03*
Y758756D03*
X818724D03*
Y761315D03*
Y763874D03*
X833120Y764094D03*
Y761535D03*
Y758976D03*
X840994D03*
Y761535D03*
Y764094D03*
G54D58*
X387842Y1593517D03*
Y1591417D03*
X391417Y1593517D03*
Y1591417D03*
X663561Y38286D03*
Y36186D03*
X666889Y38287D03*
Y36187D03*
X1327633Y252162D03*
Y254262D03*
X1343782Y243266D03*
Y245366D03*
X1340182Y243266D03*
Y245366D03*
X1339990Y260466D03*
Y262566D03*
X1336390Y260466D03*
Y262566D03*
X1331233Y252162D03*
Y254262D03*
X1347448Y251266D03*
Y253366D03*
X1353702Y243266D03*
Y245366D03*
X1357302Y243266D03*
Y245366D03*
X1360450Y251266D03*
Y253366D03*
X1351048Y251266D03*
Y253366D03*
X1364050Y251266D03*
Y253366D03*
G54D49*
X238780Y1643661D03*
X230906Y1649173D03*
X238780Y1653110D03*
Y1657834D03*
X230906Y1653897D03*
Y1663346D03*
X238780Y1667283D03*
Y1672007D03*
X230906Y1668070D03*
X254528Y1643661D03*
X246654Y1649173D03*
X254528Y1653110D03*
Y1657834D03*
X246654Y1653897D03*
Y1663346D03*
X254528Y1667283D03*
Y1672007D03*
X246654Y1668070D03*
Y1734212D03*
X270276Y1643661D03*
X262402Y1649173D03*
Y1653897D03*
Y1663346D03*
X270276Y1667283D03*
Y1672007D03*
X262402Y1668070D03*
Y1734212D03*
X286024Y1643661D03*
X278150Y1649173D03*
Y1653897D03*
Y1663346D03*
Y1668070D03*
Y1734212D03*
X305709Y1672007D03*
X321457D03*
X313583Y1734212D03*
X337205Y1672007D03*
X329331Y1734212D03*
X352953Y1672007D03*
X345079Y1734212D03*
X502953Y1672007D03*
X510827Y1734212D03*
X518701Y1672007D03*
X534449D03*
X526575Y1734212D03*
X550197Y1672007D03*
X542323Y1734212D03*
X569882Y1672007D03*
X577756Y1734212D03*
X585630Y1672007D03*
X593504Y1734212D03*
X601378Y1672007D03*
X609252Y1734212D03*
X617126Y1672007D03*
X1246654D03*
X1262402D03*
X1254528Y1734212D03*
X1278150Y1672007D03*
X1270276Y1734212D03*
X1293898Y1672007D03*
X1286024Y1734212D03*
X1313583Y1672007D03*
X1329331D03*
X1321457Y1734212D03*
X1345079Y1672007D03*
X1337205Y1734212D03*
X1360827Y1672007D03*
X1352953Y1734212D03*
X1510827Y1672007D03*
X1526575D03*
X1518701Y1734212D03*
X1542323Y1672007D03*
X1534449Y1734212D03*
X1558071Y1672007D03*
X1550197Y1734212D03*
X1577756Y1672007D03*
X1585630Y1734212D03*
X1593504Y1672007D03*
X1601378Y1734212D03*
X1609252Y1672007D03*
X1617126Y1734212D03*
X1625000Y1672007D03*
G54D76*
X705760Y-26500D03*
Y-16500D03*
D03*
Y-6500D03*
X730760Y-26500D03*
Y-16500D03*
D03*
Y-6500D03*
X822720Y3500D03*
Y13500D03*
D03*
Y23500D03*
X847720Y3500D03*
Y13500D03*
D03*
Y23500D03*
X973180Y-26500D03*
Y-16500D03*
D03*
Y-6500D03*
Y3500D03*
Y13500D03*
Y23500D03*
Y13500D03*
X998180Y-26500D03*
Y-16500D03*
D03*
Y-6500D03*
Y3500D03*
Y13500D03*
Y23500D03*
Y13500D03*
X1015152Y-26511D03*
Y-36511D03*
Y-26511D03*
Y-16511D03*
D03*
Y-6511D03*
D03*
Y3489D03*
D03*
Y13489D03*
D03*
Y23489D03*
X1040152Y-26511D03*
Y-36511D03*
Y-26511D03*
Y-16511D03*
D03*
Y-6511D03*
D03*
Y3489D03*
D03*
Y13489D03*
D03*
Y23489D03*
X1282572Y-36511D03*
Y-26511D03*
D03*
Y-16511D03*
D03*
Y-6511D03*
Y3489D03*
Y-6511D03*
Y3489D03*
Y13489D03*
Y23489D03*
Y13489D03*
X1307572Y-36511D03*
Y-26511D03*
D03*
Y-16511D03*
D03*
Y-6511D03*
Y3489D03*
Y-6511D03*
Y3489D03*
Y13489D03*
Y23489D03*
Y13489D03*
X1324471Y-26511D03*
Y-36511D03*
Y-26511D03*
Y-16511D03*
D03*
Y-6511D03*
D03*
Y3489D03*
D03*
Y13489D03*
D03*
Y23489D03*
X1349471Y-26511D03*
Y-36511D03*
Y-26511D03*
Y-16511D03*
D03*
Y-6511D03*
D03*
Y3489D03*
D03*
Y13489D03*
D03*
Y23489D03*
X1474931Y-36511D03*
Y-26511D03*
D03*
Y-16511D03*
D03*
Y-6511D03*
Y3489D03*
Y-6511D03*
Y3489D03*
Y13489D03*
Y23489D03*
Y13489D03*
X1499931Y-36511D03*
Y-26511D03*
D03*
Y-16511D03*
D03*
Y-6511D03*
Y3489D03*
Y-6511D03*
Y3489D03*
Y13489D03*
Y23489D03*
Y13489D03*
X1565236Y184783D03*
Y264035D03*
G54D67*
X500554Y98629D03*
Y108275D03*
X501932Y98629D03*
X503310D03*
X504688D03*
X506066D03*
Y108275D03*
X504688D03*
X503310D03*
X501932D03*
G54D68*
X503310Y103452D03*
G54D59*
X412561Y933298D03*
X417261D03*
X407861D03*
X412561Y939098D03*
X417261D03*
X407861D03*
X429628Y1631147D03*
Y1636947D03*
X438255Y1614977D03*
Y1609177D03*
X464080Y932964D03*
X468780D03*
X464080Y938764D03*
X468780D03*
X473480Y932964D03*
Y938764D03*
X474246Y1418684D03*
X479646D03*
X686220Y490762D03*
Y484962D03*
X906493Y476404D03*
X900460Y490022D03*
X906493Y482204D03*
X900460Y495822D03*
X913401Y475904D03*
X924782Y487212D03*
Y481412D03*
X919515D03*
Y487212D03*
X913401Y481704D03*
X956708Y381166D03*
X951914Y381162D03*
X956708Y386966D03*
X951914Y386962D03*
X1031900Y418517D03*
Y424317D03*
X1282145Y260251D03*
Y266051D03*
X1276901Y260225D03*
Y266025D03*
X1313264Y227309D03*
Y233109D03*
X1307864Y227309D03*
Y233109D03*
X1323896Y227362D03*
Y233162D03*
X1318627Y227279D03*
Y233079D03*
X1362309Y217419D03*
Y211619D03*
X1373111Y217452D03*
Y211652D03*
X1367711Y217404D03*
Y211604D03*
X1388702Y932963D03*
X1393402D03*
X1384002D03*
X1388702Y938763D03*
X1393402D03*
X1384002D03*
X1440221Y932963D03*
X1444921D03*
X1440221Y938763D03*
X1444921D03*
X1449621Y932963D03*
Y938763D03*
X1450387Y1418644D03*
X1455787D03*
G54D86*
X828780Y1694890D03*
Y1684890D03*
X818780Y1694890D03*
Y1684890D03*
X828780Y1704890D03*
X818780D03*
X828780Y1714890D03*
X818780D03*
X853780Y1694890D03*
Y1684890D03*
Y1704890D03*
Y1714890D03*
X863780Y1694890D03*
Y1684890D03*
Y1704890D03*
Y1714890D03*
X888780Y1684890D03*
Y1694890D03*
Y1704890D03*
Y1714890D03*
X898780Y1684890D03*
Y1694890D03*
Y1704890D03*
Y1714890D03*
X918780Y1684890D03*
Y1694890D03*
Y1704890D03*
Y1714890D03*
X928780Y1684890D03*
X938780D03*
X928780Y1694890D03*
X938780D03*
X928780Y1704890D03*
X938780D03*
X928780Y1714890D03*
X958780Y1694890D03*
Y1684890D03*
Y1704890D03*
Y1714890D03*
X968780Y1694890D03*
Y1684890D03*
Y1704890D03*
Y1714890D03*
X993780Y1684890D03*
Y1694890D03*
X1003780Y1684890D03*
Y1694890D03*
X993780Y1704890D03*
Y1714890D03*
X1003780Y1704890D03*
Y1714890D03*
X1028780Y1684890D03*
Y1694890D03*
X1038780Y1684890D03*
Y1694890D03*
X1028780Y1704890D03*
Y1714890D03*
X1038780Y1704890D03*
Y1714890D03*
G54D77*
X717110Y-21500D03*
X834070Y8500D03*
X1026502Y-31511D03*
Y-11511D03*
Y8489D03*
X1335821Y-31511D03*
Y-11511D03*
Y8489D03*
G54D95*
X1010362Y1637176D03*
Y1663160D03*
X1036450Y1637260D03*
Y1663244D03*
G54D96*
X1041500Y382122D03*
Y389602D03*
G54D69*
X517115Y107550D03*
Y111060D03*
X520265Y107550D03*
Y111060D03*
X931426Y527751D03*
X934576D03*
X931426D03*
X928276D03*
X931503Y533077D03*
X934653D03*
X931503D03*
X928353D03*
X1011630Y218253D03*
X1014780D03*
X1011630D03*
X1008480D03*
X1330873Y542647D03*
D03*
X1327723D03*
X1330796Y537321D03*
D03*
X1327646D03*
X1334023Y542647D03*
X1333946Y537321D03*
G54D78*
X720360Y-20516D03*
Y-22484D03*
X837320Y9484D03*
Y7516D03*
X983580Y-22484D03*
Y-20516D03*
Y7516D03*
Y9484D03*
X1029752Y-30527D03*
Y-32495D03*
Y-10527D03*
Y-12495D03*
Y9473D03*
Y7505D03*
X1292972Y-32495D03*
Y-30527D03*
Y-12495D03*
Y-10527D03*
Y7505D03*
Y9473D03*
X1339071Y-30527D03*
Y-32495D03*
Y-10527D03*
Y-12495D03*
Y9473D03*
Y7505D03*
X1485331Y-32495D03*
Y-30527D03*
Y-12495D03*
Y-10527D03*
Y7505D03*
Y9473D03*
G54D87*
X841240Y1407480D03*
X832154Y1411244D03*
X828390Y1420330D03*
X832154Y1429416D03*
X841240Y1433180D03*
X850326Y1411244D03*
X854090Y1420330D03*
X850326Y1429416D03*
X1003390Y1420330D03*
X1016240Y1407480D03*
X1007154Y1411244D03*
Y1429416D03*
X1016240Y1433180D03*
X1025326Y1411244D03*
X1029090Y1420330D03*
X1025326Y1429416D03*
G54D88*
X841240Y1420330D03*
X900196Y175197D03*
X944684Y155216D03*
X1016240Y1420330D03*
G54D79*
X725073Y1241963D03*
X734521D03*
X1700586Y1235879D03*
X1710034D03*
G54D97*
X1156378Y133866D03*
G54D98*
X1164858Y592327D03*
Y589827D03*
Y607327D03*
Y604827D03*
Y602327D03*
Y599827D03*
Y597327D03*
Y594827D03*
X1186058Y592327D03*
Y589827D03*
Y607327D03*
Y604827D03*
Y602327D03*
Y599827D03*
Y597327D03*
Y594827D03*
G54D89*
X859100Y769165D03*
Y765425D03*
Y761685D03*
X849454D03*
Y769165D03*
G54D99*
X1200450Y1247609D03*
X1263543Y141412D03*
X1261848Y146363D03*
X1264183Y154756D03*
X1266983Y151686D03*
M02*
